# BARRELEYE_G2-MB-PVT-X04-HW-BOM-X26_20180122_Final.xls.xlsx — Changelist (bom)
| BOM Change List Date:Fri May 12 14:41:10 GMT+08:00 2017 |  |  |  |  |  |  |  |  |  |
| New BOM file : C:\<user>\BARRELEYE-G2-MB-DVT-HW-SCH-X03_20170512.xls |  |  |  |  |  |  |  |  |  |
| Old BOM file : C:\<user>\Barreleye-G2-MB-DVT-X03-BOM-X14_20170504.xls |  |  |  |  |  |  |  |  |  |
| ##### Add Parts |  |  |  |  |  |  |  |  |  |
| Item | Location | Qty | Foxconn P/N | Part Description | Manufacturer Full Name | Manufacturer P/N | RoHS | Sheet |  |
| 1 | D56 | 1 | 520304B00-237-G | DIODE,Schottky,BAT54WS-7-F,30V,0.1A,G,SOD323-2,SMD | DIODES INEORPORATION | BAT54WS-7-F | N | PWA BOM |  |
| 2 | R1549 | 1 | 610107A00-017-G | RES,0 Ohm,+/-5%,1/16W,G,SMD0402 | KOA SPEER ELECTRONICS, INC. | RK73Z1ETTP | N | PWA BOM |  |
| 3 | PSUR4 | 1 | 610119C00-017-G | RES,130KOhm,+/-1%,1/16W,G,SMD0402 | KOA SPEER ELECTRONICS, INC. | RK73H1ETTP1303F | N | PWA BOM |  |
| 4 | PSUR2,PSUR5 | 2 | 610116G00-017-G | RES,150KOhm,+/-1%,1/16W,G,SMD0402 | KOA SPEER ELECTRONICS, INC. | RK73H1ETTP1503F | N | PWA BOM |  |
| 5 | R1847 | 1 | 61011LF00-017-G | RES,499KOhm,+/-1%,1/16W,G,SMD0402 | KOA SPEER ELECTRONICS, INC. | RK73H1ETTP4993F | N | PWA BOM |  |
| 6 | PSUSW1 | 1 | 34080F500-653-G | CONN,Switch,slide,25mA,24V,G,SMD-8 | DIPTRONICS MANUFACTURING INC. | DHN-04F-T-V-T/R |  | PWA BOM |  |
| ##### Remove Parts |  |  |  |  |  |  |  |  |  |
| Item | Location | Qty | Foxconn P/N | Part Description | Manufacturer Full Name | Manufacturer P/N | RoHS | Sheet |  |
| 1 | PAER46 | 1 | 610107A00-017-G | RES,0 Ohm,+/-5%,1/16W,G,SMD0402 | KOA SPEER ELECTRONICS, INC. | RK73Z1ETTP | N | PWA BOM |  |
| ##### Change Parts |  |  |  |  |  |  |  |  |  |
| Item | Location | Qty | Foxconn P/N | Part Description | Manufacturer Full Name | Manufacturer P/N | RoHS | Sheet | Remark |
| 1 | PBER93,PAFR93,PAER93,PBFR94,PBER96,PAFR96,PAER96,PBFR97 | 8 | 610107A00-017-G | RES,0 Ohm,+/-5%,1/16W,G,SMD0402 | KOA SPEER ELECTRONICS, INC. | RK73Z1ETTP | N | PWA BOM | In New BOM |
|  | PBER93,PAFR93,PAER93,PBFR94,PBER96,PAFR96,PAER96,PBFR97 | 8 | 610113800-017-G | RES,10 Ohm,+/-1%,1/16W,G,SMD0402 | KOA SPEER ELECTRONICS, INC. | RK73H1ETTP10R0F | N | PWA BOM | In Old BOM |
| 2 | PBMR303,PBFR303,PBER303,PBAR303,PAMR303,PAFR303,PAER303,PAAR303 | 8 | 610107A00-017-G | RES,0 Ohm,+/-5%,1/16W,G,SMD0402 | KOA SPEER ELECTRONICS, INC. | RK73Z1ETTP | N | PWA BOM | In New BOM |
|  | PBMR303,PBFR303,PBER303,PBAR303,PAMR303,PAFR303,PAER303,PAAR303 | 8 | 61010L300-017-G | RES,1KOhm,+/-1%,1/16W,G,SMD0402 | KOA SPEER ELECTRONICS, INC. | RK73H1ETTP1001F | N | PWA BOM | In Old BOM |
| 3 | R1281,R1283,R1285,R1289,R1290,R1291,R1292,R1293 | 8 | 610107A00-017-G | RES,0 Ohm,+/-5%,1/16W,G,SMD0402 | KOA SPEER ELECTRONICS, INC. | RK73Z1ETTP | N | PWA BOM | In New BOM |
|  | R1281,R1283,R1285,R1289,R1290,R1291,R1292,R1293 | 8 | 61011H500-017-G | RES,22 Ohm,+/-1%,1/16W,G,SMD0402 | KOA SPEER ELECTRONICS, INC. | RK73H1ETTP22R0F | N | PWA BOM | In Old BOM |
| 4 | PBFR518,PBER518,PAFR518,PBFR519,PBER519,PAFR519,PAER519,PAER520 | 8 | 610113800-017-G | RES,10 Ohm,+/-1%,1/16W,G,SMD0402 | KOA SPEER ELECTRONICS, INC. | RK73H1ETTP10R0F | N | PWA BOM | In New BOM |
|  | PBFR518,PBER518,PAFR518,PBFR519,PBER519,PAFR519,PAER519,PAER520 | 8 | 610107A00-017-G | RES,0 Ohm,+/-5%,1/16W,G,SMD0402 | KOA SPEER ELECTRONICS, INC. | RK73Z1ETTP | N | PWA BOM | In Old BOM |
| 5 | PBFR34,PBER34,PAFR34,PAER34 | 4 | 61100YT00-017-G | RES,487 Ohm,+/-0.1%,1/16W,G,SMD0402 | KOA SPEER ELECTRONICS, INC. | RN731ETTP4870B25 | N | PWA BOM | In New BOM |
|  | PBFR34,PBER34,PAFR34,PAER34 | 4 | 610118N00-017-G | RES,487 Ohm,+/-1%,1/16W,G,SMD0402 | KOA SPEER ELECTRONICS, INC. | RK73H1ETTP4870F | N | PWA BOM | In Old BOM |
| 6 | PBMR34,PAMR34 | 2 | 61100RF00-017-G | RES,402 Ohm,+/-0.1%,1/16W,G,SMD0402 | KOA SPEER ELECTRONICS, INC. | RN731ETTP4020B25 | N | PWA BOM | In New BOM |
|  | PBMR34,PAMR34 | 2 | 61011J902-017-G | RES,402 Ohm,+/-1%,1/16W,G,SMD0402 | KOA SPEER ELECTRONICS, INC. | RK73H1ETTP4020F | N | PWA BOM | In Old BOM |
| 7 | PSUR1 | 1 | 610119C00-017-G | RES,130KOhm,+/-1%,1/16W,G,SMD0402 | KOA SPEER ELECTRONICS, INC. | RK73H1ETTP1303F | N | PWA BOM | In New BOM |
|  | PSUR1 | 1 | 610115R00-017-G | RES,15KOhm,+/-1%,1/16W,G,SMD0402 | KOA SPEER ELECTRONICS, INC. | RK73H1ETTP1502F | N | PWA BOM | In Old BOM |
| 8 | R1307,R1314,R1315,R1316,R1317,R1318,R1319,R1320 | 8 | 61011H500-017-G | RES,22 Ohm,+/-1%,1/16W,G,SMD0402 | KOA SPEER ELECTRONICS, INC. | RK73H1ETTP22R0F | N | PWA BOM | In New BOM |
|  | R1307,R1314,R1315,R1316,R1317,R1318,R1319,R1320 | 8 | 610107A00-017-G | RES,0 Ohm,+/-5%,1/16W,G,SMD0402 | KOA SPEER ELECTRONICS, INC. | RK73Z1ETTP | N | PWA BOM | In Old BOM |
| 9 | U62 | 1 | 21050R500-298-G | IC,SILABS,Si5338C-B06799-GMR,G,QFN-24,SMD | Silicon Laboratories Inc. | SI5338C-B06799-GMR |  | PWA BOM | In New BOM |
|  | U62 | 1 | 21050R500-298-G | IC,SILABS,Si5338C-B06429-GMR,G,QFN-24,SMD | Silicon Laboratories Inc. | SI5338C-B06799-GMR |  | PWA BOM | In Old BOM |
| 10 | J10 | 1 | 3406B5J00-317-G | CONN,Header,Socket,V/T,Bla,2mm,15u,G,DIP-18 | MOLEX INCORPORATED | 79107-7008 |  | PWA BOM | In New BOM |
|  | J10 | 1 | 79107-7008 | CONN,Header,Socket,2X9,V/T,Bla,2mm,15u,G,DIP-18 | MOLEX INCORPORATED | 79107-7008 |  | PWA BOM | In Old BOM |
| 11 | J13 | 1 | 34064J800-317-G | CONN,Header,Socket,2X2,V/T,Bla,2mm,15u,G,DIP-4 | MOLEX INCORPORATED | 79107-7001 |  | PWA BOM | In New BOM |
|  | J13 | 1 | 79107-7001 | CONN,Header,Socket,2X2,V/T,Bla,2mm,15u,G,DIP-4 | MOLEX INCORPORATED | 79107-7001 |  | PWA BOM | In Old BOM |
| 12 | PBAR65,PAAR65 | 2 | TLRH3APTTE20L0F | RES,20mOhm,+/-1%,2W,G,SMD2512 | KOA SPEER ELECTRONICS, INC. | TLRH3APTTE20L0F |  | PWA BOM | In New BOM |
|  | PBAR65,PAAR65 | 2 | 61012WF00-017-G | RES,20mOhm,+/-1%,1W,G,SMD2512 | KOA SPEER ELECTRONICS, INC. | UR73D3ATTE20L0F |  | PWA BOM | In Old BOM |
| 13 | PBER65,PAFR65,PAER65,PBFR66 | 4 | SLW1TTE50L0F | RES,50mOhm,+/-1%,1.5W,G,SMD2512 | KOA | SLW1TTE50L0F |  | PWA BOM | In New BOM |
|  | PBER65,PAFR65,PAER65,PBFR66 | 4 | 610605200-034-G | RES,50mOhm,+/-1%,3W,G,SMD2512 | CYNTEC CO. LTD | RL-3264-0W-R050-FNH |  | PWA BOM | In Old BOM |
| 14 | PBMR65,PAMR65 | 2 | SLW1TTE75L0F | RES,75mOhm,+/-1%,1.5W,G,SMD2512 | KOA | SLW1TTE75L0F |  | PWA BOM | In New BOM |
|  | PBMR65,PAMR65 | 2 | TLRH3APTTE60L0F | RES,60mOhm,+/-0.5%,2W,G,SMD2512 | KOA SPEER ELECTRONICS, INC. | TLRH3APTTE60L0F | Y | PWA BOM | In Old BOM |
| ##### Change Revision |  |  |  |  |  |  |  |  |  |
| Sheet | REV OF BOM | CUSTOMER | CUSTOMER P/N | PWA PN | PWA DESCRIPTION | PWA REV | DATE | Remark |  |
| OOOOOOOOOOOOOOOOOOOOOOOOOOOOOOOOOOOOOOOOOOOOOOOOOOOOOOOOOOOOOOOOOOOOOOOOOOOOOOOOOOOOOOOOOO | OOOOOOOOOOOOOOOOOOOOOOOOOOOOOOOOOOOOOOOOOOOOOOOOOOOOOOOOOOOOOOOOOOOOOOOOOOOOOOOOOOOOOOOOOO | OOOOOOOOOOOOOOOOOOOOOOOOOOOOOOOOOOOOOOOOOOOOOOOOOOOOOOOOOOOOOOOOOOOOOOOOOOOOOOOOOOOOOOOOOO | OOOOOOOOOOOOOOOOOOOOOOOOOOOOOOOOOOOOOOOOOOOOOOOOOOOOOOOOOOOOOOOOOOOOOOOOOOOOOOOOOOOOOOOOOO | OOOOOOOOOOOOOOOOOOOOOOOOOOOOOOOOOOOOOOOOOOOOOOOOOOOOOOOOOOOOOOOOOOOOOOOOOOOOOOOOOOOOOOOOOO | OOOOOOOOOOOOOOOOOOOOOOOOOOOOOOOOOOOOOOOOOOOOOOOOOOOOOOOOOOOOOOOOOOOOOOOOOOOOOOOOOOOOOOOOOO | OOOOOOOOOOOOOOOOOOOOOOOOOOOOOOOOOOOOOOOOOOOOOOOOOOOOOOOOOOOOOOOOOOOOOOOOOOOOOOOOOOOOOOOOOO | OOOOOOOOOOOOOOOOOOOOOOOOOOOOOOOOOOOOOOOOOOOOOOOOOOOOOOOOOOOOOOOOOOOOOOOOOOOOOOOOOOOOOOOOOO | OOOOOOOOOOOOOOOOOOOOOOOOOOOOOOOOOOOOOOOOOOOOOOOOOOOOOOOOOOOOOOOOOOOOOOOOOOOOOOOOOOOOOOOOOO | OOOOOOOOOOOOOOOOOOOOOOOOOOOOOOOOOOOOOOOOOOOOOOOOOOOOOOOOOOOOOOOOOOOOOOOOOOOOOOOOOOOOOOOOOO |
| Second Source Change |  |  |  |  |  |  |  |  |  |
| Item | Location | Change Type | Foxconn P/N | Part Description | Manufacturer Full Name | Manufacturer P/N | RoHS | Sheet |  |
| OOOOOOOOOOOOOOOOOOOOOOOOOOOOOOOOOOOOOOOOOOOOOOOOOOOOOOOOOOOOOOOOOOOOOOOOOOOOOOOOOOOOOOOOOO | OOOOOOOOOOOOOOOOOOOOOOOOOOOOOOOOOOOOOOOOOOOOOOOOOOOOOOOOOOOOOOOOOOOOOOOOOOOOOOOOOOOOOOOOOO | OOOOOOOOOOOOOOOOOOOOOOOOOOOOOOOOOOOOOOOOOOOOOOOOOOOOOOOOOOOOOOOOOOOOOOOOOOOOOOOOOOOOOOOOOO | OOOOOOOOOOOOOOOOOOOOOOOOOOOOOOOOOOOOOOOOOOOOOOOOOOOOOOOOOOOOOOOOOOOOOOOOOOOOOOOOOOOOOOOOOO | OOOOOOOOOOOOOOOOOOOOOOOOOOOOOOOOOOOOOOOOOOOOOOOOOOOOOOOOOOOOOOOOOOOOOOOOOOOOOOOOOOOOOOOOOO | OOOOOOOOOOOOOOOOOOOOOOOOOOOOOOOOOOOOOOOOOOOOOOOOOOOOOOOOOOOOOOOOOOOOOOOOOOOOOOOOOOOOOOOOOO | OOOOOOOOOOOOOOOOOOOOOOOOOOOOOOOOOOOOOOOOOOOOOOOOOOOOOOOOOOOOOOOOOOOOOOOOOOOOOOOOOOOOOOOOOO | OOOOOOOOOOOOOOOOOOOOOOOOOOOOOOOOOOOOOOOOOOOOOOOOOOOOOOOOOOOOOOOOOOOOOOOOOOOOOOOOOOOOOOOOOO | OOOOOOOOOOOOOOOOOOOOOOOOOOOOOOOOOOOOOOOOOOOOOOOOOOOOOOOOOOOOOOOOOOOOOOOOOOOOOOOOOOOOOOOOOO | OOOOOOOOOOOOOOOOOOOOOOOOOOOOOOOOOOOOOOOOOOOOOOOOOOOOOOOOOOOOOOOOOOOOOOOOOOOOOOOOOOOOOOOOOO |
| Master Materials Change |  |  |  |  |  |  |  |  |  |
| Item | Foxconn P/N | Orig._Usage | New_Usage | Part Description | Manufacturer Full Name | Manufacturer P/N | RoHS | Location | Sheet |
| 1 | 520304B00-237-G | 2 | 3 | DIODE,Schottky,BAT54WS-7-F,30V,0.1A,G,SOD323-2,SMD | DIODES INEORPORATION | BAT54WS-7-F | N | (+)D56 | PWA BOM |
| 2 | 610107A00-017-G | 711 | 719 | RES,0 Ohm,+/-5%,1/16W,G,SMD0402 | KOA SPEER ELECTRONICS, INC. | RK73Z1ETTP | N | (+)PBER93,PAFR93,PAER93,PBFR94,PBER96,PAFR96,PAER96,PBFR97,PBMR303,PBFR303,PBER303,PBAR303,PAMR303,PAFR303,PAER303,PAAR303,R1281,R1283,R1285,R1289,R1290,R1291,R1292,R1293,R1549 (-)PAER46,PBFR518,PBER518,PAFR518,PBFR519,PBER519,PAFR519,PAER519,PAER520,R1307,R1314,R1315,R1316,R1317,R1318,R1319,R1320 | PWA BOM |
| 3 | 61010L300-017-G | 42 | 34 | RES,1KOhm,+/-1%,1/16W,G,SMD0402 | KOA SPEER ELECTRONICS, INC. | RK73H1ETTP1001F | N | (-)PBMR303,PBFR303,PBER303,PBAR303,PAMR303,PAFR303,PAER303,PAAR303 | PWA BOM |
| 4 | 61100YT00-017-G | 0 | 4 | RES,487 Ohm,+/-0.1%,1/16W,G,SMD0402 | KOA SPEER ELECTRONICS, INC. | RN731ETTP4870B25 | N | (+)PBFR34,PBER34,PAFR34,PAER34 | PWA BOM |
| 5 | 61100RF00-017-G | 0 | 2 | RES,402 Ohm,+/-0.1%,1/16W,G,SMD0402 | KOA SPEER ELECTRONICS, INC. | RN731ETTP4020B25 | N | (+)PBMR34,PAMR34 | PWA BOM |
| 6 | 610119C00-017-G | 0 | 2 | RES,130KOhm,+/-1%,1/16W,G,SMD0402 | KOA SPEER ELECTRONICS, INC. | RK73H1ETTP1303F | N | (+)PSUR1,PSUR4 | PWA BOM |
| 7 | 610116G00-017-G | 0 | 2 | RES,150KOhm,+/-1%,1/16W,G,SMD0402 | KOA SPEER ELECTRONICS, INC. | RK73H1ETTP1503F | N | (+)PSUR2,PSUR5 | PWA BOM |
| 8 | 61011LF00-017-G | 1 | 2 | RES,499KOhm,+/-1%,1/16W,G,SMD0402 | KOA SPEER ELECTRONICS, INC. | RK73H1ETTP4993F | N | (+)R1847 | PWA BOM |
| 9 | 3406B5J00-317-G | 0 | 1 | CONN,Header,Socket,V/T,Bla,2mm,15u,G,DIP-18 | MOLEX INCORPORATED | 79107-7008 |  | (+)J10 | PWA BOM |
| 10 | 34064J800-317-G | 0 | 1 | CONN,Header,Socket,2X2,V/T,Bla,2mm,15u,G,DIP-4 | MOLEX INCORPORATED | 79107-7001 |  | (+)J13 | PWA BOM |
| 11 | TLRH3APTTE20L0F | 0 | 2 | RES,20mOhm,+/-1%,2W,G,SMD2512 | KOA SPEER ELECTRONICS, INC. | TLRH3APTTE20L0F |  | (+)PBAR65,PAAR65 | PWA BOM |
| 12 | SLW1TTE50L0F | 0 | 4 | RES,50mOhm,+/-1%,1.5W,G,SMD2512 | KOA | SLW1TTE50L0F |  | (+)PBER65,PAFR65,PAER65,PBFR66 | PWA BOM |
| 13 | SLW1TTE75L0F | 0 | 2 | RES,75mOhm,+/-1%,1.5W,G,SMD2512 | KOA | SLW1TTE75L0F |  | (+)PBMR65,PAMR65 | PWA BOM |
| 14 | 34080F500-653-G | 0 | 1 | CONN,Switch,slide,25mA,24V,G,SMD-8 | DIPTRONICS MANUFACTURING INC. | DHN-04F-T-V-T/R |  | (+)PSUSW1 | PWA BOM |
| 15 | 79107-7008 | 1 | 0 | CONN,Header,Socket,2X9,V/T,Bla,2mm,15u,G,DIP-18 | MOLEX INCORPORATED | 79107-7008 |  | (-)J10 | PWA BOM |
| 16 | 79107-7001 | 1 | 0 | CONN,Header,Socket,2X2,V/T,Bla,2mm,15u,G,DIP-4 | MOLEX INCORPORATED | 79107-7001 |  | (-)J13 | PWA BOM |
| 17 | 61012WF00-017-G | 2 | 0 | RES,20mOhm,+/-1%,1W,G,SMD2512 | KOA SPEER ELECTRONICS, INC. | UR73D3ATTE20L0F |  | (-)PBAR65,PAAR65 | PWA BOM |
| 18 | 610118N00-017-G | 4 | 0 | RES,487 Ohm,+/-1%,1/16W,G,SMD0402 | KOA SPEER ELECTRONICS, INC. | RK73H1ETTP4870F | N | (-)PBFR34,PBER34,PAFR34,PAER34 | PWA BOM |
| 19 | 610605200-034-G | 4 | 0 | RES,50mOhm,+/-1%,3W,G,SMD2512 | CYNTEC CO. LTD | RL-3264-0W-R050-FNH |  | (-)PBER65,PAFR65,PAER65,PBFR66 | PWA BOM |
| 20 | 61011J902-017-G | 2 | 0 | RES,402 Ohm,+/-1%,1/16W,G,SMD0402 | KOA SPEER ELECTRONICS, INC. | RK73H1ETTP4020F | N | (-)PBMR34,PAMR34 | PWA BOM |
| 21 | TLRH3APTTE60L0F | 2 | 0 | RES,60mOhm,+/-0.5%,2W,G,SMD2512 | KOA SPEER ELECTRONICS, INC. | TLRH3APTTE60L0F | Y | (-)PBMR65,PAMR65 | PWA BOM |
| 22 | 610115R00-017-G | 1 | 0 | RES,15KOhm,+/-1%,1/16W,G,SMD0402 | KOA SPEER ELECTRONICS, INC. | RK73H1ETTP1502F | N | (-)PSUR1 | PWA BOM |
| OOOOOOOOOOOOOOOOOOOOOOOOOOOOOOOOOOOOOOOOOOOOOOOOOOOOOOOOOOOOOOOOOOOOOOOOOOOOOOOOOOOOOOOOOO | OOOOOOOOOOOOOOOOOOOOOOOOOOOOOOOOOOOOOOOOOOOOOOOOOOOOOOOOOOOOOOOOOOOOOOOOOOOOOOOOOOOOOOOOOO | OOOOOOOOOOOOOOOOOOOOOOOOOOOOOOOOOOOOOOOOOOOOOOOOOOOOOOOOOOOOOOOOOOOOOOOOOOOOOOOOOOOOOOOOOO | OOOOOOOOOOOOOOOOOOOOOOOOOOOOOOOOOOOOOOOOOOOOOOOOOOOOOOOOOOOOOOOOOOOOOOOOOOOOOOOOOOOOOOOOOO | OOOOOOOOOOOOOOOOOOOOOOOOOOOOOOOOOOOOOOOOOOOOOOOOOOOOOOOOOOOOOOOOOOOOOOOOOOOOOOOOOOOOOOOOOO | OOOOOOOOOOOOOOOOOOOOOOOOOOOOOOOOOOOOOOOOOOOOOOOOOOOOOOOOOOOOOOOOOOOOOOOOOOOOOOOOOOOOOOOOOO | OOOOOOOOOOOOOOOOOOOOOOOOOOOOOOOOOOOOOOOOOOOOOOOOOOOOOOOOOOOOOOOOOOOOOOOOOOOOOOOOOOOOOOOOOO | OOOOOOOOOOOOOOOOOOOOOOOOOOOOOOOOOOOOOOOOOOOOOOOOOOOOOOOOOOOOOOOOOOOOOOOOOOOOOOOOOOOOOOOOOO | OOOOOOOOOOOOOOOOOOOOOOOOOOOOOOOOOOOOOOOOOOOOOOOOOOOOOOOOOOOOOOOOOOOOOOOOOOOOOOOOOOOOOOOOOO |  |
| TLA Parts Change |  |  |  |  |  |  |  |  |  |
| Item | Foxconn P/N | Qty | Part Description | Manufacturer Full Name | Manufacturer P/N | RoHS | Location | Remark |  |
| BOM Change List Date:Thu May 18 14:11:20 GMT+08:00 2017 |  |  |  |  |  |  |  |  |  |
| New BOM file : C:\<user>\ |  |  |  |  |  |  |  |  |  |
| Old BOM file : C:\<user>\ |  |  |  |  |  |  |  |  |  |
| ##### Add Parts |  |  |  |  |  |  |  |  |  |
| Item | Location | Qty | Foxconn P/N | Part Description | Manufacturer Full Name | Manufacturer P/N | RoHS | Sheet |  |
| 1 | D56 | 1 | 520304B00-237-G | DIODE,Schottky,BAT54WS-7-F,30V,0.1A,G,SOD323-2,SMD | DIODES INEORPORATION | BAT54WS-7-F | G | PWA BOM |  |
|  |  |  | 520303500-223-G | Diode,Schottky,BAT54HT1G,30V,200mA,SOD-323,2P,G | ON SEMICONDUCTOR CORP | BAT54HT1G | G | PWA BOM |  |
|  |  |  | 520308200-031-G | DIODE,Schottky,1PS76SB10,30V,200mA,G,SOD323-2,SMD | NXP SEMICONDUCTORS | 1PS76SB10 | G | PWA BOM |  |
| 2 | R1549 | 1 | 610107A00-017-G | RES,0 Ohm,+/-5%,1/16W,G,SMD0402 | KOA SPEER ELECTRONICS, INC. | RK73Z1ETTP | G | PWA BOM |  |
|  |  |  | 610107A00-012-G | RES,0 Ohm,+/-5%,1/16W,G,SMD0402 | WALSIN | WR04X000PTL | G | PWA BOM |  |
|  |  |  | 610107A00-011-G | RES,0 Ohm,+/-5%,1/16W,G,SMD0402 | YAGEO | RC0402JR-070RL | G | PWA BOM |  |
|  |  |  | 610107A00-044-G | RES,0 Ohm,+/-5%,1/16W,G,SMD0402 | TA-I | RM04JTN0 | G | PWA BOM |  |
|  |  |  | 610107A00-024-G | RES,0 Ohm,+/-5%,1/16W,G,SMD0402 | PANASONIC INDUSTRIAL CO.,LTD. | ERJ2GE0R00X | G | PWA BOM |  |
|  |  |  | 610107A00-029-G | RES,0 Ohm,+/-5%,1/16W,G,SMD0402 | VISHAY ENTER TECHNO LOGY.INC | CRCW04020000Z0ED | G | PWA BOM |  |
| 3 | PSUR4 | 1 | 610119C00-017-G | RES,130KOhm,+/-1%,1/16W,G,SMD0402 | KOA SPEER ELECTRONICS, INC. | RK73H1ETTP1303F | G | PWA BOM |  |
|  |  |  | 610119C00-011-G | RES,130KOhm,+/-1%,1/16W,G,SMD0402 | YAGEO CORPORATION COMPONENT | RC0402FR-07130KL | G | PWA BOM |  |
|  |  |  | 610119C00-012-G | RES,130KOhm,+/-1%,1/16W,G,SMD0402 | WALSIN TECHNOLOGY CORPORATION | WR04X1303FTL | G | PWA BOM |  |
|  |  |  | 610119C00-044-G | RES,130KOhm,+/-1%,1/16W,G,SMD0402 | TA-I TECHNOLOGY CO., LTD | RM04FTN1303 | G | PWA BOM |  |
| 4 | PSUR2,PSUR5 | 2 | 610116G00-017-G | RES,150KOhm,+/-1%,1/16W,G,SMD0402 | KOA SPEER ELECTRONICS, INC. | RK73H1ETTP1503F | G | PWA BOM |  |
|  |  |  | 610116G00-011-G | RES,150KOhm,+/-1%,1/16W,G,SMD0402 | YAGEO CORPORATION COMPONENT | RC0402FR-07150KL | G | PWA BOM |  |
|  |  |  | 610116G00-012-G | RES,150KOhm,+/-1%,1/16W,G,SMD0402 | WALSIN TECHNOLOGY CORPORATION | WR04X1503FTL | G | PWA BOM |  |
|  |  |  | 610116G00-044-G | RES,150KOhm,+/-1%,1/16W,G,SMD0402 | TA-I TECHNOLOGY CO., LTD | RM04FTN1503 | G | PWA BOM |  |
| 5 | R1847 | 1 | 61011LF00-017-G | RES,499KOhm,+/-1%,1/16W,G,SMD0402 | KOA SPEER ELECTRONICS, INC. | RK73H1ETTP4993F | G | PWA BOM |  |
|  |  |  | 61011LF00-012-G | RES,499KOhm,+/-1%,1/16W,G,SMD0402 | WALSIN | WR04X4993FTL | G | PWA BOM |  |
|  |  |  | 61011LF00-011-G | RES,499KOhm,+/-1%,1/16W,G,SMD0402 | YAGEO | RC0402FR-07499KL | G | PWA BOM |  |
|  |  |  | 61011LF00-044-G | RES,499KOhm,+/-1%,1/16W,G,SMD0402 | TA-I | RM04FTN4993 | G | PWA BOM |  |
| 6 | PSUSW1 | 1 | 34080F500-653-G | CONN,Switch,slide,25mA,24V,G,SMD-8 | DIPTRONICS MANUFACTURING INC. | DHN-04F-T-V-T/R | G | PWA BOM |  |
| ##### Remove Parts |  |  |  |  |  |  |  |  |  |
| Item | Location | Qty | Foxconn P/N | Part Description | Manufacturer Full Name | Manufacturer P/N | RoHS | Sheet |  |
| 1 | PAER46 | 1 | 610107A00-017-G | RES,0 Ohm,+/-5%,1/16W,G,SMD0402 | KOA SPEER ELECTRONICS, INC. | RK73Z1ETTP | G | PWA BOM |  |
|  |  |  | 610107A00-012-G | RES,0 Ohm,+/-5%,1/16W,G,SMD0402 | WALSIN | WR04X000PTL | G | PWA BOM |  |
|  |  |  | 610107A00-011-G | RES,0 Ohm,+/-5%,1/16W,G,SMD0402 | YAGEO | RC0402JR-070RL | G | PWA BOM |  |
|  |  |  | 610107A00-044-G | RES,0 Ohm,+/-5%,1/16W,G,SMD0402 | TA-I | RM04JTN0 | G | PWA BOM |  |
|  |  |  | 610107A00-024-G | RES,0 Ohm,+/-5%,1/16W,G,SMD0402 | PANASONIC INDUSTRIAL CO.,LTD. | ERJ2GE0R00X | G | PWA BOM |  |
|  |  |  | 610107A00-029-G | RES,0 Ohm,+/-5%,1/16W,G,SMD0402 | VISHAY ENTER TECHNO LOGY.INC | CRCW04020000Z0ED | G | PWA BOM |  |
| ##### Change Parts |  |  |  |  |  |  |  |  |  |
| Item | Location | Qty | Foxconn P/N | Part Description | Manufacturer Full Name | Manufacturer P/N | RoHS | Sheet | Remark |
| 1 | PHAD6,D20,D21 | 3 | 520100200-237-G | DIODE,Switching,1N4148W-7-F,100V,0.15A,G,SOD123-2,SMD | DIODES INEORPORATION | 1N4148W-7-F | G | PWA BOM | In New BOM |
|  |  |  | 520102P00-031-G | DIODE,Switching,BAS16H,100V,0.5A,G,SOD123F-2,SMD | NXP SEMICONDUCTORS | BAS16H | G | PWA BOM | In New BOM |
|  | PHAD6,D20,D21 | 3 | 520100200-237-G | DIODE,Switching,1N4148W-7-F,100V,0.15A,G,SOD123-2,SMD | DIODES INEORPORATION | 1N4148W-7-F | G | PWA BOM | In Old BOM |
| 2 | D33 | 1 | 520308D00-237-G | DIODE,Schottky Rectifier,1N5819HW-7-F,40V,1A,G,SOD123-2,SMD | DIODES INCORPORATION | 1N5819HW-7-F | G | PWA BOM | In New BOM |
|  |  |  | 520318S00-223-G | Diode,Schottky,MBR140SFT3G,40V,1A,G,SOD-123FL-2,SMD | ON SEMICONDUCTOR CORP | MBR140SFT3G | G | PWA BOM | In New BOM |
|  |  |  | 52030P100-223-G | Diode,Schottky,MBR140SFT1G,40V,1A,SOD-123FL,2P,G | ON | MBR140SFT1G | G | PWA BOM | In New BOM |
|  | D33 | 1 | 520308D00-237-G | DIODE,Schottky Rectifier,1N5819HW-7-F,40V,1A,G,SOD123-2,SMD | DIODES INCORPORATION | 1N5819HW-7-F | G | PWA BOM | In Old BOM |
|  |  |  | MBR140SFT3G | DIODE,MBR140SFT3G | ON SEMICONDUCTOR CORP | MBR140SFT3G | G | PWA BOM | In Old BOM |
|  |  |  | 52030P100-223-G | Diode,Schottky,MBR140SFT1G,40V,1A,SOD-123FL,2P,G | ON | MBR140SFT1G | G | PWA BOM | In Old BOM |
| 3 | ED1,ED2,ED3 | 3 | 521800900-227-G | DIODE,Array-TVS,SRV05-4.TCT,5V,12A,G,SOT23-6,SMD | SEMTECH CORPORATION. | SRV05-4.TCT | G | PWA BOM | In New BOM |
|  |  |  | 52180H500-086-G | Diode,Array-TVS,SRV05-04HTG,SOT-23,6P,G | LITTELFUSE FAR EAST PTE LTD | SRV05-04HTG | G | PWA BOM | In New BOM |
|  | ED1,ED2,ED3 | 3 | 521800900-227-G | DIODE,Array-TVS,SRV05-4.TCT,5V,12A,G,SOT23-6,SMD | SEMTECH CORPORATION. | SRV05-4.TCT | G | PWA BOM | In Old BOM |
|  |  |  | 52180C400-237-G | Diode,Array-TVS,DRTR5V0U4TS-7,TSOT,6P,G | DIODES INCORPORATION | DRTR5V0U4TS-7 | G | PWA BOM | In Old BOM |
|  |  |  | 52180H500-086-G | Diode,Array-TVS,SRV05-04HTG,SOT-23,6P,G | LITTELFUSE FAR EAST PTE LTD | SRV05-04HTG | G | PWA BOM | In Old BOM |
| 4 | FL1,FL4,FL10 | 3 | 720406E00-015-G | Common Choke,90Ohm@100MHz,+/-25%,220mA,G,SMD0805 | MURATA ELEC. NORTH AMERICA | DLW21HN900HQ2L | G | PWA BOM | In New BOM |
|  |  |  | 720405D00-016-G | Common Choke,90 Ohm@100MHz,Type,200mA,G,SMD0805 | TDK | ACM2012E-900-2P-T01 | G | PWA BOM | In New BOM |
|  |  |  | 720402300-129-G | Filter,Inductor type,Common Mode(CMODE),90Ohm@100MHz,Type,300mA,,SMD0805,G | MagLayers | MCI-2012H-900 | G | PWA BOM | In New BOM |
|  | FL1,FL4,FL10 | 3 | 720406E00-015-G | Common Choke,90Ohm@100MHz,+/-25%,220mA,G,SMD0805 | MURATA ELEC. NORTH AMERICA | DLW21HN900HQ2L | G | PWA BOM | In Old BOM |
|  |  |  | 720405D00-016-G | Common Choke,90 Ohm@100MHz,Type,200mA,G,SMD0805 | TDK | ACM2012E-900-2P-T01 | G | PWA BOM | In Old BOM |
| 5 | FL2,FL3,FL5,FL6,FL7,FL8,FL9 | 7 | 720400201-015-G | Filter,Common Mode,90Ohm@100MHz,+/-25%,330mA,G,SMD0805 | MURATA ELEC. NORTH AMERICA | DLW21HN900SQ2L | G | PWA BOM | In New BOM |
|  |  |  | 720400M00-059-G | Common Choke,90 Ohm@100MHz,+/-25%,400mA,G,SMD0805 | TAI-TECH ADVANCED ELECTRONICS CO., LTD. | WCM2012F2SF-900T04 | G | PWA BOM | In New BOM |
|  |  |  | 720400800-016-G | Common Choke,90 Ohm@100MHz,+/-25%,400mA,190mOhm,2L,G,SMD0805 | TDK | ACM2012-900-2P-T | G | PWA BOM | In New BOM |
|  |  |  | 720400200-129-G | Common Choke,90 Ohm@100MHz,+/-25%,400mA,190mOhm,2L,G,SMD0805 | Maglayers | MCI-2012-900 | G | PWA BOM | In New BOM |
|  | FL2,FL3,FL5,FL6,FL7,FL8,FL9 | 7 | 720400201-015-G | Filter,Common Mode,90Ohm@100MHz,+/-25%,330mA,G,SMD0805 | MURATA ELEC. NORTH AMERICA | DLW21HN900SQ2L | G | PWA BOM | In Old BOM |
|  |  |  | 720400M00-059-G | Common Choke,90 Ohm@100MHz,+/-25%,400mA,G,SMD0805 | TAI-TECH ADVANCED ELECTRONICS CO., LTD. | WCM2012F2SF-900T04 | G | PWA BOM | In Old BOM |
|  |  |  | 720400800-016-G | Common Choke,90 Ohm@100MHz,+/-25%,400mA,190mOhm,2L,G,SMD0805 | TDK | ACM2012-900-2P-T | G | PWA BOM | In Old BOM |
| 6 | FS2,FS3 | 2 | 730100400-086-G | Fuse,Very fast acting,3A,32V,G,SMD0603 | LITTELFUSE FAR EAST PTE LTD | 0467003.NR | G | PWA BOM | In New BOM |
|  | FS2,FS3 | 2 | 730100400-086-G | Fuse,Very fast acting,3A,32V,G,SMD0603 | LITTELFUSE FAR EAST PTE LTD | 0467003.NR | G | PWA BOM | In Old BOM |
|  |  |  | 730103Q00-088-G | Fuse,Fast acting,32V,3A,SMD0603,G | COOPER BUSSMANN, INC. | CC06H3A-TR | G | PWA BOM | In Old BOM |
| 7 | FS4,FS9,FS12,FS15,FS16,FS21 | 6 | 730102701-086-G | Fuse,Fast acting,32V,7A,G,SMD1206 | LITTELFUSE FAR EAST PTE LTD | 0440007.WR | G | PWA BOM | In New BOM |
|  |  |  | 730102704-088-G | Fuse,Fast acting,32V,7A,SMD1206,G | Cooper Bussmann | CC12H7A-TR | G | PWA BOM | In New BOM |
|  | FS4,FS9,FS12,FS15,FS16,FS21 | 6 | 730102701-086-G | Fuse,Fast acting,32V,7A,G,SMD1206 | LITTELFUSE FAR EAST PTE LTD | 0440007.WR | G | PWA BOM | In Old BOM |
|  |  |  | CC12H7A-TR | Fuse,CC12H7A-TR | Cooper Bussmann | CC12H7A-TR | G | PWA BOM | In Old BOM |
| 8 | FS5,FS8,FS11,FS14,FS17,FS19,FS20 | 7 | 730103M00-086-G | Fuse,Fast acting,32V,5A,G,SMD0603 | LITTELFUSE FAR EAST PTE LTD | 0438005.WR | G | PWA BOM | In New BOM |
|  |  |  | 730103M00-088-G | Fuse,Fast acting,32V,5A,SMD0603,G | COOPER BUSSMANN, INC. | CC06H5A-TR | G | PWA BOM | In New BOM |
|  | FS5,FS8,FS11,FS14,FS17,FS19,FS20 | 7 | 730103M00-086-G | Fuse,Fast acting,32V,5A,G,SMD0603 | LITTELFUSE FAR EAST PTE LTD | 0438005.WR | G | PWA BOM | In Old BOM |
|  |  |  | 730100H00-085-G | Fuse,Very fast acting,32V,5A,G,SMD0603 | BEL FUSE INC | C2Q 5TR | G | PWA BOM | In Old BOM |
|  |  |  | 730103M00-088-G | Fuse,Fast acting,32V,5A,SMD0603,G | COOPER BUSSMANN, INC. | CC06H5A-TR | G | PWA BOM | In Old BOM |
| 9 | FS6,FS7,FS10,FS13,FS18 | 5 | 730102B01-086-G | Fuse,Fast acting,32V,1A,G,SMD0603 | LITTELFUSE FAR EAST PTE LTD | 0438001.WR | G | PWA BOM | In New BOM |
|  |  |  | 730102B03-088-G | Fuse,Fast acting,32V,1A,SMD0603,G | COOPER BUSSMANN, INC. | CC06H1A-TR | G | PWA BOM | In New BOM |
|  | FS6,FS7,FS10,FS13,FS18 | 5 | 730102B01-086-G | Fuse,Fast acting,32V,1A,G,SMD0603 | LITTELFUSE FAR EAST PTE LTD | 0438001.WR | G | PWA BOM | In Old BOM |
|  |  |  | 730100C00-085-G | Fuse,Very fast acting,32V,1A,G,SMD0603 | BEL FUSE INC | C2Q 1TR | G | PWA BOM | In Old BOM |
|  |  |  | 730102B00-101-G | Fuse,Fast acting,32V,1A,G,SMD0603 | BOURNS INC | SF-0603F100-2 | G | PWA BOM | In Old BOM |
|  |  |  | 730102B03-088-G | Fuse,Fast acting,32V,1A,SMD0603,G | COOPER BUSSMANN, INC. | CC06H1A-TR | G | PWA BOM | In Old BOM |
| 10 | FS22 | 1 | 730102000-086-G | Fuse,Fast acting,24V,10A,G,SMD1206 | LITTELFUSE FAR EAST PTE LTD | 0501010.WR | G | PWA BOM | In New BOM |
|  | FS22 | 1 | 730102000-086-G | Fuse,Fast acting,24V,10A,G,SMD1206 | LITTELFUSE FAR EAST PTE LTD | 0501010.WR | G | PWA BOM | In Old BOM |
|  |  |  | 730104D00-57M-G | Fuse,Fast acting,32V,10A,G,SMD1206 | COOPER BUSSMANN, INC. | CC12H10A-TR | G | PWA BOM | In Old BOM |
| 11 | LED1 | 1 | 52112H800-289-G | LED,Blu,LTST-C193TBKT-LO,5V,20mA,G,SMD | LITE-ON TECHNOLOGY CORPORATION | LTST-C193TBKT-LO | G | PWA BOM | In New BOM |
|  |  |  | 52112H900-354-G | LED LAMP,LG-192DBK-CT/T-SD,Blue,24mcd@IF=5mA,475nm,999.9999V,20mA,N/A,,SMD0603,2P,G | Ligitek Electronics Co., Ltd. | LG-192DBK-CT/T-SD | G | PWA BOM | In New BOM |
|  | LED1 | 1 | 52112H800-289-G | LED,Blu,LTST-C193TBKT-LO,5V,20mA,G,SMD | LITE-ON TECHNOLOGY CORPORATION | LTST-C193TBKT-LO | G | PWA BOM | In Old BOM |
|  |  |  | 52112H900-354-G | LED LAMP,LG-192DBK-CT/T-SD,Blue,24mcd@IF=5mA,475nm,999.9999V,20mA,N/A,,SMD0603,2P,G | Ligitek Electronics Co., Ltd. | LG-192DBK-CT/T-SD | G | PWA BOM | In Old BOM |
|  |  |  | 52113GN00-290-G | LED LAMP,B1931NB--20D-000114,Blue,112.5mcd@IF=20mA,470nm,5V,20mA,N/A,,SMD0603,2P,G | HARVATEK | B1931NB--20D-000114 | G | PWA BOM | In Old BOM |
|  |  |  | SML-LX0603USBWATR | LED,SML-LX0603USBWATR | LUMEX | SML-LX0603USBWATR | G | PWA BOM | In Old BOM |
| 12 | LED8,LED9 | 2 | 52113AY00-289-G | LED,Red,LTL-42NEW8DH184P,5V,20mA,G,DIP-2 | LITE-ON TECHNOLOGY CORPORATION | LTL-42NEW8DH184P | G | PWA BOM | In New BOM |
|  | LED8,LED9 | 2 | 52113AY00-289-G | LED,Red,LTL-42NEW8DH184P,5V,20mA,G,DIP-2 | LITE-ON TECHNOLOGY CORPORATION | LTL-42NEW8DH184P | G | PWA BOM | In Old BOM |
|  |  |  | 52113GL00-354-G | LED LAMP,LA140B-1/H-PF,Red,4.2mcd@IF=10mA,697nm,5V,20mA,N/A,,DIP,2P,G | Ligitek Electronics Co., Ltd. | LA140B-1/H-PF | G | PWA BOM | In Old BOM |
|  |  |  | L-7104ADFX013-TW | LED,L-7104ADFX013-TW | Kingbright | L-7104ADFX013-TW | G | PWA BOM | In Old BOM |
| 13 | LED10,LED14 | 2 | 52113B000-289-G | LED,Yellow,LTL-42NSV8DH184P,5V,20mA,G,DIP-2 | LITE-ON TECHNOLOGY CORPORATION | LTL-42NSV8DH184P | G | PWA BOM | In New BOM |
|  |  |  | L-7104ADFX012-TW | LED,L-7104ADFX012-TW | Kingbright | L-7104ADFX012-TW | G | PWA BOM | In New BOM |
|  | LED10,LED14 | 2 | 52113B000-289-G | LED,Yellow,LTL-42NSV8DH184P,5V,20mA,G,DIP-2 | LITE-ON TECHNOLOGY CORPORATION | LTL-42NSV8DH184P | G | PWA BOM | In Old BOM |
|  |  |  | 52113GK00-354-G | LED LAMP,LA140B-1/Y-PF,Yellow,12mcd@IF=10mA,585nm,5V,20mA,N/A,,DIP,2P,G | Ligitek Electronics Co., Ltd. | LA140B-1/Y-PF | G | PWA BOM | In Old BOM |
|  |  |  | L-7104ADFX012-TW | LED,L-7104ADFX012-TW | Kingbright | L-7104ADFX012-TW | G | PWA BOM | In Old BOM |
| 14 | LED11,LED12 | 2 | 52113AW00-289-G | LED,Green,LTL-42NGY8DH184P,5V,20mA,G,DIP-2 | LITE-ON TECHNOLOGY CORPORATION | LTL-42NGY8DH184P | G | PWA BOM | In New BOM |
|  |  |  | SSF-LXH303SUGD | LED,Green,LTL-42NGY8DH184P,5V,20mA,G,DIP-2 | Lumex | SSF-LXH303SUGD | G | PWA BOM | In New BOM |
|  | LED11,LED12 | 2 | 52113AW00-289-G | LED,Green,LTL-42NGY8DH184P,5V,20mA,G,DIP-2 | LITE-ON TECHNOLOGY CORPORATION | LTL-42NGY8DH184P | G | PWA BOM | In Old BOM |
|  |  |  | L-7104ADFX011-TW | LED,L-7104ADFX011-TW | Kingbright | L-7104ADFX011-TW | G | PWA BOM | In Old BOM |
| 15 | LED63,LED64,LED65 | 3 | 52110FE00-289-G | LED,Red,LTST-C190KRKT,2.4V,30mA,G,SMD0603 | LITE-ON TECHNOLOGY CORPORATION | LTST-C190KRKT | G | PWA BOM | In New BOM |
|  | LED63,LED64,LED65 | 3 | 52110FE00-289-G | LED,Red,LTST-C190KRKT,2.4V,30mA,G,SMD0603 | LITE-ON TECHNOLOGY CORPORATION | LTST-C190KRKT | G | PWA BOM | In Old BOM |
|  |  |  | 52113GH00-290-G | LED LAMP,B1911UR--20D-001054,Red,18mcd@IF=20mA,643nm,5V,20mA,N/A,,SMD0603,2P,G | HARVATEK | B1911UR--20D-001054 | G | PWA BOM | In Old BOM |
| 16 | L7 | 1 | 630332000-053-G | IND,3.3uH@100KHz,+/-20%,2.57A,26mOhm,SHLD,G,SMD | TOKO INC. | #A916CY-3R3M=P3 | G | PWA BOM | In New BOM |
|  |  |  | 63035BF00-129-G | IND,3.3uH@100KHz,+/-20%,2.57A,26mOhm,SHLD,G,SMD | MAG.LAYERS, SCIENTIFIC-TECHNICS (KUNSHAN) CO., LTD. | MSCDRI-6035LC-3R3M-EH | G | PWA BOM | In New BOM |
|  | L7 | 1 | 630332000-053-G | IND,3.3uH@100KHz,+/-20%,2.57A,26mOhm,SHLD,G,SMD | TOKO INC. | #A916CY-3R3M=P3 | G | PWA BOM | In Old BOM |
| 17 | L22,L23,L24,L25 | 4 | 720105P00-016-G | FB,80 Ohm@100MHz,+/-25%,500mA,150mOhm,G,SMD0603 | TDK ELECTRONICS EUROPE GMBH | MMZ1608S800AT | G | PWA BOM | In New BOM |
|  |  |  | GMLB-160808-0080P-N8 | FB,80 Ohm@100MHz,+/-25%,500mA,150mOhm,G,SMD0603 | MAG.LAYERS, SCIENTIFIC-TECHNICS (KUNSHAN) CO., LTD. | GMLB-160808-0080P-N8 | G | PWA BOM | In New BOM |
|  | L22,L23,L24,L25 | 4 | 720105P00-016-G | FB,80 Ohm@100MHz,+/-25%,500mA,150mOhm,G,SMD0603 | TDK ELECTRONICS EUROPE GMBH | MMZ1608S800AT | G | PWA BOM | In Old BOM |
|  |  |  | 720107P00-015-G | FB,Multilayer,150mOhm,70Ohm@100MHz,+/-25%,500mA,,SMD0402,G | MURATA ELEC. NORTH AMERICA | BLM15AG700SN1D | G | PWA BOM | In Old BOM |
|  |  |  | GMLB-160808-0080P-N8 | FB,GMLB-160808-0080P-N8 | MAG.LAYERS, SCIENTIFIC-TECHNICS (KUNSHAN) CO., LTD. | GMLB-160808-0080P-N8 | G | PWA BOM | In Old BOM |
| 18 | L34,L36 | 2 | 72010A400-023-G | FB,80Ohm@100MHz,+/-25%,4A,10mOhm,G,SMD1206 | TAIYO ELECTRIC IND.CO.LTD | FBMJ3216HS800-T | G | PWA BOM | In New BOM |
|  |  |  | Z1206C800APWST | FB,80Ohm@100MHz,+/-25%,4A,10mOhm,G,SMD1206 | KEMET | Z1206C800APWST | G | PWA BOM | In New BOM |
|  | L34,L36 | 2 | 72010A400-023-G | FB,80Ohm@100MHz,+/-25%,4A,10mOhm,G,SMD1206 | TAIYO ELECTRIC IND.CO.LTD | FBMJ3216HS800-T | G | PWA BOM | In Old BOM |
| 19 | L45 | 1 | 720101M00-015-G | FB,600 Ohm@100MHz,+/-25%,200mA,650mOhm,G,SMD0603 | MURATA ELEC. NORTH AMERICA | BLM18BD601SN1D | G | PWA BOM | In New BOM |
|  |  |  | 720103000-023-G | FB,600 Ohm@100MHz,+/-25%,250mA,600mOhm,G,SMD0603 | TAIYO ELECTRIC IND.CO.LTD | BK1608HM601-T | G | PWA BOM | In New BOM |
|  | L45 | 1 | 720101M00-015-G | FB,600 Ohm@100MHz,+/-25%,200mA,650mOhm,G,SMD0603 | MURATA ELEC. NORTH AMERICA | BLM18BD601SN1D | G | PWA BOM | In Old BOM |
|  |  |  | 720103000-023-G | FB,600 Ohm@100MHz,+/-25%,250mA,600mOhm,G,SMD0603 | TAIYO ELECTRIC IND.CO.LTD | BK1608HM601-T | G | PWA BOM | In Old BOM |
|  |  |  | 720101L00-059-G | FB,600 Ohm@100MHz,+/-25%,200mA,Multilayer,500mOhm,SMD0603,G | TAI-TECH ADVANCED ELECTRONICS CO., LTD. | FCM1608KF-601T02 | G | PWA BOM | In Old BOM |
| 20 | PBMC7,PBFC7,PBEC7,PBAC7,PAMC7,PAFC7,PAEC7,PAAC7 | 8 | 620102T00-015-G | CAP,150pF,+/-5%,NPO(C0G),50V,G,SMD0402 | MURATA ELEC. NORTH AMERICA | GRM1555C1H151J | G | PWA BOM | In New BOM |
|  |  |  | 620102T00-012-G | CAP,150pF,+/-5%,NPO(C0G),50V,G,SMD0402 | WALSIN TECHNOLOGY CORPORATION | 0402N151J500LT | G | PWA BOM | In New BOM |
|  |  |  | 620102T00-026-G | CAP,150pF,+/-5%,NPO(C0G),50V,G,SMD0402 | SAMSUNG SEMICONDUCTOR | CL05C151JB5NNNC | G | PWA BOM | In New BOM |
|  |  |  | 620102T00-023-G | CAP,150pF,+/-5%,NPO(C0G),50V,G,SMD0402 | TAIYO ELECTRIC IND.CO.LTD | UMK105CG151JV-F | G | PWA BOM | In New BOM |
|  | PBMC7,PBFC7,PBEC7,PBAC7,PAMC7,PAFC7,PAEC7,PAAC7 | 8 | 620102T00-015-G | CAP,150pF,+/-5%,NPO(C0G),50V,G,SMD0402 | MURATA ELEC. NORTH AMERICA | GRM1555C1H151J | G | PWA BOM | In Old BOM |
| 21 | PBMD1,PBFD1,PBED1,PBAD1,PAMD1,PAFD1,PAED1,PAAD1 | 8 | 520103B00-185-G | Diode,Rectifier&Switching,MMBD1205,100V,200mA,G,SOT-23-3,SMD | FAIRCHILD SEMICONDUCTOR CORP | MMBD1205 | G | PWA BOM | In New BOM |
|  |  |  | BAW156HM | Diode,Rectifier&Switching,100V,200mA,G,SOT-23-3,SMD | ROHM | BAW156HM | G | PWA BOM | In New BOM |
|  |  |  | 52010AP00-280-G | Diode,Rectifier&Switching,MMBD3004A,240V,225mA,SOT-23,3P,G | DIODES INC | MMBD3004A | G | PWA BOM | In New BOM |
|  | PBMD1,PBFD1,PBED1,PBAD1,PAMD1,PAFD1,PAED1,PAAD1 | 8 | 520103B00-185-G | Diode,Rectifier&Switching,MMBD1205,100V,200mA,G,SOT-23-3,SMD | FAIRCHILD SEMICONDUCTOR CORP | MMBD1205 | G | PWA BOM | In Old BOM |
| 22 | PBMC4,PAMC4 | 2 | 62010BH00-015-G | CAP,220pF,+/-5%,NPO(C0G),50V,G,SMD0402 | MURATA ELEC. NORTH AMERICA | GRM1555C1H221J | G | PWA BOM | In New BOM |
|  |  |  | 62010BH02-012-G | CAP,220pF,+/-5%,NPO(C0G),50V,G,SMD0402 | WALSIN TECHNOLOGY CORPORATION | 0402N221J500CT | G | PWA BOM | In New BOM |
|  |  |  | 62010BH00-011-G | CAP,220pF,+/-5%,NPO(C0G),50V,G,SMD0402 | YAGEO CORPORATION COMPONENT | CC0402JRNPO9BN221 | G | PWA BOM | In New BOM |
|  |  |  | 62010BH00-026-G | CAP,220pF,+/-5%,NPO(C0G),50V,G,SMD0402 | SAMSUNG SEMICONDUCTOR | CL05C221JB5NNNC | G | PWA BOM | In New BOM |
|  |  |  | 62010BH03-023-G | CAP,220pF,+/-5%,NPO(C0G),50V,G,SMD0402 | TAIYO ELECTRIC IND.CO.LTD | UMK105CG221JV-F | G | PWA BOM | In New BOM |
|  | PBMC4,PAMC4 | 2 | 62010BH00-015-G | CAP,220pF,+/-5%,NPO(C0G),50V,G,SMD0402 | MURATA ELEC. NORTH AMERICA | GRM1555C1H221J | G | PWA BOM | In Old BOM |
| 23 | PHAQ4 | 1 | 51020A000-031-G | TRANS P,PBHV9115T,150V,1A,G,SOT23-3,SMD | NXP SEMICONDUCTORS | PBHV9115T | G | PWA BOM | In New BOM |
|  |  |  | 51020AF00-280-G | Trans PNP,MMBT5401,-150V,-500mA,SOT-23,3P,G | Fairchild | MMBT5401 | G | PWA BOM | In New BOM |
|  |  |  | MMBT5401 | TRANS,150V,1A,G,SOT23-3,SMD | DIODES | MMBT5401 | G | PWA BOM | In New BOM |
|  | PHAQ4 | 1 | 51020A000-031-G | TRANS P,PBHV9115T,150V,1A,G,SOT23-3,SMD | NXP SEMICONDUCTORS | PBHV9115T | G | PWA BOM | In Old BOM |
|  |  |  | 51020AF00-280-G | Trans PNP,MMBT5401,-150V,-500mA,SOT-23,3P,G | Fairchild | MMBT5401 | G | PWA BOM | In Old BOM |
| 24 | PHAQ5,PHAQ6 | 2 | 51032D100-237-G | MOS N,DMN10H220L-7,100V,1.6A,220m@10V,G,SOT-23-3,SMD | DIODES INCORPORATION | DMN10H220L-7 | G | PWA BOM | In New BOM |
|  |  |  | FQT7N10LTF | MOS N,FQT7N10LTF | Fairchild | FQT7N10LTF | G | PWA BOM | In New BOM |
|  | PHAQ5,PHAQ6 | 2 | 51032D100-237-G | MOS N,DMN10H220L-7,100V,1.6A,220m@10V,G,SOT-23-3,SMD | DIODES INCORPORATION | DMN10H220L-7 | G | PWA BOM | In Old BOM |
|  |  |  | FQT7N10L | MOS N,FQT7N10L | Fairchild | FQT7N10L | G | PWA BOM | In Old BOM |
| 25 | PSRL2 | 1 | 63034GW00-088-G | IND,680nH@100KHz,+/-20%,34A,1.33mOhm,SHLD,G,SMD | COOPER BUSSMANN, INC. | HCM1305-R68-R | G | PWA BOM | In New BOM |
|  |  |  | CMLB135T-R68MS | IND,680nH@100KHz,+/-20%,34A,1.33mOhm,SHLD,G,SMD | CYNTEC | CMLB135T-R68MS | G | PWA BOM | In New BOM |
|  | PSRL2 | 1 | 63034GW00-088-G | IND,680nH@100KHz,+/-20%,34A,1.33mOhm,SHLD,G,SMD | COOPER BUSSMANN, INC. | HCM1305-R68-R | G | PWA BOM | In Old BOM |
| 26 | PSUQ1 | 1 | 51030CQ00-185-G | MOS N,2N7002,60V,115mA,7.5ohm@5V,G,SOT23-3,SMD | FAIRCHILD SEMICONDUCTOR CORP | 2N7002 | G | PWA BOM | In New BOM |
|  |  |  | 510301N00-223-G1 | MOS N,2N7002LT1G,60V,0.115A,7.5ohm@5V,G,SOT23-3,SMD | ON SEMICONDUCTOR CORP | 2N7002LT1G1 | G | PWA BOM | In New BOM |
|  | PSUQ1 | 1 | 51030CQ00-185-G | MOS N,2N7002,60V,115mA,7.5ohm@5V,G,SOT23-3,SMD | FAIRCHILD SEMICONDUCTOR CORP | 2N7002 | G | PWA BOM | In Old BOM |
|  |  |  | 510301N00-223-G1 | MOS N,2N7002LT1G,60V,0.115A,7.5ohm@5V,G,SOT23-3,SMD | ON SEMICONDUCTOR CORP | 2N7002LT1G | G | PWA BOM | In Old BOM |
| 27 | PSUU1 | 1 | 880302300-065-G | Converter,input 40V~60V,600W,G,Q54SJ12050NNDH,OVAL | DELTA ELECTRONICS INDUSTRIAL CO.,LTD | Q54SH12050NNDH | G | PWA BOM | In New BOM |
|  |  |  | 880302100-065-G | Converter,input 40V~60V,600W,G,Q54SH12050NNDH | DELTA ELECTRONICS INDUSTRIAL CO.,LTD | Q54SH12050NNDH | G | PWA BOM | In New BOM |
|  | PSUU1 | 1 | 880302300-065-G | Converter,input 40V~60V,600W,G,Q54SJ12050NNDH,OVAL | DELTA ELECTRONICS INDUSTRIAL CO.,LTD | Q54SH12050NNDH | G | PWA BOM | In Old BOM |
| 28 | QN2,QN3 | 2 | 510503B00-223-G | MOS N/N,NTZD3154NT1G,20V,0.54A,550m24.5V,G,SOT563-6,SMD | ON SEMICONDUCTOR CORP | NTZD3154NT1G | G | PWA BOM | In New BOM |
|  |  |  | Si1034CX-T1-GE3 | MOS N/N,Si1034CX-T1-GE3 | Vishay | Si1034CX-T1-GE3 | G | PWA BOM | In New BOM |
|  |  |  | SSM6N36FE | MOS N/N,SSM6N36FE | Toshiba | SSM6N36FE | G | PWA BOM | In New BOM |
|  | QN2,QN3 | 2 | 510503B00-223-G | MOS N/N,NTZD3154NT1G,20V,0.54A,550m24.5V,G,SOT563-6,SMD | ON SEMICONDUCTOR CORP | NTZD3154NT1G | G | PWA BOM | In Old BOM |
|  |  |  | 51050AK00-030-G | MOS N/N,EM6K6T2R,20V,0.3A,1ohm@4V,G,EMT-6,SMD | ROHM CORPORATION | EM6K6T2R | G | PWA BOM | In Old BOM |
|  |  |  | Si1034CX-T1-GE3 | MOS N/N,Si1034CX-T1-GE3 | Vishay | Si1034CX-T1-GE3 | G | PWA BOM | In Old BOM |
|  |  |  | SSM6N36FE | MOS N/N,SSM6N36FE | Toshiba | SSM6N36FE | G | PWA BOM | In Old BOM |
| 29 | Q12 | 1 | 510501900-237-G | MOS N/N,2N7002DW-7-F,60V,0.115A,7.5ohm@5V,G,SOT363-6,SMD | DIODES INEORPORATION | 2N7002DW-7-F | G | PWA BOM | In New BOM |
|  |  |  | 51050HS00-237-G | MOS N/N,60V,0.115A,7.5ohm@5V,G,SOT363-6,SMD | DIODES | DMN65D8LDW-7 | G | PWA BOM | In New BOM |
|  |  |  | SSM6N7002KFU | MOS N/N,SSM6N7002KFU,60V,200mA,3.3Ohm@4.5V,G,SC88-6,SMD | TOSHIBA ELECTRONICS ASIA LTD | SSM6N7002KFU | G | PWA BOM | In New BOM |
|  |  |  | 510507800-131-G | MOS N/N,SSM6N7002BFU,60V,200mA,3.3Ohm@4.5V,G,SC88-6,SMD | TOSHIBA ELECTRONICS ASIA LTD | SSM6N7002BFU | G | PWA BOM | In New BOM |
|  | Q12 | 1 | 510501900-237-G | MOS N/N,2N7002DW-7-F,60V,0.115A,7.5ohm@5V,G,SOT363-6,SMD | DIODES INEORPORATION | 2N7002DW-7-F | G | PWA BOM | In Old BOM |
|  |  |  | 510507800-131-G | MOS N/N,SSM6N7002BFU,60V,200mA,3.3Ohm@4.5V,G,SC88-6,SMD | TOSHIBA ELECTRONICS ASIA LTD | SSM6N7002BFU | G | PWA BOM | In Old BOM |
| 30 | U17 | 1 | 420212A00-216-G | DRAM,MT40A512M16JY-083E:B,1.2V,512M*16,1.2GHz,G,FBGA-96,SMD | MICRON SEMICONDUCTOR ASIA PTE.LTD. | MT40A512M16JY-083E:B | G | PWA BOM | In New BOM |
|  |  |  | H5AN8G6NAFR-UHC | DRAM,1.2V,512M*16,1.2GHz,G,FBGA-96,SMD | Hynix | H5AN8G6NAFR-UHC | G | PWA BOM | In New BOM |
|  | U17 | 1 | 420212A00-216-G | DRAM,MT40A512M16JY-083E:B,1.2V,512M*16,1.2GHz,G,FBGA-96,SMD | MICRON SEMICONDUCTOR ASIA PTE.LTD. | MT40A512M16JY-083E:B | G | PWA BOM | In Old BOM |
|  |  |  | H5AN8G6NAFR-UHC | DRAM,H5AN8G6NAFR-UHC | Hynix | H5AN8G6NAFR-UHC | G | PWA BOM | In Old BOM |
| 31 | U29 | 1 | 21050F900-217-G | IC,IDT,2305B-1DCG8,B,G,SOIC-8,SMD | INTEGRATED DEVICE TECHNOLOGY | 2305B-1DCG8 | G | PWA BOM | In New BOM |
|  |  |  | 31050JC00-223-G | Logic IC,Buffer,NB2305AI1DR2G,3.0V~3.6V,0.35ns,SOIC,8P,G | ON SEMICONDUCTOR CORP | NB2305AI1DR2G | G | PWA BOM | In New BOM |
|  |  |  | SL2305SC-1 | IC,IDT,2305B-1DCG8,B,G,SOIC-8,SMD | Silicon Labs | SL2305SC-1 | G | PWA BOM | In New BOM |
|  | U29 | 1 | 21050F900-217-G | IC,IDT,2305B-1DCG8,B,G,SOIC-8,SMD | INTEGRATED DEVICE TECHNOLOGY | 2305B-1DCG8 | G | PWA BOM | In Old BOM |
|  |  |  | 31050JC00-223-G | Logic IC,Buffer,NB2305AI1DR2G,3.0V~3.6V,0.35ns,SOIC,8P,G | ON SEMICONDUCTOR CORP | NB2305AI1DR2G | G | PWA BOM | In Old BOM |
| 32 | U83,U101,U102 | 3 | 310500F00-031-G | IC,Buffer,74LVC07APW,1.65~5.5V,G,TSSOP-14,SMD | NXP SEMICONDUCTORS | 74LVC07APW | G | PWA BOM | In New BOM |
|  |  |  | 31050HP00-131-G | IC,Buffer,74LCX07FT,1.65V~5.5V,G,TSSOP-14,SMD | TOSHIBA ELECTRONICS ASIA LTD | 74LCX07FT | G | PWA BOM | In New BOM |
|  |  |  | 31050BY00-183-G | IC,Buffer,74LVC07A,1.65~5.5V,G,TSSOP-14,SMD | DIODES INC | 74LVC0AT14-13 | G | PWA BOM | In New BOM |
|  | U83,U101,U102 | 3 | 310500F00-031-G | IC,Buffer,74LVC07APW,1.65~5.5V,G,TSSOP-14,SMD | NXP SEMICONDUCTORS | 74LVC07APW | G | PWA BOM | In Old BOM |
|  |  |  | 31050HP00-131-G | IC,Buffer,74LCX07FT,1.65V~5.5V,G,TSSOP-14,SMD | TOSHIBA ELECTRONICS ASIA LTD | 74LCX07FT | G | PWA BOM | In Old BOM |
|  |  |  | 31050BY00-183-G | Logic IC,Buffer,SN74LVC07APW,1.65V~5.5V,2.6ns,TSSOP,14P,G | TI | SN74LVC07APW | G | PWA BOM | In Old BOM |
| 33 | U109 | 1 | 310307T00-031-G | IC,Switch,74CBTLV1G125GV,2.3~3.6V,G,SOT753-5,SMD | NXP SEMICONDUCTORS | 74CBTLV1G125GV | G | PWA BOM | In New BOM |
|  |  |  | 310300D00-183-G | IC,Switch,SN74CBTLV1G125DBVR,2.3~3.6V,G,SOT23-5,SMD | TEXAS INSTRUMENTS | SN74CBTLV1G125DBVR | G | PWA BOM | In New BOM |
|  | U109 | 1 | 310307T00-031-G | IC,Switch,74CBTLV1G125GV,2.3~3.6V,G,SOT753-5,SMD | NXP SEMICONDUCTORS | 74CBTLV1G125GV | G | PWA BOM | In Old BOM |
|  |  |  | SN74CBTLV1G125DBVR | IC,Switch,SN74CBTLV1G125DBVR,2.3~3.6V,G,SOT23-5,SMD | TI | SN74CBTLV1G125DBVR | G | PWA BOM | In Old BOM |
| 34 | U110 | 1 | 330103N00-426-G | IC,Optocoupler,PS2811-1-F3-A,G,SSOP-4,SMD | RENESAS TECHNOLOGY AMERICA INC | PS2811-1-F3-A | G | PWA BOM | In New BOM |
|  |  |  | 330102900-289-G | OPTO-IC,ISOL,LTV-217-G,SSOP,4P,G | LITE-ON TECHNOLOGY CORPORATION | LTV-217-G | G | PWA BOM | In New BOM |
|  |  |  | VOS618A-3T | OPTO-IC,VOS618A-3T | VISHAY ENTER TECHNO LOGY.INC | VOS618A-3T | G | PWA BOM | In New BOM |
|  | U110 | 1 | 330103N00-426-G | IC,Optocoupler,PS2811-1-F3-A,G,SSOP-4,SMD | RENESAS TECHNOLOGY AMERICA INC | PS2811-1-F3-A | G | PWA BOM | In Old BOM |
|  |  |  | 330103L00-131-G | OPTO-IC,ISOL,TLP291,SO,4P,G | TOSHIBA ELECTRONICS ASIA LTD | TLP291 | G | PWA BOM | In Old BOM |
|  |  |  | 330102900-289-G | OPTO-IC,ISOL,LTV-217-G,SSOP,4P,G | LITE-ON TECHNOLOGY CORPORATION | LTV-217-G | G | PWA BOM | In Old BOM |
|  |  |  | VOS618A-3T | OPTO-IC,VOS618A-3T | VISHAY ENTER TECHNO LOGY.INC | VOS618A-3T | G | PWA BOM | In Old BOM |
| 35 | U167,U173 | 2 | 310203U00-223-G | IC,Trigger,NL17SZ14DFT2G,1.65~5.5V,G,SOT353-5,SMD | ON SEMICONDUCTOR CORP | NL17SZ14DFT2G | G | PWA BOM | In New BOM |
|  |  |  | 310200900-185-G | IC,Trigger,NC7SZ14P5X,1.65-5.5V,G,SC70-5P,SMD | FAIRCHILD SEMICONDUCTOR CORP | NC7SZ14P5X | G | PWA BOM | In New BOM |
|  |  |  | 310107000-031-G | Logic IC,Gate&Inverter,74LVC1G14GW,1.65V~5.5V,14ns,TSSOP,5P,G | NXP SEMICONDUCTORS | 74LVC1G14GW | G | PWA BOM | In New BOM |
|  | U167,U173 | 2 | 310203U00-223-G | IC,Trigger,NL17SZ14DFT2G,1.65~5.5V,G,SOT353-5,SMD | ON SEMICONDUCTOR CORP | NL17SZ14DFT2G | G | PWA BOM | In Old BOM |
|  |  |  | 310200900-185-G | IC,Trigger,NC7SZ14P5X,1.65-5.5V,G,SC70-5P,SMD | FAIRCHILD SEMICONDUCTOR CORP | NC7SZ14P5X | G | PWA BOM | In Old BOM |
|  |  |  | 310107000-031-G | Logic IC,Gate&Inverter,74LVC1G14GW,1.65V~5.5V,14ns,TSSOP,5P,G | NXP SEMICONDUCTORS | 74LVC1G14GW | G | PWA BOM | In Old BOM |
|  |  |  | 310107600-131-G | IC,Gate&Inverter,TC7SZ14FU,1.65~5.5V,G,SSOP-5,SMD | TOSHIBA ELECTRONICS ASIA LTD | TC7SZ14FU | G | PWA BOM | In Old BOM |
| 36 | X6 | 1 | 710106900-162-G | XTAL,32.768KHz,+/-20ppm,12.5pF,G,SMD | EPSON ELECTRONICS AMERICA,INC. | Q13FC1350000400 | G | PWA BOM | In New BOM |
|  |  |  | 71011P300-100-G | XTAL,32.768KHz,+/-20ppm,12.5pF,G,SMD | TXC CORPORATION | 9H03200031 | G | PWA BOM | In New BOM |
|  | X6 | 1 | 710106900-162-G | XTAL,32.768KHz,+/-20ppm,12.5pF,G,SMD | EPSON ELECTRONICS AMERICA,INC. | Q13FC1350000400 | G | PWA BOM | In Old BOM |
|  |  |  | 71011P300-100-G | XTAL,32.768KHz,+/-20ppm,12.5pF,G,SMD | TXC CORPORATION | 9H03200031 | G | PWA BOM | In Old BOM |
|  |  |  | 71010F700-107-G | XTAL,32.768KHz,+/-20ppm,12.5pF,-40_x0003_~85_x0003_,SMD,G | DAISHINKU CORPORATION/DAISHINKU SINGAPORE PTE LTD/KDS | 1TJF125DP1A000B | G | PWA BOM | In Old BOM |
| 37 | DIMM02,DIMM04,DIMM06,DIMM09,DIMM11,DIMM13,DIMM15,DIMM16,DIMM18,DIMM20,DIMM22,DIMM25,DIMM27,DIMM29,DIMM31,DIMM00 | 16 | 34021BC00-G78-G | CONN,DDR IV,V/T,1.2V,Blu,0.85mm,15u,G,SMD-288 | FCI CONNECTORS HONGKONG LTD. | 10140702-0302K11LF | G | PWA BOM | In New BOM |
|  |  |  | ADDR0245-K010C | CONN,ADDR0245-K010C | LOTES | ADDR0245-K010C | G | PWA BOM | In New BOM |
|  |  |  | 34021CD00-600-G | Memory Connector,AH58897-T2L31-3F,DDR IV,288,SMD,THERMOPLASTIC,0.85mm,15u",Blue,G | FOXCONN | AH58897-T2L31-3F | G | PWA BOM | In New BOM |
|  |  |  | 34021CC00-245-G | Memory Connector,DDR4288S05A1H,DDR IV,288,SMD,NYLON,0.85mm,15u",Blue,G | AMPHENOL SHANGHAI CORP. | DDR4288S05A1H | G | PWA BOM | In New BOM |
|  | DIMM02,DIMM04,DIMM06,DIMM09,DIMM11,DIMM13,DIMM15,DIMM16,DIMM18,DIMM20,DIMM22,DIMM25,DIMM27,DIMM29,DIMM31,DIMM00 | 16 | 34021BC00-G78-G | CONN,DDR IV,V/T,1.2V,Blu,0.85mm,15u,G,SMD-288 | FCI CONNECTORS HONGKONG LTD. | 10140702-0302K11LF | G | PWA BOM | In Old BOM |
|  |  |  | 34021CC00-245-G | Memory Connector,DDR4288S05A1H,DDR IV,288,SMD,NYLON,0.85mm,15u",Blue,G | AMPHENOL SHANGHAI CORP. | DDR4288S05A1H | G | PWA BOM | In Old BOM |
|  |  |  | 34021CD00-600-G | Memory Connector,AH58897-T2L31-3F,DDR IV,288,SMD,THERMOPLASTIC,0.85mm,15u",Blue,G | FOXCONN | AH58897-T2L31-3F | G | PWA BOM | In Old BOM |
| 38 | DIMM01,DIMM03,DIMM05,DIMM07,DIMM08,DIMM10,DIMM12,DIMM14,DIMM17,DIMM19,DIMM21,DIMM23,DIMM24,DIMM26,DIMM28,DIMM30 | 16 | 34021BD00-G78-G | CONN,DDR IV,V/T,1.2V,Bla,0.85mm,15u,G,SMD-288 | FCI CONNECTORS HONGKONG LTD. | 10140702-0301K11LF | G | PWA BOM | In New BOM |
|  |  |  | ADDR0245-P009C | CONN,ADDR0245-P009C | LOTES | ADDR0245-P009C | G | PWA BOM | In New BOM |
|  |  |  | 34021CF00-600-G | Memory Connector,AH58897-T2B21-3F,DDR IV,288,SMD,THERMOPLASTIC,0.85mm,15u",Black,G | FOXCONN | AH58897-T2B21-3F | G | PWA BOM | In New BOM |
|  |  |  | 34021CE00-245-G | Memory Connector,DDR4288S0511H,DDR IV,288,SMD,NYLON,0.85mm,15u",Black,G | AMPHENOL SHANGHAI CORP. | DDR4288S0511H | G | PWA BOM | In New BOM |
|  | DIMM01,DIMM03,DIMM05,DIMM07,DIMM08,DIMM10,DIMM12,DIMM14,DIMM17,DIMM19,DIMM21,DIMM23,DIMM24,DIMM26,DIMM28,DIMM30 | 16 | 34021BD00-G78-G | CONN,DDR IV,V/T,1.2V,Bla,0.85mm,15u,G,SMD-288 | FCI CONNECTORS HONGKONG LTD. | 10140702-0301K11LF | G | PWA BOM | In Old BOM |
|  |  |  | 34021CE00-245-G | Memory Connector,DDR4288S0511H,DDR IV,288,SMD,NYLON,0.85mm,15u",Black,G | AMPHENOL SHANGHAI CORP. | DDR4288S0511H | G | PWA BOM | In Old BOM |
|  |  |  | 34021CF00-600-G | Memory Connector,AH58897-T2B21-3F,DDR IV,288,SMD,THERMOPLASTIC,0.85mm,15u",Black,G | FOXCONN | AH58897-T2B21-3F | G | PWA BOM | In Old BOM |
| 39 | JP1(2-3),JP4(2-3),JP5(2-3),JP6(1-2) | 4 | 340612R00-309-G | CONN,Jumper,Bla,2.54mm,G,DIP-2 | SAMTEC INC. | SNT-100-BK-G | G | PWA BOM | In New BOM |
|  |  |  | 34065L900-GRT-G | CONN,jumper,Bla,2.54mm,30u,G,DIP-2 | PINREX TECHNOLOGY CORP. | 201-71-01DB00 | G | PWA BOM | In New BOM |
|  |  |  | 34066N500-600-G | Header&Socket Connector,SJ0520F-A0,Jumper,2,DIP,PBT,2.54mm,3u",Black,G | FOXCONN TECHNOLOGY CO.,LTD. | SJ0520F-A0 | G | PWA BOM | In New BOM |
|  | JP1(2-3),JP4(2-3),JP5(2-3),JP6(1-2) | 4 | 340612R00-309-G | CONN,Jumper,Bla,2.54mm,G,DIP-2 | SAMTEC INC. | SNT-100-BK-G | G | PWA BOM | In Old BOM |
|  |  |  | 34065L900-GRT-G | CONN,jumper,Bla,2.54mm,30u,G,DIP-2 | PINREX TECHNOLOGY CORP. | 201-71-01DB00 | G | PWA BOM | In Old BOM |
|  |  |  | 34066N500-600-G | Header&Socket Connector,SJ0520F-A0,Jumper,2,DIP,PBT,2.54mm,3u",Black,G | FOXCONN TECHNOLOGY CO.,LTD. | SJ0520F-A0 | G | PWA BOM | In Old BOM |
|  |  |  | 34069RA00-637-G | Header&Socket Connector,1200210020,Jumper,2,DIP,PBT,2.54mm,3u",Black,G | LONG SHOUNG CO.,LTD. | 1200210020 | G | PWA BOM | In Old BOM |
| 40 | J35,J37,J39,J42,J45 | 5 | 3406AQH00-317-G | CONN,Header,Pin Header,1X6,V/T,Bla,2.54mm,G,SMD-6 | MOLEX INCORPORATED | 87898-0656 | G | PWA BOM | In New BOM |
|  |  |  | 3406A9F00-GRT-G | Header&Socket Connector,212-91-06GBE2,Pin Header,6,SMD,NY6T,2.54mm,3u",Black,G | PINREX TECHNOLOGY CORP. | 212-91-06GBE2 | G | PWA BOM | In New BOM |
|  |  |  | 3406AYA00-245-G | Header&Socket Connector,G800MR302032EU,Pin Header,6,DIP,LCP,2.54mm,999.9999u",Black,G | AMPHENOL SHANGHAI CORP. | G800MR302032EU | G | PWA BOM | In New BOM |
|  | J35,J37,J39,J42,J45 | 5 | 3406AQH00-317-G | CONN,Header,Pin Header,1X6,V/T,Bla,2.54mm,G,SMD-6 | MOLEX INCORPORATED | 87898-0656 | G | PWA BOM | In Old BOM |
|  |  |  | 3406A9F00-GRT-G | Header&Socket Connector,212-91-06GBE2,Pin Header,6,SMD,NY6T,2.54mm,3u",Black,G | PINREX TECHNOLOGY CORP. | 212-91-06GBE2 | G | PWA BOM | In Old BOM |
|  |  |  | 3406AYA00-245-G | Header&Socket Connector,G800MR302032EU,Pin Header,6,DIP,LCP,2.54mm,999.9999u",Black,G | AMPHENOL SHANGHAI CORP. | G800MR302032EU | G | PWA BOM | In Old BOM |
|  |  |  | 3406AY600-971-G | Header&Socket Connector,C18358-1063N-L,Pin Header,6,SMD,LCP,2.54mm,999.9999u",Black,G | ALLTOP TECHNOLOGY CO.,LTD | C18358-1063N-L | G | PWA BOM | In Old BOM |
| 41 | J101 | 1 | 34062MW00-309-G | CONN,Header,WTB,2X5,V/T,Bla,1.27mm,10u,G,SMD-10 | SAMTEC INC. | FTSH-105-01-L-DV-K-P-TR | G | PWA BOM | In New BOM |
|  |  |  | 3406AR700-GRT-G | Header&Socket Connector,232-9B-05SBEC,Pin Header,10,SMD,NY6T,1.27mm,10u",Black,G | PINREX TECHNOLOGY CORP. | 232-9B-05SBEC | G | PWA BOM | In New BOM |
|  |  |  | 3406ATS00-637-G | CONN,Header,Pin Header,2X5,V/T,Bla,1.27mm,10u,G,SMD-10 | LONG SHOUNG CO.,LTD. | 11210B5805 | G | PWA BOM | In New BOM |
|  | J101 | 1 | 34062MW00-309-G | CONN,Header,WTB,2X5,V/T,Bla,1.27mm,10u,G,SMD-10 | SAMTEC INC. | FTSH-105-01-L-DV-K-P-TR | G | PWA BOM | In Old BOM |
|  |  |  | 3406AR700-GRT-G | Header&Socket Connector,232-9B-05SBEC,Pin Header,10,SMD,NY6T,1.27mm,10u",Black,G | PINREX TECHNOLOGY CORP. | 232-9B-05SBEC | G | PWA BOM | In Old BOM |
|  |  |  | 3406ATS00-637-G | CONN,Header,Pin Header,2X5,V/T,Bla,1.27mm,10u,G,SMD-10 | LONG SHOUNG CO.,LTD. | 11210B5805 | G | PWA BOM | In Old BOM |
|  |  |  | 3406AYJ00-600-G | Header&Socket Connector,HS64056-B100-9F,Pin Header,10,SMD,THERMOPLASTIC,1.27mm,10u",Black,G | FOXCONN TECHNOLOGY CO.,LTD. | HS64056-B100-9F | G | PWA BOM | In Old BOM |
| 42 | LAN1 | 1 | 34050PV00-48U-G | CONN,Modular Jack,RJ45X2,R/A,Bla,1.27mm,50u,G,DIP-28 | TRP CONNECTOR B.V. | 1840855-5 | G | PWA BOM | In New BOM |
|  |  |  | 34051E700-609-G | CONN,Modular Jack,RJ45X2,R/A,Bla,1.27mm,50u,G,DIP-28 | U.D. Electronic Corp. | MA-FN-0003 | G | PWA BOM | In New BOM |
|  | LAN1 | 1 | 34050PV00-48U-G | CONN,Modular Jack,RJ45X2,R/A,Bla,1.27mm,50u,G,DIP-28 | TRP CONNECTOR B.V. | 1840855-5 | G | PWA BOM | In Old BOM |
| 43 | PCB | 1 | 0101EW800-000-G | PCB,Zaius-MB DVT-X03,OSP,Blu,22L,22.20*13.00,G | PCB | 0101EW800-000-G | G | PWA BOM | In New BOM |
|  | PCB | 1 | PCB | PCB | PCB | PCB | G | PWA BOM | In Old BOM |
| 44 | PBER93,PAFR93,PAER93,PBFR94,PBER96,PAFR96,PAER96,PBFR97 | 8 | 610107A00-017-G | RES,0 Ohm,+/-5%,1/16W,G,SMD0402 | KOA SPEER ELECTRONICS, INC. | RK73Z1ETTP | G | PWA BOM | In New BOM |
|  |  |  | 610107A00-012-G | RES,0 Ohm,+/-5%,1/16W,G,SMD0402 | WALSIN | WR04X000PTL | G | PWA BOM | In New BOM |
|  |  |  | 610107A00-011-G | RES,0 Ohm,+/-5%,1/16W,G,SMD0402 | YAGEO | RC0402JR-070RL | G | PWA BOM | In New BOM |
|  |  |  | 610107A00-044-G | RES,0 Ohm,+/-5%,1/16W,G,SMD0402 | TA-I | RM04JTN0 | G | PWA BOM | In New BOM |
|  |  |  | 610107A00-024-G | RES,0 Ohm,+/-5%,1/16W,G,SMD0402 | PANASONIC INDUSTRIAL CO.,LTD. | ERJ2GE0R00X | G | PWA BOM | In New BOM |
|  |  |  | 610107A00-029-G | RES,0 Ohm,+/-5%,1/16W,G,SMD0402 | VISHAY ENTER TECHNO LOGY.INC | CRCW04020000Z0ED | G | PWA BOM | In New BOM |
|  | PBER93,PAFR93,PAER93,PBFR94,PBER96,PAFR96,PAER96,PBFR97 | 8 | 610113800-017-G | RES,10 Ohm,+/-1%,1/16W,G,SMD0402 | KOA SPEER ELECTRONICS, INC. | RK73H1ETTP10R0F | G | PWA BOM | In Old BOM |
|  |  |  | 610113800-012-G | RES,10 Ohm,+/-1%,1/16W,G,SMD0402 | WALSIN | WR04X10R0FTL | G | PWA BOM | In Old BOM |
|  |  |  | 610113800-011-G | RES,10 Ohm,+/-1%,1/16W,G,SMD0402 | YAGEO | RC0402FR-0710RL | G | PWA BOM | In Old BOM |
|  |  |  | 610113800-044-G | RES,10 Ohm,+/-1%,1/16W,G,SMD0402 | TA-I | RM04FTN10R0 | G | PWA BOM | In Old BOM |
| 45 | PBMR303,PBFR303,PBER303,PBAR303,PAMR303,PAFR303,PAER303,PAAR303 | 8 | 610107A00-017-G | RES,0 Ohm,+/-5%,1/16W,G,SMD0402 | KOA SPEER ELECTRONICS, INC. | RK73Z1ETTP | G | PWA BOM | In New BOM |
|  |  |  | 610107A00-012-G | RES,0 Ohm,+/-5%,1/16W,G,SMD0402 | WALSIN | WR04X000PTL | G | PWA BOM | In New BOM |
|  |  |  | 610107A00-011-G | RES,0 Ohm,+/-5%,1/16W,G,SMD0402 | YAGEO | RC0402JR-070RL | G | PWA BOM | In New BOM |
|  |  |  | 610107A00-044-G | RES,0 Ohm,+/-5%,1/16W,G,SMD0402 | TA-I | RM04JTN0 | G | PWA BOM | In New BOM |
|  |  |  | 610107A00-024-G | RES,0 Ohm,+/-5%,1/16W,G,SMD0402 | PANASONIC INDUSTRIAL CO.,LTD. | ERJ2GE0R00X | G | PWA BOM | In New BOM |
|  |  |  | 610107A00-029-G | RES,0 Ohm,+/-5%,1/16W,G,SMD0402 | VISHAY ENTER TECHNO LOGY.INC | CRCW04020000Z0ED | G | PWA BOM | In New BOM |
|  | PBMR303,PBFR303,PBER303,PBAR303,PAMR303,PAFR303,PAER303,PAAR303 | 8 | 61010L300-017-G | RES,1KOhm,+/-1%,1/16W,G,SMD0402 | KOA SPEER ELECTRONICS, INC. | RK73H1ETTP1001F | G | PWA BOM | In Old BOM |
|  |  |  | 61010L300-012-G | RES,1KOhm,+/-1%,1/16W,G,SMD0402 | WALSIN | WR04X1001FTL | G | PWA BOM | In Old BOM |
|  |  |  | 61010L300-011-G | RES,1KOhm,+/-1%,1/16W,G,SMD0402 | YAGEO | RC0402FR-071KL | G | PWA BOM | In Old BOM |
|  |  |  | 61010L300-044-G | RES,1KOhm,+/-1%,1/16W,G,SMD0402 | TA-I | RM04FTN1001 | G | PWA BOM | In Old BOM |
|  |  |  | 61010L300-024-G | RES,1KOhm,+/-1%,1/16W,G,SMD0402 | PANASONIC INDUSTRIAL CO.,LTD. | ERJ2RKF1001X | G | PWA BOM | In Old BOM |
|  |  |  | 61010L300-029-G | RES,1KOhm,+/-1%,1/16W,G,SMD0402 | VISHAY ENTER TECHNO LOGY.INC | CRCW04021K00FKED | G | PWA BOM | In Old BOM |
| 46 | R1281,R1283,R1285,R1289,R1290,R1291,R1292,R1293 | 8 | 610107A00-017-G | RES,0 Ohm,+/-5%,1/16W,G,SMD0402 | KOA SPEER ELECTRONICS, INC. | RK73Z1ETTP | G | PWA BOM | In New BOM |
|  |  |  | 610107A00-012-G | RES,0 Ohm,+/-5%,1/16W,G,SMD0402 | WALSIN | WR04X000PTL | G | PWA BOM | In New BOM |
|  |  |  | 610107A00-011-G | RES,0 Ohm,+/-5%,1/16W,G,SMD0402 | YAGEO | RC0402JR-070RL | G | PWA BOM | In New BOM |
|  |  |  | 610107A00-044-G | RES,0 Ohm,+/-5%,1/16W,G,SMD0402 | TA-I | RM04JTN0 | G | PWA BOM | In New BOM |
|  |  |  | 610107A00-024-G | RES,0 Ohm,+/-5%,1/16W,G,SMD0402 | PANASONIC INDUSTRIAL CO.,LTD. | ERJ2GE0R00X | G | PWA BOM | In New BOM |
|  |  |  | 610107A00-029-G | RES,0 Ohm,+/-5%,1/16W,G,SMD0402 | VISHAY ENTER TECHNO LOGY.INC | CRCW04020000Z0ED | G | PWA BOM | In New BOM |
|  | R1281,R1283,R1285,R1289,R1290,R1291,R1292,R1293 | 8 | 61011H500-017-G | RES,22 Ohm,+/-1%,1/16W,G,SMD0402 | KOA SPEER ELECTRONICS, INC. | RK73H1ETTP22R0F | G | PWA BOM | In Old BOM |
|  |  |  | 61011H500-012-G | RES,22 Ohm,+/-1%,1/16W,G,SMD0402 | WALSIN | WR04X22R0FTL | G | PWA BOM | In Old BOM |
|  |  |  | 61011H500-011-G | RES,22 Ohm,+/-1%,1/16W,G,SMD0402 | YAGEO | RC0402FR-0722RL | G | PWA BOM | In Old BOM |
|  |  |  | 61011H500-044-G | RES,22 Ohm,+/-1%,1/16W,G,SMD0402 | TA-I | RM04FTN22R0 | G | PWA BOM | In Old BOM |
|  |  |  | 61011H500-024-G | RES,22 Ohm,+/-1%,1/16W,G,SMD0402 | PANASONIC INDUSTRIAL CO.,LTD. | ERJ2RKF22R0X | G | PWA BOM | In Old BOM |
| 47 | PBFR518,PBER518,PAFR518,PBFR519,PBER519,PAFR519,PAER519,PAER520 | 8 | 610113800-017-G | RES,10 Ohm,+/-1%,1/16W,G,SMD0402 | KOA SPEER ELECTRONICS, INC. | RK73H1ETTP10R0F | G | PWA BOM | In New BOM |
|  |  |  | 610113800-012-G | RES,10 Ohm,+/-1%,1/16W,G,SMD0402 | WALSIN | WR04X10R0FTL | G | PWA BOM | In New BOM |
|  |  |  | 610113800-011-G | RES,10 Ohm,+/-1%,1/16W,G,SMD0402 | YAGEO | RC0402FR-0710RL | G | PWA BOM | In New BOM |
|  |  |  | 610113800-044-G | RES,10 Ohm,+/-1%,1/16W,G,SMD0402 | TA-I | RM04FTN10R0 | G | PWA BOM | In New BOM |
|  | PBFR518,PBER518,PAFR518,PBFR519,PBER519,PAFR519,PAER519,PAER520 | 8 | 610107A00-017-G | RES,0 Ohm,+/-5%,1/16W,G,SMD0402 | KOA SPEER ELECTRONICS, INC. | RK73Z1ETTP | G | PWA BOM | In Old BOM |
|  |  |  | 610107A00-012-G | RES,0 Ohm,+/-5%,1/16W,G,SMD0402 | WALSIN | WR04X000PTL | G | PWA BOM | In Old BOM |
|  |  |  | 610107A00-011-G | RES,0 Ohm,+/-5%,1/16W,G,SMD0402 | YAGEO | RC0402JR-070RL | G | PWA BOM | In Old BOM |
|  |  |  | 610107A00-044-G | RES,0 Ohm,+/-5%,1/16W,G,SMD0402 | TA-I | RM04JTN0 | G | PWA BOM | In Old BOM |
|  |  |  | 610107A00-024-G | RES,0 Ohm,+/-5%,1/16W,G,SMD0402 | PANASONIC INDUSTRIAL CO.,LTD. | ERJ2GE0R00X | G | PWA BOM | In Old BOM |
|  |  |  | 610107A00-029-G | RES,0 Ohm,+/-5%,1/16W,G,SMD0402 | VISHAY ENTER TECHNO LOGY.INC | CRCW04020000Z0ED | G | PWA BOM | In Old BOM |
| 48 | PBFR34,PBER34,PAFR34,PAER34 | 4 | 61100YT00-017-G | RES,487 Ohm,+/-0.1%,1/16W,G,SMD0402 | KOA SPEER ELECTRONICS, INC. | RN731ETTP4870B25 | G | PWA BOM | In New BOM |
|  | PBFR34,PBER34,PAFR34,PAER34 | 4 | 610118N00-017-G | RES,487 Ohm,+/-1%,1/16W,G,SMD0402 | KOA SPEER ELECTRONICS, INC. | RK73H1ETTP4870F | G | PWA BOM | In Old BOM |
| 49 | PBMR34,PAMR34 | 2 | 61100RF00-017-G | RES,402 Ohm,+/-0.1%,1/16W,G,SMD0402 | KOA SPEER ELECTRONICS, INC. | RN731ETTP4020B25 | G | PWA BOM | In New BOM |
|  | PBMR34,PAMR34 | 2 | 61011J902-017-G | RES,402 Ohm,+/-1%,1/16W,G,SMD0402 | KOA SPEER ELECTRONICS, INC. | RK73H1ETTP4020F | G | PWA BOM | In Old BOM |
| 50 | PSUR1 | 1 | 610119C00-017-G | RES,130KOhm,+/-1%,1/16W,G,SMD0402 | KOA SPEER ELECTRONICS, INC. | RK73H1ETTP1303F | G | PWA BOM | In New BOM |
|  |  |  | 610119C00-011-G | RES,130KOhm,+/-1%,1/16W,G,SMD0402 | YAGEO CORPORATION COMPONENT | RC0402FR-07130KL | G | PWA BOM | In New BOM |
|  |  |  | 610119C00-012-G | RES,130KOhm,+/-1%,1/16W,G,SMD0402 | WALSIN TECHNOLOGY CORPORATION | WR04X1303FTL | G | PWA BOM | In New BOM |
|  |  |  | 610119C00-044-G | RES,130KOhm,+/-1%,1/16W,G,SMD0402 | TA-I TECHNOLOGY CO., LTD | RM04FTN1303 | G | PWA BOM | In New BOM |
|  | PSUR1 | 1 | 610115R00-017-G | RES,15KOhm,+/-1%,1/16W,G,SMD0402 | KOA SPEER ELECTRONICS, INC. | RK73H1ETTP1502F | G | PWA BOM | In Old BOM |
|  |  |  | 610115R00-012-G | RES,15KOhm,+/-1%,1/16W,G,SMD0402 | WALSIN | WR04X1502FTL | G | PWA BOM | In Old BOM |
|  |  |  | 610115R00-011-G | RES,15KOhm,+/-1%,1/16W,G,SMD0402 | YAGEO | RC0402FR-0715KL | G | PWA BOM | In Old BOM |
|  |  |  | 610115R00-044-G | RES,15KOhm,+/-1%,1/16W,G,SMD0402 | TA-I | RM04FTN1502 | G | PWA BOM | In Old BOM |
|  |  |  | 610115R00-024-G | RES,15KOhm,+/-1%,1/16W,G,SMD0402 | PANASONIC INDUSTRIAL CO.,LTD. | ERJ2RKF1502X | G | PWA BOM | In Old BOM |
|  |  |  | 610115R00-029-G | RES,15KOhm,+/-1%,1/16W,G,SMD040 | VISHAY ENTER TECHNO LOGY.INC | CRCW040215K0FKED | G | PWA BOM | In Old BOM |
| 51 | R1307,R1314,R1315,R1316,R1317,R1318,R1319,R1320 | 8 | 61011H500-017-G | RES,22 Ohm,+/-1%,1/16W,G,SMD0402 | KOA SPEER ELECTRONICS, INC. | RK73H1ETTP22R0F | G | PWA BOM | In New BOM |
|  |  |  | 61011H500-012-G | RES,22 Ohm,+/-1%,1/16W,G,SMD0402 | WALSIN | WR04X22R0FTL | G | PWA BOM | In New BOM |
|  |  |  | 61011H500-011-G | RES,22 Ohm,+/-1%,1/16W,G,SMD0402 | YAGEO | RC0402FR-0722RL | G | PWA BOM | In New BOM |
|  |  |  | 61011H500-044-G | RES,22 Ohm,+/-1%,1/16W,G,SMD0402 | TA-I | RM04FTN22R0 | G | PWA BOM | In New BOM |
|  |  |  | 61011H500-024-G | RES,22 Ohm,+/-1%,1/16W,G,SMD0402 | PANASONIC INDUSTRIAL CO.,LTD. | ERJ2RKF22R0X | G | PWA BOM | In New BOM |
|  | R1307,R1314,R1315,R1316,R1317,R1318,R1319,R1320 | 8 | 610107A00-017-G | RES,0 Ohm,+/-5%,1/16W,G,SMD0402 | KOA SPEER ELECTRONICS, INC. | RK73Z1ETTP | G | PWA BOM | In Old BOM |
|  |  |  | 610107A00-012-G | RES,0 Ohm,+/-5%,1/16W,G,SMD0402 | WALSIN | WR04X000PTL | G | PWA BOM | In Old BOM |
|  |  |  | 610107A00-011-G | RES,0 Ohm,+/-5%,1/16W,G,SMD0402 | YAGEO | RC0402JR-070RL | G | PWA BOM | In Old BOM |
|  |  |  | 610107A00-044-G | RES,0 Ohm,+/-5%,1/16W,G,SMD0402 | TA-I | RM04JTN0 | G | PWA BOM | In Old BOM |
|  |  |  | 610107A00-024-G | RES,0 Ohm,+/-5%,1/16W,G,SMD0402 | PANASONIC INDUSTRIAL CO.,LTD. | ERJ2GE0R00X | G | PWA BOM | In Old BOM |
|  |  |  | 610107A00-029-G | RES,0 Ohm,+/-5%,1/16W,G,SMD0402 | VISHAY ENTER TECHNO LOGY.INC | CRCW04020000Z0ED | G | PWA BOM | In Old BOM |
| 52 | U62 | 1 | 21050R500-298-G | IC,SILABS,Si5338C-B06799-GMR,G,QFN-24,SMD | Silicon Laboratories Inc. | SI5338C-B06799-GMR | G | PWA BOM | In New BOM |
|  | U62 | 1 | 21050R500-298-G | IC,SILABS,Si5338C-B06429-GMR,G,QFN-24,SMD | Silicon Laboratories Inc. | SI5338C-B06799-GMR | G | PWA BOM | In Old BOM |
| 53 | J10 | 1 | 3406B5J00-317-G | CONN,Header,Socket,V/T,Bla,2mm,15u,G,DIP-18 | MOLEX INCORPORATED | 79107-7008 | G | PWA BOM | In New BOM |
|  | J10 | 1 | 79107-7008 | CONN,Header,Socket,2X9,V/T,Bla,2mm,15u,G,DIP-18 | MOLEX INCORPORATED | 79107-7008 | G | PWA BOM | In Old BOM |
| 54 | J13 | 1 | 34064J800-317-G | CONN,Header,Socket,2X2,V/T,Bla,2mm,15u,G,DIP-4 | MOLEX INCORPORATED | 79107-7001 | G | PWA BOM | In New BOM |
|  | J13 | 1 | 79107-7001 | CONN,Header,Socket,2X2,V/T,Bla,2mm,15u,G,DIP-4 | MOLEX INCORPORATED | 79107-7001 | G | PWA BOM | In Old BOM |
| 55 | PBAR65,PAAR65 | 2 | TLRH3APTTE20L0F | RES,20mOhm,+/-1%,2W,G,SMD2512 | KOA SPEER ELECTRONICS, INC. | TLRH3APTTE20L0F | G | PWA BOM | In New BOM |
|  | PBAR65,PAAR65 | 2 | 61012WF00-017-G | RES,20mOhm,+/-1%,1W,G,SMD2512 | KOA SPEER ELECTRONICS, INC. | UR73D3ATTE20L0F | G | PWA BOM | In Old BOM |
| 56 | PBER65,PAFR65,PAER65,PBFR66 | 4 | SLW1TTE50L0F | RES,50mOhm,+/-1%,1.5W,G,SMD2512 | KOA | SLW1TTE50L0F | G | PWA BOM | In New BOM |
|  | PBER65,PAFR65,PAER65,PBFR66 | 4 | 610605200-034-G | RES,50mOhm,+/-1%,3W,G,SMD2512 | CYNTEC CO. LTD | RL-3264-0W-R050-FNH | G | PWA BOM | In Old BOM |
| 57 | PBMR65,PAMR65 | 2 | SLW1TTE75L0F | RES,75mOhm,+/-1%,1.5W,G,SMD2512 | KOA | SLW1TTE75L0F | G | PWA BOM | In New BOM |
|  | PBMR65,PAMR65 | 2 | TLRH3APTTE60L0F | RES,60mOhm,+/-0.5%,2W,G,SMD2512 | KOA SPEER ELECTRONICS, INC. | TLRH3APTTE60L0F | G | PWA BOM | In Old BOM |
| ##### Change Revision |  |  |  |  |  |  |  |  |  |
| Sheet | REV OF BOM | CUSTOMER | CUSTOMER P/N | PWA PN | PWA DESCRIPTION | PWA REV | DATE | Remark |  |
| OOOOOOOOOOOOOOOOOOOOOOOOOOOOOOOOOOOOOOOOOOOOOOOOOOOOOOOOOOOOOOOOOOOOOOOOOOOOOOOOOOOOOOOOOO | OOOOOOOOOOOOOOOOOOOOOOOOOOOOOOOOOOOOOOOOOOOOOOOOOOOOOOOOOOOOOOOOOOOOOOOOOOOOOOOOOOOOOOOOOO | OOOOOOOOOOOOOOOOOOOOOOOOOOOOOOOOOOOOOOOOOOOOOOOOOOOOOOOOOOOOOOOOOOOOOOOOOOOOOOOOOOOOOOOOOO | OOOOOOOOOOOOOOOOOOOOOOOOOOOOOOOOOOOOOOOOOOOOOOOOOOOOOOOOOOOOOOOOOOOOOOOOOOOOOOOOOOOOOOOOOO | OOOOOOOOOOOOOOOOOOOOOOOOOOOOOOOOOOOOOOOOOOOOOOOOOOOOOOOOOOOOOOOOOOOOOOOOOOOOOOOOOOOOOOOOOO | OOOOOOOOOOOOOOOOOOOOOOOOOOOOOOOOOOOOOOOOOOOOOOOOOOOOOOOOOOOOOOOOOOOOOOOOOOOOOOOOOOOOOOOOOO | OOOOOOOOOOOOOOOOOOOOOOOOOOOOOOOOOOOOOOOOOOOOOOOOOOOOOOOOOOOOOOOOOOOOOOOOOOOOOOOOOOOOOOOOOO | OOOOOOOOOOOOOOOOOOOOOOOOOOOOOOOOOOOOOOOOOOOOOOOOOOOOOOOOOOOOOOOOOOOOOOOOOOOOOOOOOOOOOOOOOO | OOOOOOOOOOOOOOOOOOOOOOOOOOOOOOOOOOOOOOOOOOOOOOOOOOOOOOOOOOOOOOOOOOOOOOOOOOOOOOOOOOOOOOOOOO | OOOOOOOOOOOOOOOOOOOOOOOOOOOOOOOOOOOOOOOOOOOOOOOOOOOOOOOOOOOOOOOOOOOOOOOOOOOOOOOOOOOOOOOOOO |
| Second Source Change |  |  |  |  |  |  |  |  |  |
| Item | Location | Change Type | Foxconn P/N | Part Description | Manufacturer Full Name | Manufacturer P/N | RoHS | Sheet |  |
| 1 | PHAD6,D20,D21 |  | 520100200-237-G | DIODE,Switching,1N4148W-7-F,100V,0.15A,G,SOD123-2,SMD | DIODES INEORPORATION | 1N4148W-7-F | G | PWA BOM |  |
|  |  | ADD | 520102P00-031-G | DIODE,Switching,BAS16H,100V,0.5A,G,SOD123F-2,SMD | NXP SEMICONDUCTORS | BAS16H | G | PWA BOM |  |
| 2 | D33 |  | 520308D00-237-G | DIODE,Schottky Rectifier,1N5819HW-7-F,40V,1A,G,SOD123-2,SMD | DIODES INCORPORATION | 1N5819HW-7-F | G | PWA BOM |  |
|  |  | ADD | 520318S00-223-G | Diode,Schottky,MBR140SFT3G,40V,1A,G,SOD-123FL-2,SMD | ON SEMICONDUCTOR CORP | MBR140SFT3G | G | PWA BOM |  |
|  |  | NO | 52030P100-223-G | Diode,Schottky,MBR140SFT1G,40V,1A,SOD-123FL,2P,G | ON | MBR140SFT1G | G | PWA BOM |  |
|  |  | Delete | MBR140SFT3G | DIODE,MBR140SFT3G | ON SEMICONDUCTOR CORP | MBR140SFT3G | G | PWA BOM |  |
| 3 | ED1,ED2,ED3 |  | 521800900-227-G | DIODE,Array-TVS,SRV05-4.TCT,5V,12A,G,SOT23-6,SMD | SEMTECH CORPORATION. | SRV05-4.TCT | G | PWA BOM |  |
|  |  | NO | 52180H500-086-G | Diode,Array-TVS,SRV05-04HTG,SOT-23,6P,G | LITTELFUSE FAR EAST PTE LTD | SRV05-04HTG | G | PWA BOM |  |
|  |  | Delete | 52180C400-237-G | Diode,Array-TVS,DRTR5V0U4TS-7,TSOT,6P,G | DIODES INCORPORATION | DRTR5V0U4TS-7 | G | PWA BOM |  |
| 4 | FL1,FL4,FL10 |  | 720406E00-015-G | Common Choke,90Ohm@100MHz,+/-25%,220mA,G,SMD0805 | MURATA ELEC. NORTH AMERICA | DLW21HN900HQ2L | G | PWA BOM |  |
|  |  | NO | 720405D00-016-G | Common Choke,90 Ohm@100MHz,Type,200mA,G,SMD0805 | TDK | ACM2012E-900-2P-T01 | G | PWA BOM |  |
|  |  | ADD | 720402300-129-G | Filter,Inductor type,Common Mode(CMODE),90Ohm@100MHz,Type,300mA,,SMD0805,G | MagLayers | MCI-2012H-900 | G | PWA BOM |  |
| 5 | FL2,FL3,FL5,FL6,FL7,FL8,FL9 |  | 720400201-015-G | Filter,Common Mode,90Ohm@100MHz,+/-25%,330mA,G,SMD0805 | MURATA ELEC. NORTH AMERICA | DLW21HN900SQ2L | G | PWA BOM |  |
|  |  | NO | 720400M00-059-G | Common Choke,90 Ohm@100MHz,+/-25%,400mA,G,SMD0805 | TAI-TECH ADVANCED ELECTRONICS CO., LTD. | WCM2012F2SF-900T04 | G | PWA BOM |  |
|  |  | NO | 720400800-016-G | Common Choke,90 Ohm@100MHz,+/-25%,400mA,190mOhm,2L,G,SMD0805 | TDK | ACM2012-900-2P-T | G | PWA BOM |  |
|  |  | ADD | 720400200-129-G | Common Choke,90 Ohm@100MHz,+/-25%,400mA,190mOhm,2L,G,SMD0805 | Maglayers | MCI-2012-900 | G | PWA BOM |  |
| 6 | FS2,FS3 |  | 730100400-086-G | Fuse,Very fast acting,3A,32V,G,SMD0603 | LITTELFUSE FAR EAST PTE LTD | 0467003.NR | G | PWA BOM |  |
|  |  | Delete | 730103Q00-088-G | Fuse,Fast acting,32V,3A,SMD0603,G | COOPER BUSSMANN, INC. | CC06H3A-TR | G | PWA BOM |  |
| 7 | FS4,FS9,FS12,FS15,FS16,FS21 |  | 730102701-086-G | Fuse,Fast acting,32V,7A,G,SMD1206 | LITTELFUSE FAR EAST PTE LTD | 0440007.WR | G | PWA BOM |  |
|  |  | ADD | 730102704-088-G | Fuse,Fast acting,32V,7A,SMD1206,G | Cooper Bussmann | CC12H7A-TR | G | PWA BOM |  |
|  |  | Delete | CC12H7A-TR | Fuse,CC12H7A-TR | Cooper Bussmann | CC12H7A-TR | G | PWA BOM |  |
| 8 | FS5,FS8,FS11,FS14,FS17,FS19,FS20 |  | 730103M00-086-G | Fuse,Fast acting,32V,5A,G,SMD0603 | LITTELFUSE FAR EAST PTE LTD | 0438005.WR | G | PWA BOM |  |
|  |  | NO | 730103M00-088-G | Fuse,Fast acting,32V,5A,SMD0603,G | COOPER BUSSMANN, INC. | CC06H5A-TR | G | PWA BOM |  |
|  |  | Delete | 730100H00-085-G | Fuse,Very fast acting,32V,5A,G,SMD0603 | BEL FUSE INC | C2Q 5TR | G | PWA BOM |  |
| 9 | FS6,FS7,FS10,FS13,FS18 |  | 730102B01-086-G | Fuse,Fast acting,32V,1A,G,SMD0603 | LITTELFUSE FAR EAST PTE LTD | 0438001.WR | G | PWA BOM |  |
|  |  | NO | 730102B03-088-G | Fuse,Fast acting,32V,1A,SMD0603,G | COOPER BUSSMANN, INC. | CC06H1A-TR | G | PWA BOM |  |
|  |  | Delete | 730100C00-085-G | Fuse,Very fast acting,32V,1A,G,SMD0603 | BEL FUSE INC | C2Q 1TR | G | PWA BOM |  |
|  |  | Delete | 730102B00-101-G | Fuse,Fast acting,32V,1A,G,SMD0603 | BOURNS INC | SF-0603F100-2 | G | PWA BOM |  |
| 10 | FS22 |  | 730102000-086-G | Fuse,Fast acting,24V,10A,G,SMD1206 | LITTELFUSE FAR EAST PTE LTD | 0501010.WR | G | PWA BOM |  |
|  |  | Delete | 730104D00-57M-G | Fuse,Fast acting,32V,10A,G,SMD1206 | COOPER BUSSMANN, INC. | CC12H10A-TR | G | PWA BOM |  |
| 11 | LED1 |  | 52112H800-289-G | LED,Blu,LTST-C193TBKT-LO,5V,20mA,G,SMD | LITE-ON TECHNOLOGY CORPORATION | LTST-C193TBKT-LO | G | PWA BOM |  |
|  |  | NO | 52112H900-354-G | LED LAMP,LG-192DBK-CT/T-SD,Blue,24mcd@IF=5mA,475nm,999.9999V,20mA,N/A,,SMD0603,2P,G | Ligitek Electronics Co., Ltd. | LG-192DBK-CT/T-SD | G | PWA BOM |  |
|  |  | Delete | 52113GN00-290-G | LED LAMP,B1931NB--20D-000114,Blue,112.5mcd@IF=20mA,470nm,5V,20mA,N/A,,SMD0603,2P,G | HARVATEK | B1931NB--20D-000114 | G | PWA BOM |  |
|  |  | Delete | SML-LX0603USBWATR | LED,SML-LX0603USBWATR | LUMEX | SML-LX0603USBWATR | G | PWA BOM |  |
| 12 | LED8,LED9 |  | 52113AY00-289-G | LED,Red,LTL-42NEW8DH184P,5V,20mA,G,DIP-2 | LITE-ON TECHNOLOGY CORPORATION | LTL-42NEW8DH184P | G | PWA BOM |  |
|  |  | Delete | 52113GL00-354-G | LED LAMP,LA140B-1/H-PF,Red,4.2mcd@IF=10mA,697nm,5V,20mA,N/A,,DIP,2P,G | Ligitek Electronics Co., Ltd. | LA140B-1/H-PF | G | PWA BOM |  |
|  |  | Delete | L-7104ADFX013-TW | LED,L-7104ADFX013-TW | Kingbright | L-7104ADFX013-TW | G | PWA BOM |  |
| 13 | LED10,LED14 |  | 52113B000-289-G | LED,Yellow,LTL-42NSV8DH184P,5V,20mA,G,DIP-2 | LITE-ON TECHNOLOGY CORPORATION | LTL-42NSV8DH184P | G | PWA BOM |  |
|  |  | NO | L-7104ADFX012-TW | LED,L-7104ADFX012-TW | Kingbright | L-7104ADFX012-TW | G | PWA BOM |  |
|  |  | Delete | 52113GK00-354-G | LED LAMP,LA140B-1/Y-PF,Yellow,12mcd@IF=10mA,585nm,5V,20mA,N/A,,DIP,2P,G | Ligitek Electronics Co., Ltd. | LA140B-1/Y-PF | G | PWA BOM |  |
| 14 | LED11,LED12 |  | 52113AW00-289-G | LED,Green,LTL-42NGY8DH184P,5V,20mA,G,DIP-2 | LITE-ON TECHNOLOGY CORPORATION | LTL-42NGY8DH184P | G | PWA BOM |  |
|  |  | ADD | SSF-LXH303SUGD | LED,Green,LTL-42NGY8DH184P,5V,20mA,G,DIP-2 | Lumex | SSF-LXH303SUGD | G | PWA BOM |  |
|  |  | Delete | L-7104ADFX011-TW | LED,L-7104ADFX011-TW | Kingbright | L-7104ADFX011-TW | G | PWA BOM |  |
| 15 | LED63,LED64,LED65 |  | 52110FE00-289-G | LED,Red,LTST-C190KRKT,2.4V,30mA,G,SMD0603 | LITE-ON TECHNOLOGY CORPORATION | LTST-C190KRKT | G | PWA BOM |  |
|  |  | Delete | 52113GH00-290-G | LED LAMP,B1911UR--20D-001054,Red,18mcd@IF=20mA,643nm,5V,20mA,N/A,,SMD0603,2P,G | HARVATEK | B1911UR--20D-001054 | G | PWA BOM |  |
| 16 | L7 |  | 630332000-053-G | IND,3.3uH@100KHz,+/-20%,2.57A,26mOhm,SHLD,G,SMD | TOKO INC. | #A916CY-3R3M=P3 | G | PWA BOM |  |
|  |  | ADD | 63035BF00-129-G | IND,3.3uH@100KHz,+/-20%,2.57A,26mOhm,SHLD,G,SMD | MAG.LAYERS, SCIENTIFIC-TECHNICS (KUNSHAN) CO., LTD. | MSCDRI-6035LC-3R3M-EH | G | PWA BOM |  |
| 17 | L22,L23,L24,L25 |  | 720105P00-016-G | FB,80 Ohm@100MHz,+/-25%,500mA,150mOhm,G,SMD0603 | TDK ELECTRONICS EUROPE GMBH | MMZ1608S800AT | G | PWA BOM |  |
|  |  | NO | GMLB-160808-0080P-N8 | FB,80 Ohm@100MHz,+/-25%,500mA,150mOhm,G,SMD0603 | MAG.LAYERS, SCIENTIFIC-TECHNICS (KUNSHAN) CO., LTD. | GMLB-160808-0080P-N8 | G | PWA BOM |  |
|  |  | Delete | 720107P00-015-G | FB,Multilayer,150mOhm,70Ohm@100MHz,+/-25%,500mA,,SMD0402,G | MURATA ELEC. NORTH AMERICA | BLM15AG700SN1D | G | PWA BOM |  |
| 18 | L34,L36 |  | 72010A400-023-G | FB,80Ohm@100MHz,+/-25%,4A,10mOhm,G,SMD1206 | TAIYO ELECTRIC IND.CO.LTD | FBMJ3216HS800-T | G | PWA BOM |  |
|  |  | ADD | Z1206C800APWST | FB,80Ohm@100MHz,+/-25%,4A,10mOhm,G,SMD1206 | KEMET | Z1206C800APWST | G | PWA BOM |  |
| 19 | L45 |  | 720101M00-015-G | FB,600 Ohm@100MHz,+/-25%,200mA,650mOhm,G,SMD0603 | MURATA ELEC. NORTH AMERICA | BLM18BD601SN1D | G | PWA BOM |  |
|  |  | NO | 720103000-023-G | FB,600 Ohm@100MHz,+/-25%,250mA,600mOhm,G,SMD0603 | TAIYO ELECTRIC IND.CO.LTD | BK1608HM601-T | G | PWA BOM |  |
|  |  | Delete | 720101L00-059-G | FB,600 Ohm@100MHz,+/-25%,200mA,Multilayer,500mOhm,SMD0603,G | TAI-TECH ADVANCED ELECTRONICS CO., LTD. | FCM1608KF-601T02 | G | PWA BOM |  |
| 20 | PBMC7,PBFC7,PBEC7,PBAC7,PAMC7,PAFC7,PAEC7,PAAC7 |  | 620102T00-015-G | CAP,150pF,+/-5%,NPO(C0G),50V,G,SMD0402 | MURATA ELEC. NORTH AMERICA | GRM1555C1H151J | G | PWA BOM |  |
|  |  | ADD | 620102T00-012-G | CAP,150pF,+/-5%,NPO(C0G),50V,G,SMD0402 | WALSIN TECHNOLOGY CORPORATION | 0402N151J500LT | G | PWA BOM |  |
|  |  | ADD | 620102T00-026-G | CAP,150pF,+/-5%,NPO(C0G),50V,G,SMD0402 | SAMSUNG SEMICONDUCTOR | CL05C151JB5NNNC | G | PWA BOM |  |
|  |  | ADD | 620102T00-023-G | CAP,150pF,+/-5%,NPO(C0G),50V,G,SMD0402 | TAIYO ELECTRIC IND.CO.LTD | UMK105CG151JV-F | G | PWA BOM |  |
| 21 | PBMD1,PBFD1,PBED1,PBAD1,PAMD1,PAFD1,PAED1,PAAD1 |  | 520103B00-185-G | Diode,Rectifier&Switching,MMBD1205,100V,200mA,G,SOT-23-3,SMD | FAIRCHILD SEMICONDUCTOR CORP | MMBD1205 | G | PWA BOM |  |
|  |  | ADD | BAW156HM | Diode,Rectifier&Switching,100V,200mA,G,SOT-23-3,SMD | ROHM | BAW156HM | G | PWA BOM |  |
|  |  | ADD | 52010AP00-280-G | Diode,Rectifier&Switching,MMBD3004A,240V,225mA,SOT-23,3P,G | DIODES INC | MMBD3004A | G | PWA BOM |  |
| 22 | PBMC4,PAMC4 |  | 62010BH00-015-G | CAP,220pF,+/-5%,NPO(C0G),50V,G,SMD0402 | MURATA ELEC. NORTH AMERICA | GRM1555C1H221J | G | PWA BOM |  |
|  |  | ADD | 62010BH02-012-G | CAP,220pF,+/-5%,NPO(C0G),50V,G,SMD0402 | WALSIN TECHNOLOGY CORPORATION | 0402N221J500CT | G | PWA BOM |  |
|  |  | ADD | 62010BH00-011-G | CAP,220pF,+/-5%,NPO(C0G),50V,G,SMD0402 | YAGEO CORPORATION COMPONENT | CC0402JRNPO9BN221 | G | PWA BOM |  |
|  |  | ADD | 62010BH00-026-G | CAP,220pF,+/-5%,NPO(C0G),50V,G,SMD0402 | SAMSUNG SEMICONDUCTOR | CL05C221JB5NNNC | G | PWA BOM |  |
|  |  | ADD | 62010BH03-023-G | CAP,220pF,+/-5%,NPO(C0G),50V,G,SMD0402 | TAIYO ELECTRIC IND.CO.LTD | UMK105CG221JV-F | G | PWA BOM |  |
| 23 | PHAQ4 |  | 51020A000-031-G | TRANS P,PBHV9115T,150V,1A,G,SOT23-3,SMD | NXP SEMICONDUCTORS | PBHV9115T | G | PWA BOM |  |
|  |  | NO | 51020AF00-280-G | Trans PNP,MMBT5401,-150V,-500mA,SOT-23,3P,G | Fairchild | MMBT5401 | G | PWA BOM |  |
|  |  | ADD | MMBT5401 | TRANS,150V,1A,G,SOT23-3,SMD | DIODES | MMBT5401 | G | PWA BOM |  |
| 24 | PHAQ5,PHAQ6 |  | 51032D100-237-G | MOS N,DMN10H220L-7,100V,1.6A,220m@10V,G,SOT-23-3,SMD | DIODES INCORPORATION | DMN10H220L-7 | G | PWA BOM |  |
|  |  | ADD | FQT7N10LTF | MOS N,FQT7N10LTF | Fairchild | FQT7N10LTF | G | PWA BOM |  |
|  |  | Delete | FQT7N10L | MOS N,FQT7N10L | Fairchild | FQT7N10L | G | PWA BOM |  |
| 25 | PSRL2 |  | 63034GW00-088-G | IND,680nH@100KHz,+/-20%,34A,1.33mOhm,SHLD,G,SMD | COOPER BUSSMANN, INC. | HCM1305-R68-R | G | PWA BOM |  |
|  |  | ADD | CMLB135T-R68MS | IND,680nH@100KHz,+/-20%,34A,1.33mOhm,SHLD,G,SMD | CYNTEC | CMLB135T-R68MS | G | PWA BOM |  |
| 26 | PSUU1 |  | 880302300-065-G | Converter,input 40V~60V,600W,G,Q54SJ12050NNDH,OVAL | DELTA ELECTRONICS INDUSTRIAL CO.,LTD | Q54SH12050NNDH | G | PWA BOM |  |
|  |  | ADD | 880302100-065-G | Converter,input 40V~60V,600W,G,Q54SH12050NNDH | DELTA ELECTRONICS INDUSTRIAL CO.,LTD | Q54SH12050NNDH | G | PWA BOM |  |
| 27 | QN2,QN3 |  | 510503B00-223-G | MOS N/N,NTZD3154NT1G,20V,0.54A,550m24.5V,G,SOT563-6,SMD | ON SEMICONDUCTOR CORP | NTZD3154NT1G | G | PWA BOM |  |
|  |  | NO | Si1034CX-T1-GE3 | MOS N/N,Si1034CX-T1-GE3 | Vishay | Si1034CX-T1-GE3 | G | PWA BOM |  |
|  |  | NO | SSM6N36FE | MOS N/N,SSM6N36FE | Toshiba | SSM6N36FE | G | PWA BOM |  |
|  |  | Delete | 51050AK00-030-G | MOS N/N,EM6K6T2R,20V,0.3A,1ohm@4V,G,EMT-6,SMD | ROHM CORPORATION | EM6K6T2R | G | PWA BOM |  |
| 28 | Q12 |  | 510501900-237-G | MOS N/N,2N7002DW-7-F,60V,0.115A,7.5ohm@5V,G,SOT363-6,SMD | DIODES INEORPORATION | 2N7002DW-7-F | G | PWA BOM |  |
|  |  | ADD | 51050HS00-237-G | MOS N/N,60V,0.115A,7.5ohm@5V,G,SOT363-6,SMD | DIODES | DMN65D8LDW-7 | G | PWA BOM |  |
|  |  | ADD | SSM6N7002KFU | MOS N/N,SSM6N7002KFU,60V,200mA,3.3Ohm@4.5V,G,SC88-6,SMD | TOSHIBA ELECTRONICS ASIA LTD | SSM6N7002KFU | G | PWA BOM |  |
|  |  | NO | 510507800-131-G | MOS N/N,SSM6N7002BFU,60V,200mA,3.3Ohm@4.5V,G,SC88-6,SMD | TOSHIBA ELECTRONICS ASIA LTD | SSM6N7002BFU | G | PWA BOM |  |
| 29 | U29 |  | 21050F900-217-G | IC,IDT,2305B-1DCG8,B,G,SOIC-8,SMD | INTEGRATED DEVICE TECHNOLOGY | 2305B-1DCG8 | G | PWA BOM |  |
|  |  | NO | 31050JC00-223-G | Logic IC,Buffer,NB2305AI1DR2G,3.0V~3.6V,0.35ns,SOIC,8P,G | ON SEMICONDUCTOR CORP | NB2305AI1DR2G | G | PWA BOM |  |
|  |  | ADD | SL2305SC-1 | IC,IDT,2305B-1DCG8,B,G,SOIC-8,SMD | Silicon Labs | SL2305SC-1 | G | PWA BOM |  |
| 30 | U109 |  | 310307T00-031-G | IC,Switch,74CBTLV1G125GV,2.3~3.6V,G,SOT753-5,SMD | NXP SEMICONDUCTORS | 74CBTLV1G125GV | G | PWA BOM |  |
|  |  | ADD | 310300D00-183-G | IC,Switch,SN74CBTLV1G125DBVR,2.3~3.6V,G,SOT23-5,SMD | TEXAS INSTRUMENTS | SN74CBTLV1G125DBVR | G | PWA BOM |  |
|  |  | Delete | SN74CBTLV1G125DBVR | IC,Switch,SN74CBTLV1G125DBVR,2.3~3.6V,G,SOT23-5,SMD | TI | SN74CBTLV1G125DBVR | G | PWA BOM |  |
| 31 | U110 |  | 330103N00-426-G | IC,Optocoupler,PS2811-1-F3-A,G,SSOP-4,SMD | RENESAS TECHNOLOGY AMERICA INC | PS2811-1-F3-A | G | PWA BOM |  |
|  |  | NO | 330102900-289-G | OPTO-IC,ISOL,LTV-217-G,SSOP,4P,G | LITE-ON TECHNOLOGY CORPORATION | LTV-217-G | G | PWA BOM |  |
|  |  | NO | VOS618A-3T | OPTO-IC,VOS618A-3T | VISHAY ENTER TECHNO LOGY.INC | VOS618A-3T | G | PWA BOM |  |
|  |  | Delete | 330103L00-131-G | OPTO-IC,ISOL,TLP291,SO,4P,G | TOSHIBA ELECTRONICS ASIA LTD | TLP291 | G | PWA BOM |  |
| 32 | U167,U173 |  | 310203U00-223-G | IC,Trigger,NL17SZ14DFT2G,1.65~5.5V,G,SOT353-5,SMD | ON SEMICONDUCTOR CORP | NL17SZ14DFT2G | G | PWA BOM |  |
|  |  | NO | 310200900-185-G | IC,Trigger,NC7SZ14P5X,1.65-5.5V,G,SC70-5P,SMD | FAIRCHILD SEMICONDUCTOR CORP | NC7SZ14P5X | G | PWA BOM |  |
|  |  | NO | 310107000-031-G | Logic IC,Gate&Inverter,74LVC1G14GW,1.65V~5.5V,14ns,TSSOP,5P,G | NXP SEMICONDUCTORS | 74LVC1G14GW | G | PWA BOM |  |
|  |  | Delete | 310107600-131-G | IC,Gate&Inverter,TC7SZ14FU,1.65~5.5V,G,SSOP-5,SMD | TOSHIBA ELECTRONICS ASIA LTD | TC7SZ14FU | G | PWA BOM |  |
| 33 | X6 |  | 710106900-162-G | XTAL,32.768KHz,+/-20ppm,12.5pF,G,SMD | EPSON ELECTRONICS AMERICA,INC. | Q13FC1350000400 | G | PWA BOM |  |
|  |  | NO | 71011P300-100-G | XTAL,32.768KHz,+/-20ppm,12.5pF,G,SMD | TXC CORPORATION | 9H03200031 | G | PWA BOM |  |
|  |  | Delete | 71010F700-107-G | XTAL,32.768KHz,+/-20ppm,12.5pF,-40_x0003_~85_x0003_,SMD,G | DAISHINKU CORPORATION/DAISHINKU SINGAPORE PTE LTD/KDS | 1TJF125DP1A000B | G | PWA BOM |  |
| 34 | DIMM02,DIMM04,DIMM06,DIMM09,DIMM11,DIMM13,DIMM15,DIMM16,DIMM18,DIMM20,DIMM22,DIMM25,DIMM27,DIMM29,DIMM31,DIMM00 |  | 34021BC00-G78-G | CONN,DDR IV,V/T,1.2V,Blu,0.85mm,15u,G,SMD-288 | FCI CONNECTORS HONGKONG LTD. | 10140702-0302K11LF | G | PWA BOM |  |
|  |  | ADD | ADDR0245-K010C | CONN,ADDR0245-K010C | LOTES | ADDR0245-K010C | G | PWA BOM |  |
|  |  | NO | 34021CD00-600-G | Memory Connector,AH58897-T2L31-3F,DDR IV,288,SMD,THERMOPLASTIC,0.85mm,15u",Blue,G | FOXCONN | AH58897-T2L31-3F | G | PWA BOM |  |
|  |  | NO | 34021CC00-245-G | Memory Connector,DDR4288S05A1H,DDR IV,288,SMD,NYLON,0.85mm,15u",Blue,G | AMPHENOL SHANGHAI CORP. | DDR4288S05A1H | G | PWA BOM |  |
| 35 | DIMM01,DIMM03,DIMM05,DIMM07,DIMM08,DIMM10,DIMM12,DIMM14,DIMM17,DIMM19,DIMM21,DIMM23,DIMM24,DIMM26,DIMM28,DIMM30 |  | 34021BD00-G78-G | CONN,DDR IV,V/T,1.2V,Bla,0.85mm,15u,G,SMD-288 | FCI CONNECTORS HONGKONG LTD. | 10140702-0301K11LF | G | PWA BOM |  |
|  |  | ADD | ADDR0245-P009C | CONN,ADDR0245-P009C | LOTES | ADDR0245-P009C | G | PWA BOM |  |
|  |  | NO | 34021CF00-600-G | Memory Connector,AH58897-T2B21-3F,DDR IV,288,SMD,THERMOPLASTIC,0.85mm,15u",Black,G | FOXCONN | AH58897-T2B21-3F | G | PWA BOM |  |
|  |  | NO | 34021CE00-245-G | Memory Connector,DDR4288S0511H,DDR IV,288,SMD,NYLON,0.85mm,15u",Black,G | AMPHENOL SHANGHAI CORP. | DDR4288S0511H | G | PWA BOM |  |
| 36 | JP1(2-3),JP4(2-3),JP5(2-3),JP6(1-2) |  | 340612R00-309-G | CONN,Jumper,Bla,2.54mm,G,DIP-2 | SAMTEC INC. | SNT-100-BK-G | G | PWA BOM |  |
|  |  | NO | 34065L900-GRT-G | CONN,jumper,Bla,2.54mm,30u,G,DIP-2 | PINREX TECHNOLOGY CORP. | 201-71-01DB00 | G | PWA BOM |  |
|  |  | NO | 34066N500-600-G | Header&Socket Connector,SJ0520F-A0,Jumper,2,DIP,PBT,2.54mm,3u",Black,G | FOXCONN TECHNOLOGY CO.,LTD. | SJ0520F-A0 | G | PWA BOM |  |
|  |  | Delete | 34069RA00-637-G | Header&Socket Connector,1200210020,Jumper,2,DIP,PBT,2.54mm,3u",Black,G | LONG SHOUNG CO.,LTD. | 1200210020 | G | PWA BOM |  |
| 37 | J35,J37,J39,J42,J45 |  | 3406AQH00-317-G | CONN,Header,Pin Header,1X6,V/T,Bla,2.54mm,G,SMD-6 | MOLEX INCORPORATED | 87898-0656 | G | PWA BOM |  |
|  |  | NO | 3406A9F00-GRT-G | Header&Socket Connector,212-91-06GBE2,Pin Header,6,SMD,NY6T,2.54mm,3u",Black,G | PINREX TECHNOLOGY CORP. | 212-91-06GBE2 | G | PWA BOM |  |
|  |  | NO | 3406AYA00-245-G | Header&Socket Connector,G800MR302032EU,Pin Header,6,DIP,LCP,2.54mm,999.9999u",Black,G | AMPHENOL SHANGHAI CORP. | G800MR302032EU | G | PWA BOM |  |
|  |  | Delete | 3406AY600-971-G | Header&Socket Connector,C18358-1063N-L,Pin Header,6,SMD,LCP,2.54mm,999.9999u",Black,G | ALLTOP TECHNOLOGY CO.,LTD | C18358-1063N-L | G | PWA BOM |  |
| 38 | J101 |  | 34062MW00-309-G | CONN,Header,WTB,2X5,V/T,Bla,1.27mm,10u,G,SMD-10 | SAMTEC INC. | FTSH-105-01-L-DV-K-P-TR | G | PWA BOM |  |
|  |  | NO | 3406AR700-GRT-G | Header&Socket Connector,232-9B-05SBEC,Pin Header,10,SMD,NY6T,1.27mm,10u",Black,G | PINREX TECHNOLOGY CORP. | 232-9B-05SBEC | G | PWA BOM |  |
|  |  | NO | 3406ATS00-637-G | CONN,Header,Pin Header,2X5,V/T,Bla,1.27mm,10u,G,SMD-10 | LONG SHOUNG CO.,LTD. | 11210B5805 | G | PWA BOM |  |
|  |  | Delete | 3406AYJ00-600-G | Header&Socket Connector,HS64056-B100-9F,Pin Header,10,SMD,THERMOPLASTIC,1.27mm,10u",Black,G | FOXCONN TECHNOLOGY CO.,LTD. | HS64056-B100-9F | G | PWA BOM |  |
| 39 | LAN1 |  | 34050PV00-48U-G | CONN,Modular Jack,RJ45X2,R/A,Bla,1.27mm,50u,G,DIP-28 | TRP CONNECTOR B.V. | 1840855-5 | G | PWA BOM |  |
|  |  | ADD | 34051E700-609-G | CONN,Modular Jack,RJ45X2,R/A,Bla,1.27mm,50u,G,DIP-28 | U.D. Electronic Corp. | MA-FN-0003 | G | PWA BOM |  |
| OOOOOOOOOOOOOOOOOOOOOOOOOOOOOOOOOOOOOOOOOOOOOOOOOOOOOOOOOOOOOOOOOOOOOOOOOOOOOOOOOOOOOOOOOO | OOOOOOOOOOOOOOOOOOOOOOOOOOOOOOOOOOOOOOOOOOOOOOOOOOOOOOOOOOOOOOOOOOOOOOOOOOOOOOOOOOOOOOOOOO | OOOOOOOOOOOOOOOOOOOOOOOOOOOOOOOOOOOOOOOOOOOOOOOOOOOOOOOOOOOOOOOOOOOOOOOOOOOOOOOOOOOOOOOOOO | OOOOOOOOOOOOOOOOOOOOOOOOOOOOOOOOOOOOOOOOOOOOOOOOOOOOOOOOOOOOOOOOOOOOOOOOOOOOOOOOOOOOOOOOOO | OOOOOOOOOOOOOOOOOOOOOOOOOOOOOOOOOOOOOOOOOOOOOOOOOOOOOOOOOOOOOOOOOOOOOOOOOOOOOOOOOOOOOOOOOO | OOOOOOOOOOOOOOOOOOOOOOOOOOOOOOOOOOOOOOOOOOOOOOOOOOOOOOOOOOOOOOOOOOOOOOOOOOOOOOOOOOOOOOOOOO | OOOOOOOOOOOOOOOOOOOOOOOOOOOOOOOOOOOOOOOOOOOOOOOOOOOOOOOOOOOOOOOOOOOOOOOOOOOOOOOOOOOOOOOOOO | OOOOOOOOOOOOOOOOOOOOOOOOOOOOOOOOOOOOOOOOOOOOOOOOOOOOOOOOOOOOOOOOOOOOOOOOOOOOOOOOOOOOOOOOOO | OOOOOOOOOOOOOOOOOOOOOOOOOOOOOOOOOOOOOOOOOOOOOOOOOOOOOOOOOOOOOOOOOOOOOOOOOOOOOOOOOOOOOOOOOO | OOOOOOOOOOOOOOOOOOOOOOOOOOOOOOOOOOOOOOOOOOOOOOOOOOOOOOOOOOOOOOOOOOOOOOOOOOOOOOOOOOOOOOOOOO |
| Master Materials Change |  |  |  |  |  |  |  |  |  |
| Item | Foxconn P/N | Orig._Usage | New_Usage | Part Description | Manufacturer Full Name | Manufacturer P/N | RoHS | Location | Sheet |
| 1 | 0101EW800-000-G | 0 | 1 | PCB,Zaius-MB DVT-X03,OSP,Blu,22L,22.20*13.00,G | PCB | 0101EW800-000-G | G | (+)PCB | PWA BOM |
| 2 | 520304B00-237-G | 2 | 3 | DIODE,Schottky,BAT54WS-7-F,30V,0.1A,G,SOD323-2,SMD | DIODES INEORPORATION | BAT54WS-7-F | G | (+)D56 | PWA BOM |
|  | 520303500-223-G |  |  | Diode,Schottky,BAT54HT1G,30V,200mA,SOD-323,2P,G | ON SEMICONDUCTOR CORP | BAT54HT1G |  |  | PWA BOM |
|  | 520308200-031-G |  |  | DIODE,Schottky,1PS76SB10,30V,200mA,G,SOD323-2,SMD | NXP SEMICONDUCTORS | 1PS76SB10 |  |  | PWA BOM |
| 3 | 610107A00-017-G | 711 | 719 | RES,0 Ohm,+/-5%,1/16W,G,SMD0402 | KOA SPEER ELECTRONICS, INC. | RK73Z1ETTP | G | (+)PBER93,PAFR93,PAER93,PBFR94,PBER96,PAFR96,PAER96,PBFR97,PBMR303,PBFR303,PBER303,PBAR303,PAMR303,PAFR303,PAER303,PAAR303,R1281,R1283,R1285,R1289,R1290,R1291,R1292,R1293,R1549 (-)PAER46,PBFR518,PBER518,PAFR518,PBFR519,PBER519,PAFR519,PAER519,PAER520,R1307,R1314,R1315,R1316,R1317,R1318,R1319,R1320 | PWA BOM |
|  | 610107A00-012-G |  |  | RES,0 Ohm,+/-5%,1/16W,G,SMD0402 | WALSIN | WR04X000PTL |  |  | PWA BOM |
|  | 610107A00-011-G |  |  | RES,0 Ohm,+/-5%,1/16W,G,SMD0402 | YAGEO | RC0402JR-070RL |  |  | PWA BOM |
|  | 610107A00-044-G |  |  | RES,0 Ohm,+/-5%,1/16W,G,SMD0402 | TA-I | RM04JTN0 |  |  | PWA BOM |
|  | 610107A00-024-G |  |  | RES,0 Ohm,+/-5%,1/16W,G,SMD0402 | PANASONIC INDUSTRIAL CO.,LTD. | ERJ2GE0R00X |  |  | PWA BOM |
|  | 610107A00-029-G |  |  | RES,0 Ohm,+/-5%,1/16W,G,SMD0402 | VISHAY ENTER TECHNO LOGY.INC | CRCW04020000Z0ED |  |  | PWA BOM |
| 4 | 61010L300-017-G | 42 | 34 | RES,1KOhm,+/-1%,1/16W,G,SMD0402 | KOA SPEER ELECTRONICS, INC. | RK73H1ETTP1001F | G | (-)PBMR303,PBFR303,PBER303,PBAR303,PAMR303,PAFR303,PAER303,PAAR303 | PWA BOM |
|  | 61010L300-012-G |  |  | RES,1KOhm,+/-1%,1/16W,G,SMD0402 | WALSIN | WR04X1001FTL |  |  | PWA BOM |
|  | 61010L300-011-G |  |  | RES,1KOhm,+/-1%,1/16W,G,SMD0402 | YAGEO | RC0402FR-071KL |  |  | PWA BOM |
|  | 61010L300-044-G |  |  | RES,1KOhm,+/-1%,1/16W,G,SMD0402 | TA-I | RM04FTN1001 |  |  | PWA BOM |
|  | 61010L300-024-G |  |  | RES,1KOhm,+/-1%,1/16W,G,SMD0402 | PANASONIC INDUSTRIAL CO.,LTD. | ERJ2RKF1001X |  |  | PWA BOM |
|  | 61010L300-029-G |  |  | RES,1KOhm,+/-1%,1/16W,G,SMD0402 | VISHAY ENTER TECHNO LOGY.INC | CRCW04021K00FKED |  |  | PWA BOM |
| 5 | 61100YT00-017-G | 0 | 4 | RES,487 Ohm,+/-0.1%,1/16W,G,SMD0402 | KOA SPEER ELECTRONICS, INC. | RN731ETTP4870B25 | G | (+)PBFR34,PBER34,PAFR34,PAER34 | PWA BOM |
| 6 | 61100RF00-017-G | 0 | 2 | RES,402 Ohm,+/-0.1%,1/16W,G,SMD0402 | KOA SPEER ELECTRONICS, INC. | RN731ETTP4020B25 | G | (+)PBMR34,PAMR34 | PWA BOM |
| 7 | 610119C00-017-G | 0 | 2 | RES,130KOhm,+/-1%,1/16W,G,SMD0402 | KOA SPEER ELECTRONICS, INC. | RK73H1ETTP1303F | G | (+)PSUR1,PSUR4 | PWA BOM |
|  | 610119C00-011-G |  |  | RES,130KOhm,+/-1%,1/16W,G,SMD0402 | YAGEO CORPORATION COMPONENT | RC0402FR-07130KL |  |  | PWA BOM |
|  | 610119C00-012-G |  |  | RES,130KOhm,+/-1%,1/16W,G,SMD0402 | WALSIN TECHNOLOGY CORPORATION | WR04X1303FTL |  |  | PWA BOM |
|  | 610119C00-044-G |  |  | RES,130KOhm,+/-1%,1/16W,G,SMD0402 | TA-I TECHNOLOGY CO., LTD | RM04FTN1303 |  |  | PWA BOM |
| 8 | 610116G00-017-G | 0 | 2 | RES,150KOhm,+/-1%,1/16W,G,SMD0402 | KOA SPEER ELECTRONICS, INC. | RK73H1ETTP1503F | G | (+)PSUR2,PSUR5 | PWA BOM |
|  | 610116G00-011-G |  |  | RES,150KOhm,+/-1%,1/16W,G,SMD0402 | YAGEO CORPORATION COMPONENT | RC0402FR-07150KL |  |  | PWA BOM |
|  | 610116G00-012-G |  |  | RES,150KOhm,+/-1%,1/16W,G,SMD0402 | WALSIN TECHNOLOGY CORPORATION | WR04X1503FTL |  |  | PWA BOM |
|  | 610116G00-044-G |  |  | RES,150KOhm,+/-1%,1/16W,G,SMD0402 | TA-I TECHNOLOGY CO., LTD | RM04FTN1503 |  |  | PWA BOM |
| 9 | 61011LF00-017-G | 1 | 2 | RES,499KOhm,+/-1%,1/16W,G,SMD0402 | KOA SPEER ELECTRONICS, INC. | RK73H1ETTP4993F | G | (+)R1847 | PWA BOM |
|  | 61011LF00-012-G |  |  | RES,499KOhm,+/-1%,1/16W,G,SMD0402 | WALSIN | WR04X4993FTL |  |  | PWA BOM |
|  | 61011LF00-011-G |  |  | RES,499KOhm,+/-1%,1/16W,G,SMD0402 | YAGEO | RC0402FR-07499KL |  |  | PWA BOM |
|  | 61011LF00-044-G |  |  | RES,499KOhm,+/-1%,1/16W,G,SMD0402 | TA-I | RM04FTN4993 |  |  | PWA BOM |
| 10 | 3406B5J00-317-G | 0 | 1 | CONN,Header,Socket,V/T,Bla,2mm,15u,G,DIP-18 | MOLEX INCORPORATED | 79107-7008 | G | (+)J10 | PWA BOM |
| 11 | 34064J800-317-G | 0 | 1 | CONN,Header,Socket,2X2,V/T,Bla,2mm,15u,G,DIP-4 | MOLEX INCORPORATED | 79107-7001 | G | (+)J13 | PWA BOM |
| 12 | TLRH3APTTE20L0F | 0 | 2 | RES,20mOhm,+/-1%,2W,G,SMD2512 | KOA SPEER ELECTRONICS, INC. | TLRH3APTTE20L0F | G | (+)PBAR65,PAAR65 | PWA BOM |
| 13 | SLW1TTE50L0F | 0 | 4 | RES,50mOhm,+/-1%,1.5W,G,SMD2512 | KOA | SLW1TTE50L0F | G | (+)PBER65,PAFR65,PAER65,PBFR66 | PWA BOM |
| 14 | SLW1TTE75L0F | 0 | 2 | RES,75mOhm,+/-1%,1.5W,G,SMD2512 | KOA | SLW1TTE75L0F | G | (+)PBMR65,PAMR65 | PWA BOM |
| 15 | 34080F500-653-G | 0 | 1 | CONN,Switch,slide,25mA,24V,G,SMD-8 | DIPTRONICS MANUFACTURING INC. | DHN-04F-T-V-T/R | G | (+)PSUSW1 | PWA BOM |
| 16 | PCB | 1 | 0 | PCB | PCB | PCB | G | (-)PCB | PWA BOM |
| 17 | 79107-7008 | 1 | 0 | CONN,Header,Socket,2X9,V/T,Bla,2mm,15u,G,DIP-18 | MOLEX INCORPORATED | 79107-7008 | G | (-)J10 | PWA BOM |
| 18 | 79107-7001 | 1 | 0 | CONN,Header,Socket,2X2,V/T,Bla,2mm,15u,G,DIP-4 | MOLEX INCORPORATED | 79107-7001 | G | (-)J13 | PWA BOM |
| 19 | 61012WF00-017-G | 2 | 0 | RES,20mOhm,+/-1%,1W,G,SMD2512 | KOA SPEER ELECTRONICS, INC. | UR73D3ATTE20L0F | G | (-)PBAR65,PAAR65 | PWA BOM |
| 20 | 610118N00-017-G | 4 | 0 | RES,487 Ohm,+/-1%,1/16W,G,SMD0402 | KOA SPEER ELECTRONICS, INC. | RK73H1ETTP4870F | G | (-)PBFR34,PBER34,PAFR34,PAER34 | PWA BOM |
| 21 | 610605200-034-G | 4 | 0 | RES,50mOhm,+/-1%,3W,G,SMD2512 | CYNTEC CO. LTD | RL-3264-0W-R050-FNH | G | (-)PBER65,PAFR65,PAER65,PBFR66 | PWA BOM |
| 22 | 61011J902-017-G | 2 | 0 | RES,402 Ohm,+/-1%,1/16W,G,SMD0402 | KOA SPEER ELECTRONICS, INC. | RK73H1ETTP4020F | G | (-)PBMR34,PAMR34 | PWA BOM |
| 23 | 610115R00-017-G | 1 | 0 | RES,15KOhm,+/-1%,1/16W,G,SMD0402 | KOA SPEER ELECTRONICS, INC. | RK73H1ETTP1502F | G | (-)PSUR1 | PWA BOM |
|  | 610115R00-012-G |  |  | RES,15KOhm,+/-1%,1/16W,G,SMD0402 | WALSIN | WR04X1502FTL |  |  | PWA BOM |
|  | 610115R00-011-G |  |  | RES,15KOhm,+/-1%,1/16W,G,SMD0402 | YAGEO | RC0402FR-0715KL |  |  | PWA BOM |
|  | 610115R00-044-G |  |  | RES,15KOhm,+/-1%,1/16W,G,SMD0402 | TA-I | RM04FTN1502 |  |  | PWA BOM |
|  | 610115R00-024-G |  |  | RES,15KOhm,+/-1%,1/16W,G,SMD0402 | PANASONIC INDUSTRIAL CO.,LTD. | ERJ2RKF1502X |  |  | PWA BOM |
|  | 610115R00-029-G |  |  | RES,15KOhm,+/-1%,1/16W,G,SMD040 | VISHAY ENTER TECHNO LOGY.INC | CRCW040215K0FKED |  |  | PWA BOM |
| 24 | TLRH3APTTE60L0F | 2 | 0 | RES,60mOhm,+/-0.5%,2W,G,SMD2512 | KOA SPEER ELECTRONICS, INC. | TLRH3APTTE60L0F | G | (-)PBMR65,PAMR65 | PWA BOM |
| OOOOOOOOOOOOOOOOOOOOOOOOOOOOOOOOOOOOOOOOOOOOOOOOOOOOOOOOOOOOOOOOOOOOOOOOOOOOOOOOOOOOOOOOOO | OOOOOOOOOOOOOOOOOOOOOOOOOOOOOOOOOOOOOOOOOOOOOOOOOOOOOOOOOOOOOOOOOOOOOOOOOOOOOOOOOOOOOOOOOO | OOOOOOOOOOOOOOOOOOOOOOOOOOOOOOOOOOOOOOOOOOOOOOOOOOOOOOOOOOOOOOOOOOOOOOOOOOOOOOOOOOOOOOOOOO | OOOOOOOOOOOOOOOOOOOOOOOOOOOOOOOOOOOOOOOOOOOOOOOOOOOOOOOOOOOOOOOOOOOOOOOOOOOOOOOOOOOOOOOOOO | OOOOOOOOOOOOOOOOOOOOOOOOOOOOOOOOOOOOOOOOOOOOOOOOOOOOOOOOOOOOOOOOOOOOOOOOOOOOOOOOOOOOOOOOOO | OOOOOOOOOOOOOOOOOOOOOOOOOOOOOOOOOOOOOOOOOOOOOOOOOOOOOOOOOOOOOOOOOOOOOOOOOOOOOOOOOOOOOOOOOO | OOOOOOOOOOOOOOOOOOOOOOOOOOOOOOOOOOOOOOOOOOOOOOOOOOOOOOOOOOOOOOOOOOOOOOOOOOOOOOOOOOOOOOOOOO | OOOOOOOOOOOOOOOOOOOOOOOOOOOOOOOOOOOOOOOOOOOOOOOOOOOOOOOOOOOOOOOOOOOOOOOOOOOOOOOOOOOOOOOOOO | OOOOOOOOOOOOOOOOOOOOOOOOOOOOOOOOOOOOOOOOOOOOOOOOOOOOOOOOOOOOOOOOOOOOOOOOOOOOOOOOOOOOOOOOOO | OOOOOOOOOOOOOOOOOOOOOOOOOOOOOOOOOOOOOOOOOOOOOOOOOOOOOOOOOOOOOOOOOOOOOOOOOOOOOOOOOOOOOOOOOO |
| TLA Parts Change |  |  |  |  |  |  |  |  |  |
| Item | Foxconn P/N | Qty | Part Description | Manufacturer Full Name | Manufacturer P/N | RoHS | Location | Remark | BOM |
| BOM Change List Date:Fri May 19 21:26:39 GMT+08:00 2017 |  |  |  |  |  |  |  |  |  |
| New BOM file : C:\<user>\BARRELEYE-G2-MB-DVT-HW-EBOM-X03_20170519.xls |  |  |  |  |  |  |  |  |  |
| Old BOM file : C:\<user>\BARRELEYE-G2-MB-DVT-HW-EBOM-X03_20170512.xls |  |  |  |  |  |  |  |  |  |
| ##### Add Parts |  |  |  |  |  |  |  |  |  |
| Item | Location | Qty | Foxconn P/N | Part Description | Manufacturer Full Name | Manufacturer P/N | RoHS | Sheet |  |
| 1 | R1519,R1848,R1849 | 3 | 610107A00-017-G | RES,0 Ohm,+/-5%,1/16W,G,SMD0402 | KOA SPEER ELECTRONICS, INC. | RK73Z1ETTP | N | PWA BOM |  |
| 2 | R1559 | 1 | 61010L100-017-G | RES,100KOhm,+/-1%,1/16W,G,SMD0402 | KOA SPEER ELECTRONICS, INC. | RK73H1ETTP1003F | N | PWA BOM |  |
| 3 | R1558 | 1 | 61010LA00-017-G | RES,4.7KOhm,+/-1%,1/16W,G,SMD0402 | KOA SPEER ELECTRONICS, INC. | RK73H1ETTP4701F | N | PWA BOM |  |
| 4 | Q15 | 1 | 510301N00-223-G | MOS N,2N7002LT1G,60V,0.115A,7.5ohm@5V,G,SOT23-3,SMD | ON SEMICONDUCTOR CORP | 2N7002LT1G | N | PWA BOM |  |
| ##### Remove Parts |  |  |  |  |  |  |  |  |  |
| Item | Location | Qty | Foxconn P/N | Part Description | Manufacturer Full Name | Manufacturer P/N | RoHS | Sheet |  |
| 1 | R1845 | 1 | 610108300-017-G | RES,0 Ohm,+/-5%,1/10W,G,SMD0603 | KOA SPEER ELECTRONICS, INC. | RK73Z1JTTD | N | PWA BOM |  |
| 2 | R1811 | 1 | 610102700-017-G | RES,49.9 Ohm,+/-1%,1/16W,G,SMD0402 | KOA SPEER ELECTRONICS, INC. | RK73H1ETTP49R9F | N | PWA BOM |  |
| ##### Change Parts |  |  |  |  |  |  |  |  |  |
| Item | Location | Qty | Foxconn P/N | Part Description | Manufacturer Full Name | Manufacturer P/N | RoHS | Sheet | Remark |
| 1 | PALR19,PALR20,PBLR23,PBLR24 | 4 | 61100LR00-017-G | RES,100 Ohm,+/-1%,1/16W,G,SMD0402 | KOA SPEER ELECTRONICS, INC. | RN731ETTP1000F50 |  | PWA BOM | In New BOM |
|  | PALR19,PALR20,PBLR23,PBLR24 | 4 | 610113800-017-G | RES,10 Ohm,+/-1%,1/16W,G,SMD0402 | KOA SPEER ELECTRONICS, INC. | RK73H1ETTP10R0F | N | PWA BOM | In Old BOM |
| 2 | PBMR57,PAMR57 | 2 | 610119U00-017-G | RES,133 Ohm,+/-1%,1/16W,G,SMD0402 | KOA SPEER ELECTRONICS, INC. | RK73H1ETTP1330F | N | PWA BOM | In New BOM |
|  | PBMR57,PAMR57 | 2 | 610123T00-017-G | RES,232 Ohm,+/-1%,1/16W,G,SMD0402 | KOA SPEER ELECTRONICS, INC. | RK73H1ETTP2320F | N | PWA BOM | In Old BOM |
| 3 | PSUU1 | 1 | 880302300-065-G | Converter,input 40V~60V,600W,G,Q54SJ12050NNDH,OVAL | DELTA ELECTRONICS INDUSTRIAL CO.,LTD | Q54SJ12050NNDH |  | PWA BOM | In New BOM |
|  | PSUU1 | 1 | 880302300-065-G | Converter,input 40V~60V,600W,G,Q54SJ12050NNDH,OVAL | DELTA ELECTRONICS INDUSTRIAL CO.,LTD | Q54SH12050NNDH |  | PWA BOM | In Old BOM |
| 4 | PBMR34,PAMR34 | 2 | RN731ETTP3160B25 | RES,316 Ohm,+/-0.1%,1/16W,G,SMD0402 | KOA SPEER ELECTRONICS, INC. | RN731ETTP3160B25 | N | PWA BOM | In New BOM |
|  | PBMR34,PAMR34 | 2 | 61100RF00-017-G | RES,402 Ohm,+/-0.1%,1/16W,G,SMD0402 | KOA SPEER ELECTRONICS, INC. | RN731ETTP4020B25 | N | PWA BOM | In Old BOM |
| ##### Change Revision |  |  |  |  |  |  |  |  |  |
| Sheet | REV OF BOM | CUSTOMER | CUSTOMER P/N | PWA PN | PWA DESCRIPTION | PWA REV | DATE | Remark |  |
| OOOOOOOOOOOOOOOOOOOOOOOOOOOOOOOOOOOOOOOOOOOOOOOOOOOOOOOOOOOOOOOOOOOOOOOOOOOOOOOOOOOOOOOOOO | OOOOOOOOOOOOOOOOOOOOOOOOOOOOOOOOOOOOOOOOOOOOOOOOOOOOOOOOOOOOOOOOOOOOOOOOOOOOOOOOOOOOOOOOOO | OOOOOOOOOOOOOOOOOOOOOOOOOOOOOOOOOOOOOOOOOOOOOOOOOOOOOOOOOOOOOOOOOOOOOOOOOOOOOOOOOOOOOOOOOO | OOOOOOOOOOOOOOOOOOOOOOOOOOOOOOOOOOOOOOOOOOOOOOOOOOOOOOOOOOOOOOOOOOOOOOOOOOOOOOOOOOOOOOOOOO | OOOOOOOOOOOOOOOOOOOOOOOOOOOOOOOOOOOOOOOOOOOOOOOOOOOOOOOOOOOOOOOOOOOOOOOOOOOOOOOOOOOOOOOOOO | OOOOOOOOOOOOOOOOOOOOOOOOOOOOOOOOOOOOOOOOOOOOOOOOOOOOOOOOOOOOOOOOOOOOOOOOOOOOOOOOOOOOOOOOOO | OOOOOOOOOOOOOOOOOOOOOOOOOOOOOOOOOOOOOOOOOOOOOOOOOOOOOOOOOOOOOOOOOOOOOOOOOOOOOOOOOOOOOOOOOO | OOOOOOOOOOOOOOOOOOOOOOOOOOOOOOOOOOOOOOOOOOOOOOOOOOOOOOOOOOOOOOOOOOOOOOOOOOOOOOOOOOOOOOOOOO | OOOOOOOOOOOOOOOOOOOOOOOOOOOOOOOOOOOOOOOOOOOOOOOOOOOOOOOOOOOOOOOOOOOOOOOOOOOOOOOOOOOOOOOOOO | OOOOOOOOOOOOOOOOOOOOOOOOOOOOOOOOOOOOOOOOOOOOOOOOOOOOOOOOOOOOOOOOOOOOOOOOOOOOOOOOOOOOOOOOOO |
| Second Source Change |  |  |  |  |  |  |  |  |  |
| Item | Location | Change Type | Foxconn P/N | Part Description | Manufacturer Full Name | Manufacturer P/N | RoHS | Sheet |  |
| OOOOOOOOOOOOOOOOOOOOOOOOOOOOOOOOOOOOOOOOOOOOOOOOOOOOOOOOOOOOOOOOOOOOOOOOOOOOOOOOOOOOOOOOOO | OOOOOOOOOOOOOOOOOOOOOOOOOOOOOOOOOOOOOOOOOOOOOOOOOOOOOOOOOOOOOOOOOOOOOOOOOOOOOOOOOOOOOOOOOO | OOOOOOOOOOOOOOOOOOOOOOOOOOOOOOOOOOOOOOOOOOOOOOOOOOOOOOOOOOOOOOOOOOOOOOOOOOOOOOOOOOOOOOOOOO | OOOOOOOOOOOOOOOOOOOOOOOOOOOOOOOOOOOOOOOOOOOOOOOOOOOOOOOOOOOOOOOOOOOOOOOOOOOOOOOOOOOOOOOOOO | OOOOOOOOOOOOOOOOOOOOOOOOOOOOOOOOOOOOOOOOOOOOOOOOOOOOOOOOOOOOOOOOOOOOOOOOOOOOOOOOOOOOOOOOOO | OOOOOOOOOOOOOOOOOOOOOOOOOOOOOOOOOOOOOOOOOOOOOOOOOOOOOOOOOOOOOOOOOOOOOOOOOOOOOOOOOOOOOOOOOO | OOOOOOOOOOOOOOOOOOOOOOOOOOOOOOOOOOOOOOOOOOOOOOOOOOOOOOOOOOOOOOOOOOOOOOOOOOOOOOOOOOOOOOOOOO | OOOOOOOOOOOOOOOOOOOOOOOOOOOOOOOOOOOOOOOOOOOOOOOOOOOOOOOOOOOOOOOOOOOOOOOOOOOOOOOOOOOOOOOOOO | OOOOOOOOOOOOOOOOOOOOOOOOOOOOOOOOOOOOOOOOOOOOOOOOOOOOOOOOOOOOOOOOOOOOOOOOOOOOOOOOOOOOOOOOOO | OOOOOOOOOOOOOOOOOOOOOOOOOOOOOOOOOOOOOOOOOOOOOOOOOOOOOOOOOOOOOOOOOOOOOOOOOOOOOOOOOOOOOOOOOO |
| Master Materials Change |  |  |  |  |  |  |  |  |  |
| Item | Foxconn P/N | Orig._Usage | New_Usage | Part Description | Manufacturer Full Name | Manufacturer P/N | RoHS | Location | Sheet |
| 1 | 610108300-017-G | 109 | 108 | RES,0 Ohm,+/-5%,1/10W,G,SMD0603 | KOA SPEER ELECTRONICS, INC. | RK73Z1JTTD | N | (-)R1845 | PWA BOM |
| 2 | 610107A00-017-G | 719 | 722 | RES,0 Ohm,+/-5%,1/16W,G,SMD0402 | KOA SPEER ELECTRONICS, INC. | RK73Z1ETTP | N | (+)R1519,R1848,R1849 | PWA BOM |
| 3 | 610113800-017-G | 31 | 27 | RES,10 Ohm,+/-1%,1/16W,G,SMD0402 | KOA SPEER ELECTRONICS, INC. | RK73H1ETTP10R0F | N | (-)PALR19,PALR20,PBLR23,PBLR24 | PWA BOM |
| 4 | 61100LR00-017-G | 27 | 31 | RES,100 Ohm,+/-1%,1/16W,G,SMD0402 | KOA SPEER ELECTRONICS, INC. | RN731ETTP1000F50 |  | (+)PALR19,PALR20,PBLR23,PBLR24 | PWA BOM |
| 5 | 61010L100-017-G | 16 | 17 | RES,100KOhm,+/-1%,1/16W,G,SMD0402 | KOA SPEER ELECTRONICS, INC. | RK73H1ETTP1003F | N | (+)R1559 | PWA BOM |
| 6 | 610119U00-017-G | 0 | 2 | RES,133 Ohm,+/-1%,1/16W,G,SMD0402 | KOA SPEER ELECTRONICS, INC. | RK73H1ETTP1330F | N | (+)PBMR57,PAMR57 | PWA BOM |
| 7 | 61010LA00-017-G | 152 | 153 | RES,4.7KOhm,+/-1%,1/16W,G,SMD0402 | KOA SPEER ELECTRONICS, INC. | RK73H1ETTP4701F | N | (+)R1558 | PWA BOM |
| 8 | 510301N00-223-G | 4 | 5 | MOS N,2N7002LT1G,60V,0.115A,7.5ohm@5V,G,SOT23-3,SMD | ON SEMICONDUCTOR CORP | 2N7002LT1G | N | (+)Q15 | PWA BOM |
| 9 | 610102700-017-G | 209 | 208 | RES,49.9 Ohm,+/-1%,1/16W,G,SMD0402 | KOA SPEER ELECTRONICS, INC. | RK73H1ETTP49R9F | N | (-)R1811 | PWA BOM |
| 10 | RN731ETTP3160B25 | 0 | 2 | RES,316 Ohm,+/-0.1%,1/16W,G,SMD0402 | KOA SPEER ELECTRONICS, INC. | RN731ETTP3160B25 | N | (+)PBMR34,PAMR34 | PWA BOM |
| 11 | 61100RF00-017-G | 2 | 0 | RES,402 Ohm,+/-0.1%,1/16W,G,SMD0402 | KOA SPEER ELECTRONICS, INC. | RN731ETTP4020B25 | N | (-)PBMR34,PAMR34 | PWA BOM |
| 12 | 610123T00-017-G | 2 | 0 | RES,232 Ohm,+/-1%,1/16W,G,SMD0402 | KOA SPEER ELECTRONICS, INC. | RK73H1ETTP2320F | N | (-)PBMR57,PAMR57 | PWA BOM |
| OOOOOOOOOOOOOOOOOOOOOOOOOOOOOOOOOOOOOOOOOOOOOOOOOOOOOOOOOOOOOOOOOOOOOOOOOOOOOOOOOOOOOOOOOO | OOOOOOOOOOOOOOOOOOOOOOOOOOOOOOOOOOOOOOOOOOOOOOOOOOOOOOOOOOOOOOOOOOOOOOOOOOOOOOOOOOOOOOOOOO | OOOOOOOOOOOOOOOOOOOOOOOOOOOOOOOOOOOOOOOOOOOOOOOOOOOOOOOOOOOOOOOOOOOOOOOOOOOOOOOOOOOOOOOOOO | OOOOOOOOOOOOOOOOOOOOOOOOOOOOOOOOOOOOOOOOOOOOOOOOOOOOOOOOOOOOOOOOOOOOOOOOOOOOOOOOOOOOOOOOOO | OOOOOOOOOOOOOOOOOOOOOOOOOOOOOOOOOOOOOOOOOOOOOOOOOOOOOOOOOOOOOOOOOOOOOOOOOOOOOOOOOOOOOOOOOO | OOOOOOOOOOOOOOOOOOOOOOOOOOOOOOOOOOOOOOOOOOOOOOOOOOOOOOOOOOOOOOOOOOOOOOOOOOOOOOOOOOOOOOOOOO | OOOOOOOOOOOOOOOOOOOOOOOOOOOOOOOOOOOOOOOOOOOOOOOOOOOOOOOOOOOOOOOOOOOOOOOOOOOOOOOOOOOOOOOOOO | OOOOOOOOOOOOOOOOOOOOOOOOOOOOOOOOOOOOOOOOOOOOOOOOOOOOOOOOOOOOOOOOOOOOOOOOOOOOOOOOOOOOOOOOOO | OOOOOOOOOOOOOOOOOOOOOOOOOOOOOOOOOOOOOOOOOOOOOOOOOOOOOOOOOOOOOOOOOOOOOOOOOOOOOOOOOOOOOOOOOO |  |
| TLA Parts Change |  |  |  |  |  |  |  |  |  |
| Item | Foxconn P/N | Qty | Part Description | Manufacturer Full Name | Manufacturer P/N | RoHS | Location | Remark |  |
| BOM Change List Date:Thu May 25 13:30:29 GMT+08:00 2017 |  |  |  |  |  |  |  |  |  |
| New BOM file : C:\<user>\BARRELEYE-G2-MB-DVT-HW-X03-BOM-X17_20170525.xls |  |  |  |  |  |  |  |  |  |
| Old BOM file : C:\<user>\BARRELEYE-G2-MB-DVT-HW-X03-BOM-X16_20170517.xls |  |  |  |  |  |  |  |  |  |
| ##### Add Parts |  |  |  |  |  |  |  |  |  |
| Item | Location | Qty | Foxconn P/N | Part Description | Manufacturer Full Name | Manufacturer P/N | RoHS | Sheet |  |
| 1 | R1519,R1848,R1849 | 3 | 610107A00-017-G | RES,0 Ohm,+/-5%,1/16W,G,SMD0402 | KOA SPEER ELECTRONICS, INC. | RK73Z1ETTP | G | PWA BOM |  |
|  |  |  | 610107A00-012-G | RES,0 Ohm,+/-5%,1/16W,G,SMD0402 | WALSIN TECHNOLOGY CORPORATION | WR04X000PTL | G | PWA BOM |  |
|  |  |  | 610107A00-011-G | RES,0 Ohm,+/-5%,1/16W,G,SMD0402 | YAGEO CORPORATION COMPONENT | RC0402JR-070RL | G | PWA BOM |  |
|  |  |  | 610107A00-044-G | RES,0 Ohm,+/-5%,1/16W,G,SMD0402 | TA-I TECHNOLOGY CO., LTD | RM04JTN0 | G | PWA BOM |  |
|  |  |  | 610107A00-024-G | RES,0 Ohm,+/-5%,1/16W,G,SMD0402 | PANASONIC INDUSTRIAL CO.,LTD. | ERJ2GE0R00X | G | PWA BOM |  |
|  |  |  | 610107A00-029-G | RES,0 Ohm,+/-5%,1/16W,G,SMD0402 | VISHAY ENTER TECHNO LOGY.INC | CRCW04020000Z0ED | G | PWA BOM |  |
| 2 | R1559 | 1 | 61010L100-017-G | RES,100KOhm,+/-1%,1/16W,G,SMD0402 | KOA SPEER ELECTRONICS, INC. | RK73H1ETTP1003F | G | PWA BOM |  |
|  |  |  | 61010L100-012-G | RES,100KOhm,+/-1%,1/16W,G,SMD0402 | WALSIN TECHNOLOGY CORPORATION | WR04X1003FTL | G | PWA BOM |  |
|  |  |  | 61010L100-011-G | RES,100KOhm,+/-1%,1/16W,G,SMD0402 | YAGEO CORPORATION COMPONENT | RC0402FR-07100KL | G | PWA BOM |  |
|  |  |  | 61010L100-044-G | RES,100KOhm,+/-1%,1/16W,G,SMD0402 | TA-I TECHNOLOGY CO., LTD | RM04FTN1003 | G | PWA BOM |  |
|  |  |  | 61010L106-029-G | RES,100KOhm,+/-1%,1/16W,G,SMD0402 | VISHAY ENTER TECHNO LOGY.INC | CRCW0402100KFKEDC | G | PWA BOM |  |
|  |  |  | 61010L100-024-G | RES,100KOhm,+/-1%,1/16W,G,SMD0402 | PANASONIC INDUSTRIAL CO.,LTD. | ERJ2RKF1003X | G | PWA BOM |  |
| 3 | R1558 | 1 | 61010LA00-017-G | RES,4.7KOhm,+/-1%,1/16W,G,SMD0402 | KOA SPEER ELECTRONICS, INC. | RK73H1ETTP4701F | G | PWA BOM |  |
|  |  |  | 61010LA00-012-G | RES,4.7KOhm,+/-1%,1/16W,G,SMD0402 | WALSIN TECHNOLOGY CORPORATION | WR04X4701FTL | G | PWA BOM |  |
|  |  |  | 61010LA00-011-G | RES,4.7KOhm,+/-1%,1/16W,G,SMD0402 | YAGEO CORPORATION COMPONENT | RC0402FR-074K7L | G | PWA BOM |  |
|  |  |  | 61010LA00-044-G | RES,4.7KOhm,+/-1%,1/16W,G,SMD0402 | TA-I TECHNOLOGY CO., LTD | RM04FTN4701 | G | PWA BOM |  |
| 4 | Q15 | 1 | 510301N00-223-G | MOS N,2N7002LT1G,60V,0.115A,7.5ohm@5V,G,SOT23-3,SMD | ON SEMICONDUCTOR CORP | 2N7002LT1G | G | PWA BOM |  |
|  |  |  | 51030CQ00-185-G | MOS N,2N7002,60V,115mA,7.5ohm@5V,G,SOT23-3,SMD | FAIRCHILD SEMICONDUCTOR CORP | 2N7002 |  | PWA BOM |  |
| ##### Remove Parts |  |  |  |  |  |  |  |  |  |
| Item | Location | Qty | Foxconn P/N | Part Description | Manufacturer Full Name | Manufacturer P/N | RoHS | Sheet |  |
| 1 | R1845 | 1 | 610108300-017-G | RES,0 Ohm,+/-5%,1/10W,G,SMD0603 | KOA SPEER ELECTRONICS, INC. | RK73Z1JTTD | N | PWA BOM |  |
|  |  |  | 610108300-012-G | RES,0 Ohm,+/-5%,1/10W,G,SMD0603 | WALSIN | WR06X000PTL | G | PWA BOM |  |
|  |  |  | 610108300-011-G | RES,0 Ohm,+/-5%,1/10W,G,SMD0603 | YAGEO | RC0603JR-070RL | G | PWA BOM |  |
|  |  |  | 610108300-044-G | RES,0 Ohm,+/-5%,1/10W,G,SMD0603 | TA-I | RM06JTN0 | G | PWA BOM |  |
|  |  |  | 610108300-024-G | RES,0 Ohm,+/-5%,1/10W,G,SMD0603 | PANASONIC INDUSTRIAL CO.,LTD. | ERJ3GEY0R00V | G | PWA BOM |  |
| 2 | R1811 | 1 | 610102700-017-G | RES,49.9 Ohm,+/-1%,1/16W,G,SMD0402 | KOA SPEER ELECTRONICS, INC. | RK73H1ETTP49R9F | N | PWA BOM |  |
|  |  |  | 610102700-012-G | RES,49.9 Ohm,+/-1%,1/16W,G,SMD0402 | WALSIN | WR04X49R9FTL | G | PWA BOM |  |
|  |  |  | 610102700-011-G | RES,49.9 Ohm,+/-1%,1/16W,G,SMD0402 | YAGEO | RC0402FR-0749R9L | G | PWA BOM |  |
|  |  |  | 610102700-044-G | RES,49.9 Ohm,+/-1%,1/16W,G,SMD0402 | TA-I | RM04FTN49R9 | G | PWA BOM |  |
|  |  |  | 610102700-029-G | RES,49.9 Ohm,+/-1%,1/16W,G,SMD0402 | VISHAY ENTER TECHNO LOGY.INC | CRCW040249R9FKED | G | PWA BOM |  |
|  |  |  | 610102700-024-G | RES,49.9 Ohm,+/-1%,1/16W,G,SMD0402 | PANASONIC INDUSTRIAL CO.,LTD. | ERJ2RKF49R9X | G | PWA BOM |  |
| ##### Change Parts |  |  |  |  |  |  |  |  |  |
| Item | Location | Qty | Foxconn P/N | Part Description | Manufacturer Full Name | Manufacturer P/N | RoHS | Sheet | Remark |
| 1 | PCB | 1 | 0101EW800-000-G | PCB,Zaius-MB DVT-X03,OSP,Blu,22L,22.20*13.00,G | GOLD CIRCUIT ELECTRONICS LTD. | 0101EW800-000-G | G | PWA BOM | In New BOM |
|  |  |  | 0101EW800-000-G | PCB,Zaius-MB DVT-X03,OSP,Blu,22L,22.20*13.00,G | ZHUHAI FOUNDER PRINTED CIRCUIT BOARD（HK） DEVELOPMENT LIMITED | 0101EW800-000-G | G | PWA BOM | In New BOM |
|  | PCB | 1 | 0101EW800-000-G | PCB,Zaius-MB DVT-X03,OSP,Blu,22L,22.20*13.00,G | PCB | 0101EW800-000-G |  | PWA BOM | In Old BOM |
| 2 | C5,C6,C9,C14,C15,C189,C190,C730,C731,C734,C737,C738,C905,C906,C1513,C1628,C1629,C1630,C1631,C1632,C1633,C1634,C1635,C1636,C1637,C1638,C1639,C1640,C1641,C1642,C1643,C1644,C1667,C1730,C1731,C1732,C1733,C1742,C1743,C1744,C1745,C2048,C2087 | 43 | 62011U701-015-G | CAP,10nF,+/-10%,X7R,6.3V,G,SMD0402 | MURATA ELEC. NORTH AMERICA | GRM155R70J103K | G | PWA BOM | In New BOM |
|  |  |  | 62011U700-012-G | CAP,10nF,+/-10%,X7R,6.3V,G,SMD0402 | WALSIN TECHNOLOGY CORPORATION | 0402B103K6R3CT | G | PWA BOM | In New BOM |
|  |  |  | 62011U700-023-G | CAP,10nF,+/-10%,X7R,6.3V,G,SMD0402 | TAIYO ELECTRIC IND.CO.LTD | JMK105B7103KV-F | G | PWA BOM | In New BOM |
|  | C5,C6,C9,C14,C15,C189,C190,C730,C731,C734,C737,C738,C905,C906,C1513,C1628,C1629,C1630,C1631,C1632,C1633,C1634,C1635,C1636,C1637,C1638,C1639,C1640,C1641,C1642,C1643,C1644,C1667,C1730,C1731,C1732,C1733,C1742,C1743,C1744,C1745,C2048,C2087 | 43 | 62011U701-015-G | CAP,10nF,+/-10%,X7R,6.3V,G,SMD0402 | MURATA ELEC. NORTH AMERICA | GRM155R70J103K |  | PWA BOM | In Old BOM |
|  |  |  | 62011U700-012-G | CAP,10nF,+/-10%,X7R,6.3V,G,SMD0402 | WALSIN | 0402B103K6R3CT | G | PWA BOM | In Old BOM |
|  |  |  | 62011U700-023-G | CAP,10nF,+/-10%,X7R,6.3V,G,SMD0402 | TAIYO ELECTRIC IND.CO.LTD | JMK105B7103KV-F | G | PWA BOM | In Old BOM |
| 3 | PUAC2,PSAC2,PRAC2,PQAC2,PPAC2,PIAC2,PFAC2,PEAC2,PANC7,PBNC8,PBNC15,PANC15,C33,C34,C698,C700,C701,C702,C705,C750,C1714,C1718,C1722,C1726,C2026,C2064,C2065,C2085,C2086,C2088,C2089,C2090,C2091,C2092,C2093,C2094,C2098,C2115,C2116,C2120,C2121,C2122 | 42 | 620106200-015-G | CAP,10nF,+/-10%,X7R,16V,G,SMD0402 | MURATA ELEC. NORTH AMERICA | GRM155R71C103KA01D | G | PWA BOM | In New BOM |
|  |  |  | 620106200-012-G | CAP,10nF,+/-10%,X7R,16V,G,SMD0402 | WALSIN TECHNOLOGY CORPORATION | 0402B103K160CT | G | PWA BOM | In New BOM |
|  |  |  | 620106200-026-G | CAP,10nF,+/-10%,X7R,16V,G,SMD0402 | SAMSUNG SEMICONDUCTOR | CL05B103KO5NNNC | G | PWA BOM | In New BOM |
|  |  |  | 620106200-023-G | CAP,10nF,+/-10%,X7R,16V,G,SMD0402 | TAIYO ELECTRIC IND.CO.LTD | EMK105B7103KV-F | G | PWA BOM | In New BOM |
|  | PUAC2,PSAC2,PRAC2,PQAC2,PPAC2,PIAC2,PFAC2,PEAC2,PANC7,PBNC8,PBNC15,PANC15,C33,C34,C698,C700,C701,C702,C705,C750,C1714,C1718,C1722,C1726,C2026,C2064,C2065,C2085,C2086,C2088,C2089,C2090,C2091,C2092,C2093,C2094,C2098,C2115,C2116,C2120,C2121,C2122 | 42 | 620106200-015-G | CAP,10nF,+/-10%,X7R,16V,G,SMD0402 | MURATA ELEC. NORTH AMERICA | GRM155R71C103KA01D | Y | PWA BOM | In Old BOM |
|  |  |  | 620106200-012-G | CAP,10nF,+/-10%,X7R,16V,G,SMD0402 | WALSIN | 0402B103K160CT | G | PWA BOM | In Old BOM |
|  |  |  | 620106200-026-G | CAP,10nF,+/-10%,X7R,16V,G,SMD0402 | SAMSUNG SEMICONDUCTOR | CL05B103KO5NNNC | G | PWA BOM | In Old BOM |
|  |  |  | 620106200-023-G | CAP,10nF,+/-10%,X7R,16V,G,SMD0402 | TAIYO ELECTRIC IND.CO.LTD | EMK105B7103KV-F | G | PWA BOM | In Old BOM |
| 4 | PHAC5,PUAC10,PSLC10,PSIC10,PSFC10,PSEC10,PSDC10,PSAC10,PRAC10,PQAC10,PPAC10,PIAC10,PFAC10,PEEC10,PEDC10,PEAC10,C35,C84,C85,C86,C87,C88,C89,C90,C91,C92,C93,C94,C98,C99,C100,C101,C102,C103,C104,C105,C106,C107,C108,C687,C688,C691,C692,C693,C695,C696,C706,C707,C708,C709,C710,C711,C712,C713,C714,C715,C716,C717,C718,C720,C721,C722,C723,C724,C725,C751,C793,C801,C802,C803,C804,C805,C806,C807,C808,C809,C810,C815,C816,C817,C818,C819,C820,C821,C822,C823,C824,C1497,C1498,C1503,C1504,C1691,C1692,C1693,C1694,C1699,C1700,C1701,C1702,C2000,C2001,C2002,C2003,C2021,C2022,C2023,C2024,C2025,C2027,C2034,C2036,C2037,C2038,C2039,C2040,C2042,C2043,C2044,C2045,C2046,C2049,C2050,C2051,C2052,C2053,C2054,C2055,C2056,C2057,C2058,C2059,C2060,C2061,C2062,C2067,C2068,C2073,C2075,C2077,C2078,C2079,C2080,C2083,C2084,C2095,C2096,C2099,C2100,C2101,C2102,C2103,C2104,C2105,C2106,C2117,C2118,C2119,C2123,C2125,C2126,C2127,C2128,C2130,C2133,C2134,C2135,C2142,C2144,C2157,C2158,C2159,C2160,C2161,C2186 | 174 | 620103700-015-G | CAP,100nF,+/-10%,X7R,10V,G,SMD0402 | MURATA ELEC. NORTH AMERICA | GRM155R71A104K | G | PWA BOM | In New BOM |
|  |  |  | 620103700-012-G | CAP,0.1uF,+/-10%,X7R,10V,G,SMD0402 | WALSIN TECHNOLOGY CORPORATION | 0402B104K100CT | G | PWA BOM | In New BOM |
|  |  |  | 620103700-023-G | CAP,100nF,+/-10%,X7R,10V,G,SMD0402 | TAIYO ELECTRIC IND.CO.LTD | LMK105B7104KV-F | G | PWA BOM | In New BOM |
|  |  |  | 620103700-026-G | CAP,100nF,+/-10%,X7R,10V,G,SMD0402 | SAMSUNG SEMICONDUCTOR | CL05B104KP5NNNC | G | PWA BOM | In New BOM |
|  | PHAC5,PUAC10,PSLC10,PSIC10,PSFC10,PSEC10,PSDC10,PSAC10,PRAC10,PQAC10,PPAC10,PIAC10,PFAC10,PEEC10,PEDC10,PEAC10,C35,C84,C85,C86,C87,C88,C89,C90,C91,C92,C93,C94,C98,C99,C100,C101,C102,C103,C104,C105,C106,C107,C108,C687,C688,C691,C692,C693,C695,C696,C706,C707,C708,C709,C710,C711,C712,C713,C714,C715,C716,C717,C718,C720,C721,C722,C723,C724,C725,C751,C793,C801,C802,C803,C804,C805,C806,C807,C808,C809,C810,C815,C816,C817,C818,C819,C820,C821,C822,C823,C824,C1497,C1498,C1503,C1504,C1691,C1692,C1693,C1694,C1699,C1700,C1701,C1702,C2000,C2001,C2002,C2003,C2021,C2022,C2023,C2024,C2025,C2027,C2034,C2036,C2037,C2038,C2039,C2040,C2042,C2043,C2044,C2045,C2046,C2049,C2050,C2051,C2052,C2053,C2054,C2055,C2056,C2057,C2058,C2059,C2060,C2061,C2062,C2067,C2068,C2073,C2075,C2077,C2078,C2079,C2080,C2083,C2084,C2095,C2096,C2099,C2100,C2101,C2102,C2103,C2104,C2105,C2106,C2117,C2118,C2119,C2123,C2125,C2126,C2127,C2128,C2130,C2133,C2134,C2135,C2142,C2144,C2157,C2158,C2159,C2160,C2161,C2186 | 174 | 620103700-015-G | CAP,100nF,+/-10%,X7R,10V,G,SMD0402 | MURATA ELEC. NORTH AMERICA | GRM155R71A104K | Y | PWA BOM | In Old BOM |
|  |  |  | 620103700-012-G | CAP,0.1uF,+/-10%,X7R,10V,G,SMD0402 | WALSIN | 0402B104K100CT | G | PWA BOM | In Old BOM |
|  |  |  | 620103700-023-G | CAP,100nF,+/-10%,X7R,10V,G,SMD0402 | TAIYO ELECTRIC IND.CO.LTD | LMK105B7104KV-F | G | PWA BOM | In Old BOM |
|  |  |  | 620103700-026-G | CAP,100nF,+/-10%,X7R,10V,G,SMD0402 | SAMSUNG SEMICONDUCTOR | CL05B104KP5NNNC | G | PWA BOM | In Old BOM |
| 5 | PSTC5,PSLC5,PSFC5,PSEC5,PSDC5,PQPC5,PFRC5,PEEC5,PEDC5,C46,C63,C69,C79,C142,C144,C157,C167,C226,C234,C774,C781,C785,C813,C856,C864,C873,C883 | 27 | 62012P100-015-G | CAP,2.2uF,+/-20%,X7S,10V,G,SMD0402 | MURATA ELEC. NORTH AMERICA | GRM155C71A225M | G | PWA BOM | In New BOM |
|  |  |  | 62012P100-012-G | CAP,2.2uF,+/-20%,X7S,10V,G,SMD0402 | WALSIN TECHNOLOGY CORPORATION | 0402A225M100CT | G | PWA BOM | In New BOM |
|  | PSTC5,PSLC5,PSFC5,PSEC5,PSDC5,PQPC5,PFRC5,PEEC5,PEDC5,C46,C63,C69,C79,C142,C144,C157,C167,C226,C234,C774,C781,C785,C813,C856,C864,C873,C883 | 27 | 62012P100-015-G | CAP,2.2uF,+/-20%,X7S,10V,G,SMD0402 | MURATA ELEC. NORTH AMERICA | GRM155C71A225M |  | PWA BOM | In Old BOM |
|  |  |  | 62012P100-012-G | CAP,2.2uF,+/-20%,X7S,10V,G,SMD0402 | WALSIN | 0402A225M100CT | G | PWA BOM | In Old BOM |
| 6 | PSPC1,PIPC1,PFPC1,PEPC1,PSTC10,PQPC10,PFRC10,PETC10,PERC10,PBNC16,PANC16,PBNC17,PANC17,PALC36,PALC41,PALC44,PBLC57,PBLC61,PBLC64,C192,C194,C196,C198,C316,C318,C320,C322,C440,C442,C444,C446,PBFC500,PBEC500,PAFC500,PAEC500,C564,C566,C568,C570,PBMC600,PBAC600,PAMC600,PAAC600,C908,C910,C912,C914,C1032,C1034,C1036,C1038,C1156,C1158,C1160,C1162,C1280,C1282,C1284,C1286,C1403,C1404,C1405,C1406,C1407,C1408,C1409,C1410,C1411,C1412,C1413,C1414,C1415,C1416,C1417,C1418,C1419,C1422,C1423,C1425,C1426,C1428,C1429,C1430,C1431,C1432,C1433,C1434,C1435,C1436,C1437,C1438,C1441,C1442,C1443,C1444,C1445,C1446,C1449,C1450,C1452,C1453,C1454,C1457,C1460,C1461,C1462,C1465,C1467,C1469,C1471,C1472,C1480,C1481,C1484,C1487,C1488,C1490,C1491,C1493,C1494,C1496,C1515,C1516,C1518,C1520,C1521,C1522,C1524,C1526,C1527,C1528,C1529,C1530,C1531,C1534,C1535,C1536,C1537,C1538,C1539,C1540,C1543,C1544,C1545,C1552,C1561,C1562,C1568,C1569,C1570,C1571,C1576,C1597,C1600,C1603,C1606,C1608,C1609,C1610,C1611,C1612,C1613,C1616,C1617,C1618,C1619,C1620,C1621,C1622,C1624,C1625,C1626,C1627,C1645,C1646,C1647,C1648,C1649,C1651,C1652,C1677,C1678,C1713,C1715,C1719,C1723,C1727,C1738,C1740,C1749,C1750,C1787,C1796,C1797,C1841,C1842,C1876,C1886,C1887,C1940,C1941,C1943,C1946,C1949,C1951,C1959,C1960,C1961,C1977,C1978,C1979,C1980,C1981,C1982,C1983,C2011,C2012,C2029,C2070,C2107,C2108,C2109,C2112,C2131,C2132,C2152,C2155,C2156,C2163,C2164,C2165,C2167,C2181,PSRC3016 | 234 | 620101T02-015-G | CAP,100nF,+/-10%,X7R,16V,G,SMD0402 | MURATA ELEC. NORTH AMERICA | GRM155R71C104K | G | PWA BOM | In New BOM |
|  |  |  | 620101T00-012-G | CAP,100nF,+/-10%,X7R,16V,G,SMD0402 | WALSIN TECHNOLOGY CORPORATION | 0402B104K160CT | G | PWA BOM | In New BOM |
|  |  |  | 620101T00-026-G | CAP,100nF,+/-10%,X7R,16V,G,SMD0402 | SAMSUNG SEMICONDUCTOR | CL05B104KO5NNNC | G | PWA BOM | In New BOM |
|  |  |  | 620101T00-015-G | CAP,100nF,+/-10%,X7R,16V,G,SMD0402 | MURATA ELEC. NORTH AMERICA | GRM155R71C104KA88D | G | PWA BOM | In New BOM |
|  | PSPC1,PIPC1,PFPC1,PEPC1,PSTC10,PQPC10,PFRC10,PETC10,PERC10,PBNC16,PANC16,PBNC17,PANC17,PALC36,PALC41,PALC44,PBLC57,PBLC61,PBLC64,C192,C194,C196,C198,C316,C318,C320,C322,C440,C442,C444,C446,PBFC500,PBEC500,PAFC500,PAEC500,C564,C566,C568,C570,PBMC600,PBAC600,PAMC600,PAAC600,C908,C910,C912,C914,C1032,C1034,C1036,C1038,C1156,C1158,C1160,C1162,C1280,C1282,C1284,C1286,C1403,C1404,C1405,C1406,C1407,C1408,C1409,C1410,C1411,C1412,C1413,C1414,C1415,C1416,C1417,C1418,C1419,C1422,C1423,C1425,C1426,C1428,C1429,C1430,C1431,C1432,C1433,C1434,C1435,C1436,C1437,C1438,C1441,C1442,C1443,C1444,C1445,C1446,C1449,C1450,C1452,C1453,C1454,C1457,C1460,C1461,C1462,C1465,C1467,C1469,C1471,C1472,C1480,C1481,C1484,C1487,C1488,C1490,C1491,C1493,C1494,C1496,C1515,C1516,C1518,C1520,C1521,C1522,C1524,C1526,C1527,C1528,C1529,C1530,C1531,C1534,C1535,C1536,C1537,C1538,C1539,C1540,C1543,C1544,C1545,C1552,C1561,C1562,C1568,C1569,C1570,C1571,C1576,C1597,C1600,C1603,C1606,C1608,C1609,C1610,C1611,C1612,C1613,C1616,C1617,C1618,C1619,C1620,C1621,C1622,C1624,C1625,C1626,C1627,C1645,C1646,C1647,C1648,C1649,C1651,C1652,C1677,C1678,C1713,C1715,C1719,C1723,C1727,C1738,C1740,C1749,C1750,C1787,C1796,C1797,C1841,C1842,C1876,C1886,C1887,C1940,C1941,C1943,C1946,C1949,C1951,C1959,C1960,C1961,C1977,C1978,C1979,C1980,C1981,C1982,C1983,C2011,C2012,C2029,C2070,C2107,C2108,C2109,C2112,C2131,C2132,C2152,C2155,C2156,C2163,C2164,C2165,C2167,C2181,PSRC3016 | 234 | 620101T02-015-G | CAP,100nF,+/-10%,X7R,16V,G,SMD0402 | MURATA ELEC. NORTH AMERICA | GRM155R71C104K | Y | PWA BOM | In Old BOM |
|  |  |  | 620101T00-012-G | CAP,100nF,+/-10%,X7R,16V,G,SMD0402 | WALSIN | 0402B104K160CT | G | PWA BOM | In Old BOM |
|  |  |  | 620101T00-026-G | CAP,100nF,+/-10%,X7R,16V,G,SMD0402 | SAMSUNG SEMICONDUCTOR | CL05B104KO5NNNC | G | PWA BOM | In Old BOM |
|  |  |  | 620101T00-015-G | CAP,100nF,+/-10%,X7R,16V,G,SMD0402 | MURATA ELEC. NORTH AMERICA | GRM155R71C104KA88D | G | PWA BOM | In Old BOM |
| 7 | C209,C210,C211,C212,C213,C214,C215,C216,C227,C333,C334,C335,C336,C337,C338,C339,C340,C457,C458,C459,C460,C461,C462,C463,C464,C581,C582,C583,C584,C585,C586,C587,C588,C925,C926,C927,C928,C929,C930,C931,C932,C1049,C1050,C1051,C1052,C1053,C1054,C1055,C1056,C1173,C1174,C1175,C1176,C1177,C1178,C1179,C1180,C1297,C1298,C1299,C1300,C1301,C1302,C1303,C1304,C1532,C2009 | 67 | 62011KG00-015-G | CAP,100nF,+/-5%,X7R,10V,G,SMD0402 | MURATA ELEC. NORTH AMERICA | GRM155R71A104JA01D | G | PWA BOM | In New BOM |
|  |  |  | 62011KG00-012-G | CAP,100nF,+/-5%,X7R,10V,G,SMD0402 | WALSIN TECHNOLOGY CORPORATION | 0402B104J100CT | G | PWA BOM | In New BOM |
|  |  |  | 62011KG00-026-G | CAP,100nF,+/-5%,X7R,10V,G,SMD0402 | SAMSUNG SEMICONDUCTOR | CL05B104JP5NNNC | G | PWA BOM | In New BOM |
|  | C209,C210,C211,C212,C213,C214,C215,C216,C227,C333,C334,C335,C336,C337,C338,C339,C340,C457,C458,C459,C460,C461,C462,C463,C464,C581,C582,C583,C584,C585,C586,C587,C588,C925,C926,C927,C928,C929,C930,C931,C932,C1049,C1050,C1051,C1052,C1053,C1054,C1055,C1056,C1173,C1174,C1175,C1176,C1177,C1178,C1179,C1180,C1297,C1298,C1299,C1300,C1301,C1302,C1303,C1304,C1532,C2009 | 67 | 62011KG00-015-G | CAP,100nF,+/-5%,X7R,10V,G,SMD0402 | MURATA ELEC. NORTH AMERICA | GRM155R71A104JA01D | N | PWA BOM | In Old BOM |
|  |  |  | 62011KG00-012-G | CAP,100nF,+/-5%,X7R,10V,G,SMD0402 | WALSIN | 0402B104J100CT | G | PWA BOM | In Old BOM |
|  |  |  | 62011KG00-026-G | CAP,100nF,+/-5%,X7R,10V,G,SMD0402 | SAMSUNG SEMICONDUCTOR | CL05B104JP5NNNC | G | PWA BOM | In Old BOM |
| 8 | PBNC9,PANC9,C237,C238,C239,C240,C247,C248,C249,C250,C265,C266,C267,C268,C283,C284,C285,C286,C361,C362,C363,C364,C371,C372,C373,C374,C389,C390,C391,C392,C407,C408,C409,C410,C485,C486,C487,C488,C495,C496,C497,C498,C513,C514,C515,C516,C531,C532,C533,C534,C609,C610,C611,C612,C619,C620,C621,C622,C637,C638,C639,C640,C655,C656,C657,C658,C953,C954,C955,C956,C963,C964,C965,C966,C981,C982,C983,C984,C999,C1000,C1001,C1002,C1077,C1078,C1079,C1080,C1087,C1088,C1089,C1090,C1105,C1106,C1107,C1108,C1123,C1124,C1125,C1126,C1201,C1202,C1203,C1204,C1211,C1212,C1213,C1214,C1229,C1230,C1231,C1232,C1247,C1248,C1249,C1250,C1325,C1326,C1327,C1328,C1335,C1336,C1337,C1338,C1353,C1354,C1355,C1356,C1371,C1372,C1373,C1374 | 130 | 620135Y00-015-G | CAP,2.2uF,+/-20%,X6S,10V,G,SMD0402 | MURATA ELEC. NORTH AMERICA | GRM155C81A225ME15D | G | PWA BOM | In New BOM |
|  |  |  | 620135Y00-012-G | CAP,2.2uF,+/-20%,X6S,10V,G,SMD0402 | WALSIN TECHNOLOGY CORPORATION | 0402S225M100CT | G | PWA BOM | In New BOM |
|  | PBNC9,PANC9,C237,C238,C239,C240,C247,C248,C249,C250,C265,C266,C267,C268,C283,C284,C285,C286,C361,C362,C363,C364,C371,C372,C373,C374,C389,C390,C391,C392,C407,C408,C409,C410,C485,C486,C487,C488,C495,C496,C497,C498,C513,C514,C515,C516,C531,C532,C533,C534,C609,C610,C611,C612,C619,C620,C621,C622,C637,C638,C639,C640,C655,C656,C657,C658,C953,C954,C955,C956,C963,C964,C965,C966,C981,C982,C983,C984,C999,C1000,C1001,C1002,C1077,C1078,C1079,C1080,C1087,C1088,C1089,C1090,C1105,C1106,C1107,C1108,C1123,C1124,C1125,C1126,C1201,C1202,C1203,C1204,C1211,C1212,C1213,C1214,C1229,C1230,C1231,C1232,C1247,C1248,C1249,C1250,C1325,C1326,C1327,C1328,C1335,C1336,C1337,C1338,C1353,C1354,C1355,C1356,C1371,C1372,C1373,C1374 | 130 | 620135Y00-015-G | CAP,2.2uF,+/-20%,X6S,10V,G,SMD0402 | MURATA ELEC. NORTH AMERICA | GRM155C81A225ME15D |  | PWA BOM | In Old BOM |
|  |  |  | 620135Y00-012-G | CAP,2.2uF,+/-20%,X6S,10V,G,SMD0402 | WALSIN | 0402S225M100CT | G | PWA BOM | In Old BOM |
| 9 | PUAC3,PSAC3,PRAC3,PQAC3,PPAC3,PIAC3,PFAC3,PEAC3,C1420,C1421,C1653,C1654,C2146 | 13 | 620102S00-015-G | CAP,33pF,+/-5%,NPO(C0G),50V,G,SMD0402 | MURATA ELEC. NORTH AMERICA | GRM1555C1H330J | G | PWA BOM | In New BOM |
|  |  |  | 620102S06-012-G | CAP,33pF,+/-5%,NPO(C0G),50V,G,SMD0402 | WALSIN TECHNOLOGY CORPORATION | 0402N330J500CT | G | PWA BOM | In New BOM |
|  |  |  | 620102S00-023-G | CAP,33pF,+/-5%,NPO(C0G),50V,G,SMD0402 | TAIYO ELECTRIC IND.CO.LTD | UMK105CG330JV-F | G | PWA BOM | In New BOM |
|  |  |  | 620102S00-026-G | CAP,33pF,+/-5%,NPO(C0G),50V,G,SMD0402 | SAMSUNG SEMICONDUCTOR | CL05C330JB5NNNC | G | PWA BOM | In New BOM |
|  | PUAC3,PSAC3,PRAC3,PQAC3,PPAC3,PIAC3,PFAC3,PEAC3,C1420,C1421,C1653,C1654,C2146 | 13 | 620102S00-015-G | CAP,33pF,+/-5%,NPO(C0G),50V,G,SMD0402 | MURATA ELEC. NORTH AMERICA | GRM1555C1H330J | Y | PWA BOM | In Old BOM |
|  |  |  | 620102S06-012-G | CAP,33pF,+/-5%,NPO(C0G),50V,G,SMD0402 | WALSIN | 0402N330J500CT | G | PWA BOM | In Old BOM |
|  |  |  | 620102S00-023-G | CAP,33pF,+/-5%,NPO(C0G),50V,G,SMD0402 | TAIYO ELECTRIC IND.CO.LTD | UMK105CG330JV-F | G | PWA BOM | In Old BOM |
|  |  |  | 620102S00-026-G | CAP,33pF,+/-5%,NPO(C0G),50V,G,SMD0402 | SAMSUNG SEMICONDUCTOR | CL05C330JB5NNNC | G | PWA BOM | In Old BOM |
| 10 | C1458,C1463,C1486,C1489,C1492,C1774,C1775,C1793,C1795,C1839,C1840,C1883,C1885,C1938,C1939,C1950,C1976 | 17 | 620115801-015-G | CAP,22uF,+/-10%,X7R,10V,G,SMD1206 | MURATA ELEC. NORTH AMERICA | GRM31CR71A226KE15L | G | PWA BOM | In New BOM |
|  |  |  | 620115800-023-G | CAP,22uF,+/-10%,X7R,10V,G,SMD1206 | TAIYO ELECTRIC IND.CO.LTD | LMK316B7226KL-TR | G | PWA BOM | In New BOM |
|  |  |  | 620115800-026-G | CAP,22uF,+/-10%,X7R,10V,G,SMD1206 | SAMSUNG SEMICONDUCTOR | CL31B226KPHNNNE | G | PWA BOM | In New BOM |
|  | C1458,C1463,C1486,C1489,C1492,C1774,C1775,C1793,C1795,C1839,C1840,C1883,C1885,C1938,C1939,C1950,C1976 | 17 | 620115801-015-G | CAP,22uF,+/-10%,X7R,10V,G,SMD1206 | MURATA ELEC. NORTH AMERICA | GRM31CR71A226KE15L |  | PWA BOM | In Old BOM |
|  |  |  | 620115800-023-G | CAP,22uF,+/-10%,X7R,10V,G,SMD1206 | TAIYO ELECTRIC IND.CO.LTD | LMK316B7226KL-TR | G | PWA BOM | In Old BOM |
|  |  |  | 620115800-026-G | CAP,22uF,+/-10%,X7R,10V,G,SMD1206 | SAMSUNG | CL31B226KPHNNNE | G | PWA BOM | In Old BOM |
| 11 | PSPC4,PIPC4,PFPC4,PEPC4,PSRC9,PBNC12,PANC12,PSLC14,PSFC14,PSEC14,PSDC14,PEEC14,PEDC14,PBNC14,PANC14,PSIC20,PETC20,PERC20,C1473,C1474,C1554,C1559,C1565,C1567,C2041,C2114 | 26 | 620108000-015-G | CAP,100pF,+/-5%,NPO(C0G),50V,G,SMD0402 | MURATA ELEC. NORTH AMERICA | GRM1555C1H101J | G | PWA BOM | In New BOM |
|  |  |  | 62010800A-012-G | CAP,100pF,+/-5%,NPO(C0G),50V,G,SMD0402 | WALSIN TECHNOLOGY CORPORATION | 0402N101J500CT | G | PWA BOM | In New BOM |
|  |  |  | 620108000-026-G | CAP,100pF,+/-5%,NPO(C0G),50V,G,SMD0402 | SAMSUNG SEMICONDUCTOR | CL05C101JB5NNNC | G | PWA BOM | In New BOM |
|  |  |  | 620108000-023-G | CAP,100pF,+/-5%,NPO(C0G),50V,G,SMD0402 | TAIYO ELECTRIC IND.CO.LTD | UMK105CG101JV-F | G | PWA BOM | In New BOM |
|  | PSPC4,PIPC4,PFPC4,PEPC4,PSRC9,PBNC12,PANC12,PSLC14,PSFC14,PSEC14,PSDC14,PEEC14,PEDC14,PBNC14,PANC14,PSIC20,PETC20,PERC20,C1473,C1474,C1554,C1559,C1565,C1567,C2041,C2114 | 26 | 620108000-015-G | CAP,100pF,+/-5%,NPO(C0G),50V,G,SMD0402 | MURATA ELEC. NORTH AMERICA | GRM1555C1H101J | Y | PWA BOM | In Old BOM |
|  |  |  | 62010800A-012-G | CAP,100pF,+/-5%,NPO(C0G),50V,G,SMD0402 | WALSIN | 0402N101J500CT | G | PWA BOM | In Old BOM |
|  |  |  | 620108000-026-G | CAP,100pF,+/-5%,NPO(C0G),50V,G,SMD0402 | SAMSUNG SEMICONDUCTOR | CL05C101JB5NNNC | G | PWA BOM | In Old BOM |
|  |  |  | 620108000-023-G | CAP,100pF,+/-5%,NPO(C0G),50V,G,SMD0402 | TAIYO ELECTRIC IND.CO.LTD | UMK105CG101JV-F | G | PWA BOM | In Old BOM |
| 12 | C1502,C1592,C1598,C1601,C1604,C1607 | 6 | 62010MF00-015-G | CAP,100pF,+/-10%,X7R,16V,G,SMD0201 | MURATA ELEC. NORTH AMERICA | GRM033R71C101K | G | PWA BOM | In New BOM |
|  |  |  | 62010MF00-012-G | CAP,100pF,+/-10%,X7R,16V,G,SMD0201 | WALSIN TECHNOLOGY CORPORATION | 0201B101K160CT | G | PWA BOM | In New BOM |
|  | C1502,C1592,C1598,C1601,C1604,C1607 | 6 | 62010MF00-015-G | CAP,100pF,+/-10%,X7R,16V,G,SMD0201 | MURATA ELEC. NORTH AMERICA | GRM033R71C101K |  | PWA BOM | In Old BOM |
|  |  |  | 62010MF00-012-G | CAP,100pF,+/-10%,X7R,16V,G,SMD0201 | WALSIN | 0201B101K160CT | G | PWA BOM | In Old BOM |
| 13 | PSIC7,C1541,C1679,C1680,C1681,C1682,C1684,C1685,C1686,C1688,C1704,C1710,C2069 | 13 | 62010QB00-015-G | CAP,10nF,+/-10%,X7R,50V,G,SMD0402 | MURATA ELEC. NORTH AMERICA | GRM155R71H103K | G | PWA BOM | In New BOM |
|  |  |  | 62010QB00-012-G | CAP,10nF,+/-10%,X7R,50V,G,SMD0402 | WALSIN TECHNOLOGY CORPORATION | 0402B103K500CT | G | PWA BOM | In New BOM |
|  |  |  | 62010QB00-026-G | CAP,10nF,+/-10%,X7R,50V,G,SMD0402 | SAMSUNG SEMICONDUCTOR | CL05B103KB5NNNC | G | PWA BOM | In New BOM |
|  |  |  | 62010QB00-023-G | CAP,10nF,+/-10%,X7R,50V,G,SMD0402 | TAIYO ELECTRIC IND.CO.LTD | UMK105B7103KV-F | G | PWA BOM | In New BOM |
|  | PSIC7,C1541,C1679,C1680,C1681,C1682,C1684,C1685,C1686,C1688,C1704,C1710,C2069 | 13 | 62010QB00-015-G | CAP,10nF,+/-10%,X7R,50V,G,SMD0402 | MURATA ELEC. NORTH AMERICA | GRM155R71H103K | N | PWA BOM | In Old BOM |
|  |  |  | 62010QB00-012-G | CAP,10nF,+/-10%,X7R,50V,G,SMD0402 | WALSIN | 0402B103K500CT | G | PWA BOM | In Old BOM |
|  |  |  | 62010QB00-026-G | CAP,10nF,+/-10%,X7R,50V,G,SMD0402 | SAMSUNG SEMICONDUCTOR | CL05B103KB5NNNC | G | PWA BOM | In Old BOM |
|  |  |  | 62010QB00-023-G | CAP,10nF,+/-10%,X7R,50V,G,SMD0402 | TAIYO ELECTRIC IND.CO.LTD | UMK105B7103KV-F | G | PWA BOM | In Old BOM |
| 14 | C1542,C1555,C1560,C1564,C1566 | 5 | 62010GW00-015-G | CAP,10pF,+/-5%,NPO,50V,G,SMD0402 | MURATA ELEC. NORTH AMERICA | GRM1555C1H100J | G | PWA BOM | In New BOM |
|  |  |  | 620102D05-012-G | CAP,10pF,+/-5%,NPO,50V,G,SMD0402 | WALSIN TECHNOLOGY CORPORATION | 0402N100J500CT | G | PWA BOM | In New BOM |
|  |  |  | 620102D00-026-G | CAP,10pF,+/-5%,NPO(C0G),50V,G,SMD0402 | SAMSUNG SEMICONDUCTOR | CL05C100JB5NNNC | G | PWA BOM | In New BOM |
|  | C1542,C1555,C1560,C1564,C1566 | 5 | 62010GW00-015-G | CAP,10pF,+/-5%,NPO,50V,G,SMD0402 | MURATA ELEC. NORTH AMERICA | GRM1555C1H100J | N | PWA BOM | In Old BOM |
|  |  |  | 620102D05-012-G | CAP,10pF,+/-5%,NPO,50V,G,SMD0402 | WALSIN | 0402N100J500CT | G | PWA BOM | In Old BOM |
|  |  |  | 620102D00-026-G | CAP,10pF,+/-5%,NPO(C0G),50V,G,SMD0402 | SAMSUNG SEMICONDUCTOR | CL05C100JB5NNNC | G | PWA BOM | In Old BOM |
| 15 | C1546,C1547,C1548,C1549,C1550,C1551,C1655,C1656 | 8 | 62010K200-015-G | CAP,12pF,+/-5%,NPO(C0G),50V,G,SMD0402 | MURATA ELEC. NORTH AMERICA | GRM1555C1H120J | G | PWA BOM | In New BOM |
|  |  |  | 62010K207-012-G | CAP,12pF,+/-5%,NPO(C0G),50V,G,SMD0402 | WALSIN TECHNOLOGY CORPORATION | 0402N120J500CT | G | PWA BOM | In New BOM |
|  |  |  | 62010K200-023-G | CAP,12pF,+/-5%,NPO(C0G),50V,G,SMD0402 | TAIYO ELECTRIC IND.CO.LTD | UMK105CG120JV-F | G | PWA BOM | In New BOM |
|  |  |  | 62010K200-026-G | CAP,12pF,+/-5%,NPO(C0G),50V,G,SMD0402 | SAMSUNG SEMICONDUCTOR | CL05C120JB5NNNC | G | PWA BOM | In New BOM |
|  | C1546,C1547,C1548,C1549,C1550,C1551,C1655,C1656 | 8 | 62010K200-015-G | CAP,12pF,+/-5%,NPO(C0G),50V,G,SMD0402 | MURATA ELEC. NORTH AMERICA | GRM1555C1H120J | N | PWA BOM | In Old BOM |
|  |  |  | 62010K207-012-G | CAP,12pF,+/-5%,NPO(C0G),50V,G,SMD0402 | WALSIN | 0402N120J500CT | G | PWA BOM | In Old BOM |
|  |  |  | 62010K200-023-G | CAP,12pF,+/-5%,NPO(C0G),50V,G,SMD0402 | TAIYO ELECTRIC IND.CO.LTD | UMK105CG120JV-F | G | PWA BOM | In Old BOM |
|  |  |  | 62010K200-026-G | CAP,12pF,+/-5%,NPO(C0G),50V,G,SMD0402 | SAMSUNG SEMICONDUCTOR | CL05C120JB5NNNC | G | PWA BOM | In Old BOM |
| 16 | C1657,C1658,C1659,C1660,C1661,C1662,C1663,C1664,C1665,C1666,C1668,C1669 | 12 | 620100L00-015-G | CAP,22pF,+/-5%,NPO(C0G),50V,G,SMD0402 | MURATA ELEC. NORTH AMERICA | GRM1555C1H220J | G | PWA BOM | In New BOM |
|  |  |  | 620100L08-012-G | CAP,22pF,+/-5%,NPO(C0G),50V,G,SMD0402 | WALSIN TECHNOLOGY CORPORATION | 0402N220J500CT | G | PWA BOM | In New BOM |
|  |  |  | 620100L00-023-G | CAP,22pF,+/-5%,NPO(C0G),50V,G,SMD0402 | TAIYO ELECTRIC IND.CO.LTD | UMK105CG220JV-F | G | PWA BOM | In New BOM |
|  |  |  | 620100L00-026-G | CAP,22pF,+/-5%,NPO(C0G),50V,G,SMD0402 | SAMSUNG SEMICONDUCTOR | CL05C220JB5NNNC | G | PWA BOM | In New BOM |
|  | C1657,C1658,C1659,C1660,C1661,C1662,C1663,C1664,C1665,C1666,C1668,C1669 | 12 | 620100L00-015-G | CAP,22pF,+/-5%,NPO(C0G),50V,G,SMD0402 | MURATA ELEC. NORTH AMERICA | GRM1555C1H220J | Y | PWA BOM | In Old BOM |
|  |  |  | 620100L08-012-G | CAP,22pF,+/-5%,NPO(C0G),50V,G,SMD0402 | WALSIN | 0402N220J500CT | G | PWA BOM | In Old BOM |
|  |  |  | 620100L00-023-G | CAP,22pF,+/-5%,NPO(C0G),50V,G,SMD0402 | TAIYO ELECTRIC IND.CO.LTD | UMK105CG220JV-F | G | PWA BOM | In Old BOM |
|  |  |  | 620100L00-026-G | CAP,22pF,+/-5%,NPO(C0G),50V,G,SMD0402 | SAMSUNG SEMICONDUCTOR | CL05C220JB5NNNC | G | PWA BOM | In Old BOM |
| 17 | PSTC1,PSLC1,PSFC1,PSEC1,PSDC1,PQPC1,PFRC1,PEEC1,PEDC1,PSUC3,PSTC6,PSLC6,PSFC6,PSEC6,PSDC6,PQPC6,PFRC6,PEEC6,PEDC6,PANC6,PBNC7,PBMC10,PBFC10,PBEC10,PBAC10,PAMC10,PAFC10,PAEC10,PAAC10,PSIC21,PETC21,PERC21,PBFC58,PBEC58,PAFC58,PAEC58,PBMC59,PAMC59,PBAC123,PAAC123,C1689,C1695,C1696,C1697,C1698,C1705,C1711,C1770,C1771,C1772,C1773,C1776,C1777,C1779,C1810,C1816,C1817,C1818,C1857,C1863,C1864,C1865,C1900,C1906,C1907,C1908,C1934,C1935,C1936,C1937,C1944,C1945,C1971,C1972,C1973,C2030,C2031,PSPC3002,PIPC3002,PFPC3002,PEPC3002,PSRC3006,PSPC3008,PIPC3008,PFPC3008,PEPC3008,PSRC3009,PSRC3011 | 88 | 62012A400-015-G | CAP,100nF,+/-10%,X7R,25V,G,SMD0402 | MURATA ELEC. NORTH AMERICA | GRM155R71E104KE14D | G | PWA BOM | In New BOM |
|  |  |  | 62012A400-023-G | CAP,100nF,+/-10%,X7R,25V,G,SMD0402 | TAIYO ELECTRIC IND.CO.LTD | TMK105B7104KV-FR | G | PWA BOM | In New BOM |
|  |  |  | 62012A400-026-G | CAP,100nF,+/-10%,X7R,25V,G,SMD0402 | SAMSUNG SEMICONDUCTOR | CL05B104KA5NNNC | G | PWA BOM | In New BOM |
|  |  |  | 62012A400-012-G | CAP,100nF,+/-10%,X7R,25V,G,SMD0402 | WALSIN TECHNOLOGY CORPORATION | 0402B104K250CT | G | PWA BOM | In New BOM |
|  | PSTC1,PSLC1,PSFC1,PSEC1,PSDC1,PQPC1,PFRC1,PEEC1,PEDC1,PSUC3,PSTC6,PSLC6,PSFC6,PSEC6,PSDC6,PQPC6,PFRC6,PEEC6,PEDC6,PANC6,PBNC7,PBMC10,PBFC10,PBEC10,PBAC10,PAMC10,PAFC10,PAEC10,PAAC10,PSIC21,PETC21,PERC21,PBFC58,PBEC58,PAFC58,PAEC58,PBMC59,PAMC59,PBAC123,PAAC123,C1689,C1695,C1696,C1697,C1698,C1705,C1711,C1770,C1771,C1772,C1773,C1776,C1777,C1779,C1810,C1816,C1817,C1818,C1857,C1863,C1864,C1865,C1900,C1906,C1907,C1908,C1934,C1935,C1936,C1937,C1944,C1945,C1971,C1972,C1973,C2030,C2031,PSPC3002,PIPC3002,PFPC3002,PEPC3002,PSRC3006,PSPC3008,PIPC3008,PFPC3008,PEPC3008,PSRC3009,PSRC3011 | 88 | 62012A400-015-G | CAP,100nF,+/-10%,X7R,25V,G,SMD0402 | MURATA ELEC. NORTH AMERICA | GRM155R71E104KE14D | N | PWA BOM | In Old BOM |
|  |  |  | 62012A400-023-G | CAP,100nF,+/-10%,X7R,25V,G,SMD0402 | TAIYO ELECTRIC IND.CO.LTD | TMK105B7104KV-FR | G | PWA BOM | In Old BOM |
|  |  |  | 62012A400-026-G | CAP,100nF,+/-10%,X7R,25V,G,SMD0402 | SAMSUNG SEMICONDUCTOR | CL05B104KA5NNNC | G | PWA BOM | In Old BOM |
|  |  |  | 62012A400-012-G | CAP,100nF,+/-10%,X7R,25V,G,SMD0402 | WALSIN | 0402B104K250CT | G | PWA BOM | In Old BOM |
| 18 | PHAC2,PUAC7,PSAC7,PRAC7,PQAC7,PPAC7,PIAC7,PFAC7,PEAC7,PBMC60,PAMC60,PBAC124,PAAC124,C1690,C1706,C1712 | 16 | 620103K00-015-G | CAP,1nF,+/-10%,X7R,50V,G,SMD0402 | MURATA ELEC. NORTH AMERICA | GRM155R71H102K | G | PWA BOM | In New BOM |
|  |  |  | 620103K00-012-G | CAP,1nF,+/-10%,X7R,50V,G,SMD0402 | WALSIN TECHNOLOGY CORPORATION | 0402B102K500CT | G | PWA BOM | In New BOM |
|  |  |  | 620103K00-026-G | CAP,1nF,+/-10%,X7R,50V,G,SMD0402 | SAMSUNG SEMICONDUCTOR | CL05B102KB5NNNC | G | PWA BOM | In New BOM |
|  |  |  | 620103K00-023-G | CAP,1nF,+/-10%,X7R,50V,G,SMD0402 | TAIYO ELECTRIC IND.CO.LTD | UMK105B7102KV-F | G | PWA BOM | In New BOM |
|  | PHAC2,PUAC7,PSAC7,PRAC7,PQAC7,PPAC7,PIAC7,PFAC7,PEAC7,PBMC60,PAMC60,PBAC124,PAAC124,C1690,C1706,C1712 | 16 | 620103K00-015-G | CAP,1nF,+/-10%,X7R,50V,G,SMD0402 | MURATA ELEC. NORTH AMERICA | GRM155R71H102K | N | PWA BOM | In Old BOM |
|  |  |  | 620103K00-012-G | CAP,1nF,+/-10%,X7R,50V,G,SMD0402 | WALSIN | 0402B102K500CT | G | PWA BOM | In Old BOM |
|  |  |  | 620103K00-026-G | CAP,1nF,+/-10%,X7R,50V,G,SMD0402 | SAMSUNG SEMICONDUCTOR | CL05B102KB5NNNC | G | PWA BOM | In Old BOM |
|  |  |  | 620103K00-023-G | CAP,1nF,+/-10%,X7R,50V,G,SMD0402 | TAIYO ELECTRIC IND.CO.LTD | UMK105B7102KV-F | G | PWA BOM | In Old BOM |
| 19 | C1707,C1708 | 2 | 620107600-015-G | CAP,27pF,+/-5%,NPO(C0G),50V,G,SMD0402 | MURATA ELEC. NORTH AMERICA | GRM1555C1H270J | G | PWA BOM | In New BOM |
|  |  |  | 620107600-011-G | CAP,27pF,+/-5%,NPO(C0G),50V,G,SMD0402 | YAGEO CORPORATION COMPONENT | CC0402JRNPO9BN270 | G | PWA BOM | In New BOM |
|  |  |  | 620107600-012-G | CAP,27pF,+/-5%,NPO(C0G),50V,G,SMD0402 | WALSIN TECHNOLOGY CORPORATION | 0402N270J500LT | G | PWA BOM | In New BOM |
|  |  |  | 620107600-023-G | CAP,27pF,+/-5%,NPO(C0G),50V,G,SMD0402 | TAIYO ELECTRIC IND.CO.LTD | UMK105CG270JV-F | G | PWA BOM | In New BOM |
|  |  |  | 620107600-025-G | CAP,27pF,+/-5%,NPO(C0G),50V,G,SMD0402 | KEMET ELECTRONICS CORPORATION | C0402C270J5GAC | G | PWA BOM | In New BOM |
|  |  |  | 620107600-026-G | CAP,27pF,+/-5%,NPO(C0G),50V,G,SMD0402 | SAMSUNG SEMICONDUCTOR | CL05C270JB5NNNC | G | PWA BOM | In New BOM |
|  |  |  | 620107602-012-G | CAP,27pF,+/-5%,NPO(C0G),50V,G,SMD0402 | WALSIN TECHNOLOGY CORPORATION | 0402N270J500CT | G | PWA BOM | In New BOM |
|  | C1707,C1708 | 2 | 620107600-015-G | CAP,27pF,+/-5%,NPO(C0G),50V,G,SMD0402 | MURATA ELEC. NORTH AMERICA | GRM1555C1H270J | N | PWA BOM | In Old BOM |
|  |  |  | 620107600-011-G | CAP,27pF,+/-5%,NPO(C0G),50V,G,SMD0402 | YAGEO | CC0402JRNPO9BN270 | G | PWA BOM | In Old BOM |
|  |  |  | 620107600-012-G | CAP,27pF,+/-5%,NPO(C0G),50V,G,SMD0402 | WALSIN | 0402N270J500LT | G | PWA BOM | In Old BOM |
|  |  |  | 620107600-023-G | CAP,27pF,+/-5%,NPO(C0G),50V,G,SMD0402 | TAIYO | UMK105CG270JV-F | G | PWA BOM | In Old BOM |
|  |  |  | 620107600-025-G | CAP,27pF,+/-5%,NPO(C0G),50V,G,SMD0402 | KEMET ELECTRONICS CORPORATION | C0402C270J5GAC | G | PWA BOM | In Old BOM |
|  |  |  | 620107600-026-G | CAP,27pF,+/-5%,NPO(C0G),50V,G,SMD0402 | SAMSUNG | CL05C270JB5NNNC | G | PWA BOM | In Old BOM |
|  |  |  | 620107602-012-G | CAP,27pF,+/-5%,NPO(C0G),50V,G,SMD0402 | WALSIN | 0402N270J500CT | G | PWA BOM | In Old BOM |
| 20 | C1734,C1735,C1736,C1739 | 4 | 620112900-015-G | CAP,47nF,+/-10%,X7R,25V,G,SMD0402 | MURATA ELEC. NORTH AMERICA | GRM155R71E473K | G | PWA BOM | In New BOM |
|  |  |  | 620112900-012-G | CAP,47nF,+/-10%,X7R,25V,G,SMD0402 | WALSIN TECHNOLOGY CORPORATION | 0402B473K250CT | G | PWA BOM | In New BOM |
|  | C1734,C1735,C1736,C1739 | 4 | 620112900-015-G | CAP,47nF,+/-10%,X7R,25V,G,SMD0402 | MURATA ELEC. NORTH AMERICA | GRM155R71E473K | N | PWA BOM | In Old BOM |
|  |  |  | 620112900-012-G | CAP,47nF,+/-10%,X7R,25V,G,SMD0402 | WALSIN | 0402B473K250CT | G | PWA BOM | In Old BOM |
| 21 | PBMC3,PBFC3,PBEC3,PBAC3,PAMC3,PAFC3,PAEC3,PAAC3,PALC42,PALC43,PBLC58,PBLC59,C1737,C1741 | 14 | 620103U00-015-G | CAP,470pF,+/-10%,X7R,50V,G,SMD0402 | MURATA ELEC. NORTH AMERICA | GRM155R71H471K | G | PWA BOM | In New BOM |
|  |  |  | 620103U00-012-G | CAP,470pF,+/-10%,X7R,50V,G,SMD0402 | WALSIN TECHNOLOGY CORPORATION | 0402B471K500CT | G | PWA BOM | In New BOM |
|  |  |  | 620103U00-026-G | CAP,470pF,+/-10%,X7R,50V,G,SMD0402 | SAMSUNG SEMICONDUCTOR | CL05B471KB5NNNC | G | PWA BOM | In New BOM |
|  |  |  | 620103U00-023-G | CAP,470pF,+/-10%,X7R,50V,G,SMD0402 | TAIYO ELECTRIC IND.CO.LTD | UMK105B7471KV-F | G | PWA BOM | In New BOM |
|  | PBMC3,PBFC3,PBEC3,PBAC3,PAMC3,PAFC3,PAEC3,PAAC3,PALC42,PALC43,PBLC58,PBLC59,C1737,C1741 | 14 | 620103U00-015-G | CAP,470pF,+/-10%,X7R,50V,G,SMD0402 | MURATA ELEC. NORTH AMERICA | GRM155R71H471K | Y | PWA BOM | In Old BOM |
|  |  |  | 620103U00-012-G | CAP,470pF,+/-10%,X7R,50V,G,SMD0402 | WALSIN | 0402B471K500CT | G | PWA BOM | In Old BOM |
|  |  |  | 620103U00-026-G | CAP,470pF,+/-10%,X7R,50V,G,SMD0402 | SAMSUNG SEMICONDUCTOR | CL05B471KB5NNNC | G | PWA BOM | In Old BOM |
|  |  |  | 620103U00-023-G | CAP,470pF,+/-10%,X7R,50V,G,SMD0402 | TAIYO ELECTRIC IND.CO.LTD | UMK105B7471KV-F | G | PWA BOM | In Old BOM |
| 22 | C2008,C2010 | 2 | 620108100-015-G | CAP,15pF,+/-5%,NPO(C0G),50V,G,SMD0402 | MURATA ELEC. NORTH AMERICA | GRM1555C1H150J | G | PWA BOM | In New BOM |
|  |  |  | 620108100-011-G | CAP,15pF,+/-5%,NPO(C0G),50V,G,SMD0402 | YAGEO CORPORATION COMPONENT | CC0402JRNPO9BN150 | G | PWA BOM | In New BOM |
|  |  |  | 620108100-012-G | CAP,15pF,+/-5%,NPO(C0G),50V,G,SMD0402 | WALSIN TECHNOLOGY CORPORATION | 0402N150J500LT | G | PWA BOM | In New BOM |
|  |  |  | 620108100-023-G | CAP,15pF,+/-5%,NPO(C0G),50V,G,SMD0402 | TAIYO ELECTRIC IND.CO.LTD | UMK105CG150JV-F | G | PWA BOM | In New BOM |
|  |  |  | 620108100-025-G | CAP,15pF,+/-5%,NPO(C0G),50V,G,SMD0402 | KEMET ELECTRONICS CORPORATION | C0402C150J5GAC | G | PWA BOM | In New BOM |
|  |  |  | 620108100-026-G | CAP,15pF,+/-5%,NPO(C0G),50V,G,SMD0402 | SAMSUNG SEMICONDUCTOR | CL05C150JB5NNNC | G | PWA BOM | In New BOM |
|  | C2008,C2010 | 2 | 620108100-015-G | CAP,15pF,+/-5%,NPO(C0G),50V,G,SMD0402 | MURATA ELEC. NORTH AMERICA | GRM1555C1H150J | N | PWA BOM | In Old BOM |
|  |  |  | 620108100-011-G | CAP,15pF,+/-5%,NPO(C0G),50V,G,SMD0402 | YAGEO | CC0402JRNPO9BN150 | G | PWA BOM | In Old BOM |
|  |  |  | 620108100-012-G | CAP,15pF,+/-5%,NPO(C0G),50V,G,SMD0402 | WALSIN | 0402N150J500LT | G | PWA BOM | In Old BOM |
|  |  |  | 620108100-023-G | CAP,15pF,+/-5%,NPO(C0G),50V,G,SMD0402 | TAIYO | UMK105CG150JV-F | G | PWA BOM | In Old BOM |
|  |  |  | 620108100-025-G | CAP,15pF,+/-5%,NPO(C0G),50V,G,SMD0402 | KEMET ELECTRONICS CORPORATION | C0402C150J5GAC | G | PWA BOM | In Old BOM |
|  |  |  | 620108100-026-G | CAP,15pF,+/-5%,NPO(C0G),50V,G,SMD0402 | SAMSUNG | CL05C150JB5NNNC | G | PWA BOM | In Old BOM |
| 23 | PHAC4,C2063,C2129 | 3 | 62010G800-015-G | CAP,22nF,+/-10%,X7R,16V,G,SMD0402 | MURATA ELEC. NORTH AMERICA | GRM155R71C223K | G | PWA BOM | In New BOM |
|  |  |  | 62010G800-012-G | CAP,22nF,+/-10%,X7R,16V,G,SMD0402 | WALSIN TECHNOLOGY CORPORATION | 0402B223K160CT | G | PWA BOM | In New BOM |
|  |  |  | 62010G800-026-G | CAP,22nF,+/-10%,X7R,16V,G,SMD0402 | SAMSUNG SEMICONDUCTOR | CL05B223KO5NNNC | G | PWA BOM | In New BOM |
|  |  |  | 62010G800-023-G | CAP,22nF,+/-10%,X7R,16V,G,SMD0402 | TAIYO ELECTRIC IND.CO.LTD | EMK105B7223KV-F | G | PWA BOM | In New BOM |
|  | PHAC4,C2063,C2129 | 3 | 62010G800-015-G | CAP,22nF,+/-10%,X7R,16V,G,SMD0402 | MURATA ELEC. NORTH AMERICA | GRM155R71C223K | N | PWA BOM | In Old BOM |
|  |  |  | 62010G800-012-G | CAP,22nF,+/-10%,X7R,16V,G,SMD0402 | WALSIN | 0402B223K160CT | G | PWA BOM | In Old BOM |
|  |  |  | 62010G800-026-G | CAP,22nF,+/-10%,X7R,16V,G,SMD0402 | SAMSUNG SEMICONDUCTOR | CL05B223KO5NNNC | G | PWA BOM | In Old BOM |
|  |  |  | 62010G800-023-G | CAP,22nF,+/-10%,X7R,16V,G,SMD0402 | TAIYO ELECTRIC IND.CO.LTD | EMK105B7223KV-F | G | PWA BOM | In Old BOM |
| 24 | C2184,C2185 | 2 | 620108B00-015-G | CAP,120pF,+/-5%,NPO(C0G),50V,G,SMD0402 | MURATA ELEC. NORTH AMERICA | GRM1555C1H121J | G | PWA BOM | In New BOM |
|  |  |  | 620108B00-012-G | CAP,120pF,+/-5%,NPO(C0G),50V,G,SMD0402 | WALSIN TECHNOLOGY CORPORATION | 0402N121J500LT | G | PWA BOM | In New BOM |
|  |  |  | 620108B00-026-G | CAP,120pF,+/-5%,NPO(C0G),50V,G,SMD0402 | SAMSUNG SEMICONDUCTOR | CL05C121JB5NNNC | G | PWA BOM | In New BOM |
|  | C2184,C2185 | 2 | 620108B00-015-G | CAP,120pF,+/-5%,NPO(C0G),50V,G,SMD0402 | MURATA ELEC. NORTH AMERICA | GRM1555C1H121J | N | PWA BOM | In Old BOM |
|  |  |  | 620108B00-012-G | CAP,120pF,+/-5%,NPO(C0G),50V,G,SMD0402 | WALSIN | 0402N121J500LT | G | PWA BOM | In Old BOM |
|  |  |  | 620108B00-026-G | CAP,120pF,+/-5%,NPO(C0G),50V,G,SMD0402 | SAMSUNG | CL05C121JB5NNNC | G | PWA BOM | In Old BOM |
| 25 | PHAD6,D20,D21 | 3 | 520100200-237-G | DIODE,Switching,1N4148W-7-F,100V,0.15A,G,SOD123-2,SMD | DIODES INEORPORATION | 1N4148W-7-F | G | PWA BOM | In New BOM |
|  |  |  | 520102P00-031-G | DIODE,Switching,BAS16H,100V,0.5A,G,SOD123F-2,SMD | NXP SEMICONDUCTORS | BAS16H | G | PWA BOM | In New BOM |
|  | PHAD6,D20,D21 | 3 | 520100200-237-G | DIODE,Switching,1N4148W-7-F,100V,0.15A,G,SOD123-2,SMD | DIODES INEORPORATION | 1N4148W-7-F | N | PWA BOM | In Old BOM |
|  |  |  | 520102P00-031-G | DIODE,Switching,BAS16H,100V,0.5A,G,SOD123F-2,SMD | NXP SEMICONDUCTORS | BAS16H |  | PWA BOM | In Old BOM |
| 26 | D22,D23,D24,D25,D26,D27 | 6 | 520308A00-237-G | Diode,Schottky,B0530WS-7-F,30V,500mA,G,SOD-323-2,SMD | DIODES INCORPORATION | B0530WS-7-F | G | PWA BOM | In New BOM |
|  |  |  | 520309600-031-G | Diode,Schottky,PMEG3005AEA,30V,500mA,SOD-323,2P,G | NXP SEMICONDUCTORS | PMEG3005AEA | G | PWA BOM | In New BOM |
|  | D22,D23,D24,D25,D26,D27 | 6 | 520308A00-237-G | Diode,Schottky,B0530WS-7-F,30V,500mA,G,SOD-323-2,SMD | DIODES INCORPORATION | B0530WS-7-F | N | PWA BOM | In Old BOM |
|  |  |  | 520309600-031-G | Diode,Schottky,PMEG3005AEA,30V,500mA,SOD-323,2P,G | NXP | PMEG3005AEA | G | PWA BOM | In Old BOM |
| 27 | D33 | 1 | 520308D00-237-G | DIODE,Schottky Rectifier,1N5819HW-7-F,40V,1A,G,SOD123-2,SMD | DIODES INCORPORATION | 1N5819HW-7-F | G | PWA BOM | In New BOM |
|  |  |  | 52030P100-223-G | Diode,Schottky,MBR140SFT1G,40V,1A,SOD-123FL,2P,G | ON SEMICONDUCTOR CORP | MBR140SFT1G | G | PWA BOM | In New BOM |
|  |  |  | 520318S00-223-G | Diode,Schottky,MBR140SFT3G,40V,1A,G,SOD-123FL-2,SMD | ON SEMICONDUCTOR CORP | MBR140SFT3G | G | PWA BOM | In New BOM |
|  | D33 | 1 | 520308D00-237-G | DIODE,Schottky Rectifier,1N5819HW-7-F,40V,1A,G,SOD123-2,SMD | DIODES INCORPORATION | 1N5819HW-7-F | N | PWA BOM | In Old BOM |
|  |  |  | 520318S00-223-G | Diode,Schottky,MBR140SFT3G,40V,1A,G,SOD-123FL-2,SMD | ON SEMICONDUCTOR CORP | MBR140SFT3G | G | PWA BOM | In Old BOM |
|  |  |  | 52030P100-223-G | Diode,Schottky,MBR140SFT1G,40V,1A,SOD-123FL,2P,G | ON | MBR140SFT1G | G | PWA BOM | In Old BOM |
| 28 | D57 | 1 | 52030NP00-185-G | DIODE,Schottky,RB521S30,30V,200mA,G,SOD523-2,SMD | FAIRCHILD SEMICONDUCTOR CORP | RB521S30 | G | PWA BOM | In New BOM |
|  |  |  | 52030AG00-237-G | DIODE,Schottky,SDM20U30-7,30V,0.2A,G,SOD523-2,SMD | DIODES INCORPORATION | SDM20U30-7 | G | PWA BOM | In New BOM |
|  |  |  | 52030NP00-031-G | Diode,Schottky,RB521S30,30V,200mA,SOD-523,2P,G | NXP SEMICONDUCTORS | RB521S30 | G | PWA BOM | In New BOM |
|  | D57 | 1 | 52030NP00-185-G | DIODE,Schottky,RB521S30,30V,200mA,G,SOD523-2,SMD | FAIRCHILD SEMICONDUCTOR CORP | RB521S30 |  | PWA BOM | In Old BOM |
|  |  |  | 52030AG00-237-G | DIODE,Schottky,SDM20U30-7,30V,0.2A,G,SOD523-2,SMD | DIODES INCORPORATION | SDM20U30-7 | G | PWA BOM | In Old BOM |
|  |  |  | 52030NP00-031-G | Diode,Schottky,RB521S30,30V,200mA,SOD-523,2P,G | NXP | RB521S30 | G | PWA BOM | In Old BOM |
| 29 | FB1 | 1 | 720101900-015-G | FB,60 Ohm@100MHz,+/-25%,3A,25mOhm,G,SMD0805 | MURATA ELEC. NORTH AMERICA | BLM21PG600SN1D | G | PWA BOM | In New BOM |
|  |  |  | 720101900-026-G | FB,60 Ohm@100MHz,+/-25%,3A,25mOhm,G,SMD0805 | SAMSUNG SEMICONDUCTOR | CIC21P600NE | G | PWA BOM | In New BOM |
|  | FB1 | 1 | 720101900-015-G | FB,60 Ohm@100MHz,+/-25%,3A,25mOhm,G,SMD0805 | MURATA ELEC. NORTH AMERICA | BLM21PG600SN1D | N | PWA BOM | In Old BOM |
|  |  |  | 720101900-026-G | FB,60 Ohm@100MHz,+/-25%,3A,25mOhm,G,SMD0805 | SAMSUNG | CIC21P600NE | G | PWA BOM | In Old BOM |
| 30 | FL1,FL4,FL10 | 3 | 720406E00-015-G | Common Choke,90Ohm@100MHz,+/-25%,220mA,G,SMD0805 | MURATA ELEC. NORTH AMERICA | DLW21HN900HQ2L | G | PWA BOM | In New BOM |
|  |  |  | 720405D00-016-G | Common Choke,90 Ohm@100MHz,Type,200mA,G,SMD0805 | TDK ELECTRONICS EUROPE GMBH | ACM2012E-900-2P-T01 | G | PWA BOM | In New BOM |
|  |  |  | 720402300-129-G | Filter,Inductor type,Common Mode(CMODE),90Ohm@100MHz,Type,300mA,,SMD0805,G | MAG.LAYERS, SCIENTIFIC-TECHNICS (KUNSHAN) CO., LTD. | MCI-2012H-900 | G | PWA BOM | In New BOM |
|  | FL1,FL4,FL10 | 3 | 720406E00-015-G | Common Choke,90Ohm@100MHz,+/-25%,220mA,G,SMD0805 | MURATA ELEC. NORTH AMERICA | DLW21HN900HQ2L |  | PWA BOM | In Old BOM |
|  |  |  | 720405D00-016-G | Common Choke,90 Ohm@100MHz,Type,200mA,G,SMD0805 | TDK | ACM2012E-900-2P-T01 | G | PWA BOM | In Old BOM |
|  |  |  | 720402300-129-G | Filter,Inductor type,Common Mode(CMODE),90Ohm@100MHz,Type,300mA,,SMD0805,G | MagLayers | MCI-2012H-900 |  | PWA BOM | In Old BOM |
| 31 | FL2,FL3,FL5,FL6,FL7,FL8,FL9 | 7 | 720400201-015-G | Filter,Common Mode,90Ohm@100MHz,+/-25%,330mA,G,SMD0805 | MURATA ELEC. NORTH AMERICA | DLW21HN900SQ2L | G | PWA BOM | In New BOM |
|  |  |  | 720400M00-059-G | Common Choke,90 Ohm@100MHz,+/-25%,400mA,G,SMD0805 | TAI-TECH ADVANCED ELECTRONICS CO., LTD. | WCM2012F2SF-900T04 | G | PWA BOM | In New BOM |
|  |  |  | 720400800-016-G | Common Choke,90 Ohm@100MHz,+/-25%,400mA,190mOhm,2L,G,SMD0805 | TDK ELECTRONICS EUROPE GMBH | ACM2012-900-2P-T | G | PWA BOM | In New BOM |
|  |  |  | 720400200-129-G | Common Choke,90 Ohm@100MHz,+/-25%,400mA,190mOhm,2L,G,SMD0805 | MAG.LAYERS, SCIENTIFIC-TECHNICS (KUNSHAN) CO., LTD. | MCI-2012-900 | G | PWA BOM | In New BOM |
|  | FL2,FL3,FL5,FL6,FL7,FL8,FL9 | 7 | 720400201-015-G | Filter,Common Mode,90Ohm@100MHz,+/-25%,330mA,G,SMD0805 | MURATA ELEC. NORTH AMERICA | DLW21HN900SQ2L | N | PWA BOM | In Old BOM |
|  |  |  | 720400M00-059-G | Common Choke,90 Ohm@100MHz,+/-25%,400mA,G,SMD0805 | TAI-TECH ADVANCED ELECTRONICS CO., LTD. | WCM2012F2SF-900T04 | G | PWA BOM | In Old BOM |
|  |  |  | 720400800-016-G | Common Choke,90 Ohm@100MHz,+/-25%,400mA,190mOhm,2L,G,SMD0805 | TDK | ACM2012-900-2P-T | G | PWA BOM | In Old BOM |
|  |  |  | 720400200-129-G | Common Choke,90 Ohm@100MHz,+/-25%,400mA,190mOhm,2L,G,SMD0805 | Maglayers | MCI-2012-900 |  | PWA BOM | In Old BOM |
| 32 | FS4,FS9,FS12,FS15,FS16,FS21 | 6 | 730102701-086-G | Fuse,Fast acting,32V,7A,G,SMD1206 | LITTELFUSE FAR EAST PTE LTD | 0440007.WR | G | PWA BOM | In New BOM |
|  |  |  | 730102704-088-G | Fuse,Fast acting,32V,7A,SMD1206,G | COOPER BUSSMANN, INC. | CC12H7A-TR | G | PWA BOM | In New BOM |
|  | FS4,FS9,FS12,FS15,FS16,FS21 | 6 | 730102701-086-G | Fuse,Fast acting,32V,7A,G,SMD1206 | LITTELFUSE FAR EAST PTE LTD | 0440007.WR |  | PWA BOM | In Old BOM |
|  |  |  | 730102704-088-G | Fuse,Fast acting,32V,7A,SMD1206,G | Cooper Bussmann | CC12H7A-TR | G | PWA BOM | In Old BOM |
| 33 | LED11,LED12 | 2 | 52113AW00-289-G | LED,Green,LTL-42NGY8DH184P,5V,20mA,G,DIP-2 | LITE-ON TECHNOLOGY CORPORATION | LTL-42NGY8DH184P | G | PWA BOM | In New BOM |
|  |  |  | SSF-LXH303GD | LED,Green,SSF-LXH303GD,5V,20mA,G,DIP-2 | LUEMX INC,TAIWAN BRANCH | SSF-LXH303GD | G | PWA BOM | In New BOM |
|  | LED11,LED12 | 2 | 52113AW00-289-G | LED,Green,LTL-42NGY8DH184P,5V,20mA,G,DIP-2 | LITE-ON TECHNOLOGY CORPORATION | LTL-42NGY8DH184P |  | PWA BOM | In Old BOM |
|  |  |  | SSF-LXH303SUGD | LED,Green,LTL-42NGY8DH184P,5V,20mA,G,DIP-2 | Lumex | SSF-LXH303SUGD | G | PWA BOM | In Old BOM |
| 34 | LED13 | 1 | 52113B100-289-G | LED,Blue,LTL42TB6NH184P,5V,30mA,G,DIP-2 | LITE-ON TECHNOLOGY CORPORATION | LTL42TB6NH184P | G | PWA BOM | In New BOM |
|  |  |  | L-7104ADFX010-TW | LED,Blue,LTL42TB6NH184P,5V,30mA,G,DIP-2 | Kingbright | L-7104ADFX010-TW | G | PWA BOM | In New BOM |
|  | LED13 | 1 | 52113B100-289-G | LED,Blue,LTL42TB6NH184P,5V,30mA,G,DIP-2 | LITE-ON TECHNOLOGY CORPORATION | LTL42TB6NH184P |  | PWA BOM | In Old BOM |
|  |  |  | 52113GJ00-354-G | LED LAMP,LA140B-1/DBK-1-PF,Blue,700mcd@IF=20mA,470nm,5V,30mA,N/A,,DIP,2P,G | Ligitek Electronics Co., Ltd. | LA140B-1/DBK-1-PF | G | PWA BOM | In Old BOM |
|  |  |  | SSF-LXH303USBC | LED,SSF-LXH303USBC | LUMEX | SSF-LXH303USBC | G | PWA BOM | In Old BOM |
|  |  |  | L-7104ADFX010-TW | LED,Blue,LTL42TB6NH184P,5V,30mA,G,DIP-2 | Kingbright | L-7104ADFX010-TW | G | PWA BOM | In Old BOM |
| 35 | L2,L3,L4,L5,L6,L8,L9,L10,L11,L12,L13,L14,L15,L16 | 14 | 720108301-015-G | FB,600 Ohm@100MHz,+/-25%,500mA,350mOhm,G,SMD0603 | MURATA ELEC. NORTH AMERICA | BLM18EG601SN1D | G | PWA BOM | In New BOM |
|  |  |  | 720105E00-059-G | FB,600 Ohm@100MHz,+/-25%,500mA,400mOhm,G,SMD0603 | TAI-TECH ADVANCED ELECTRONICS CO., LTD. | FCM1608KF-601T05 | G | PWA BOM | In New BOM |
|  |  |  | 720105E00-016-G | FB,600 Ohm@100MHz,+/-25%,500mA,400mOhm,G,SMD0603 | TDK ELECTRONICS EUROPE GMBH | MMZ1608S601AT | G | PWA BOM | In New BOM |
|  | L2,L3,L4,L5,L6,L8,L9,L10,L11,L12,L13,L14,L15,L16 | 14 | 720108301-015-G | FB,600 Ohm@100MHz,+/-25%,500mA,350mOhm,G,SMD0603 | MURATA ELEC. NORTH AMERICA | BLM18EG601SN1D | N | PWA BOM | In Old BOM |
|  |  |  | 720105E00-059-G | FB,600 Ohm@100MHz,+/-25%,500mA,400mOhm,G,SMD0603 | TAI-TECH ADVANCED ELECTRONICS CO., LTD. | FCM1608KF-601T05 | G | PWA BOM | In Old BOM |
|  |  |  | 720105E00-016-G | FB,600 Ohm@100MHz,+/-25%,500mA,400mOhm,G,SMD0603 | TDK | MMZ1608S601AT | G | PWA BOM | In Old BOM |
| 36 | L7 | 1 | 630332000-053-G | IND,3.3uH@100KHz,+/-20%,2.57A,26mOhm,SHLD,G,SMD | TOKO INC. | #A916CY-3R3M=P3 | G | PWA BOM | In New BOM |
|  |  |  | 63035BF00-129-G | IND,3.3uH@100KHz,+/-20%,2.57A,26mOhm,SHLD,G,SMD | MAG.LAYERS, SCIENTIFIC-TECHNICS (KUNSHAN) CO., LTD. | MSCDRI-6035LC-3R3M-EH | G | PWA BOM | In New BOM |
|  | L7 | 1 | 630332000-053-G | IND,3.3uH@100KHz,+/-20%,2.57A,26mOhm,SHLD,G,SMD | TOKO INC. | #A916CY-3R3M=P3 |  | PWA BOM | In Old BOM |
|  |  |  | 63035BF00-129-G | IND,3.3uH@100KHz,+/-20%,2.57A,26mOhm,SHLD,G,SMD | MAG.LAYERS, SCIENTIFIC-TECHNICS (KUNSHAN) CO., LTD. | MSCDRI-6035LC-3R3M-EH |  | PWA BOM | In Old BOM |
| 37 | L17 | 1 | 720106E00-015-G | FB,330 Ohm@100MHz,+/-25%,500mA,300mOhm,G,SMD0603 | MURATA ELEC. NORTH AMERICA | BLM18EG331TN1D | G | PWA BOM | In New BOM |
|  |  |  | 72010YW01-129-G | FB,Multilayer,100mOhm,330Ohm@100MHz,+/-25%,2A,,SMD0603,G | MAG.LAYERS, SCIENTIFIC-TECHNICS (KUNSHAN) CO., LTD. | GMLB-160808-0330P-N8 | G | PWA BOM | In New BOM |
|  | L17 | 1 | 720106E00-015-G | FB,330 Ohm@100MHz,+/-25%,500mA,300mOhm,G,SMD0603 | MURATA ELEC. NORTH AMERICA | BLM18EG331TN1D | N | PWA BOM | In Old BOM |
|  |  |  | 72010B000-016-G | FB,Multilayer,300mOhm,300Ohm@100MHz,+/-25%,500mA,,SMD0603,G | TDK | MMZ1608S301AT | G | PWA BOM | In Old BOM |
|  |  |  | 72010YW01-129-G | FB,Multilayer,100mOhm,330Ohm@100MHz,+/-25%,2A,,SMD0603,G | MAG.LAYERS, SCIENTIFIC-TECHNICS (KUNSHAN) CO., LTD. | GMLB-160808-0330P-N8 | G | PWA BOM | In Old BOM |
| 38 | L22,L23,L24,L25 | 4 | 720105P00-016-G | FB,80 Ohm@100MHz,+/-25%,500mA,150mOhm,G,SMD0603 | TDK ELECTRONICS EUROPE GMBH | MMZ1608S800AT | G | PWA BOM | In New BOM |
|  |  |  | 72010WQ00-129-G | FB,80 Ohm@100MHz,+/-25%,3A,0.04Ohm,G,SMD0603 | MAG.LAYERS, SCIENTIFIC-TECHNICS (KUNSHAN) CO., LTD. | GMLB-160808-0080P-N8 | G | PWA BOM | In New BOM |
|  | L22,L23,L24,L25 | 4 | 720105P00-016-G | FB,80 Ohm@100MHz,+/-25%,500mA,150mOhm,G,SMD0603 | TDK ELECTRONICS EUROPE GMBH | MMZ1608S800AT | N | PWA BOM | In Old BOM |
|  |  |  | GMLB-160808-0080P-N8 | FB,80 Ohm@100MHz,+/-25%,500mA,150mOhm,G,SMD0603 | MAG.LAYERS, SCIENTIFIC-TECHNICS (KUNSHAN) CO., LTD. | GMLB-160808-0080P-N8 | G | PWA BOM | In Old BOM |
| 39 | L34,L36 | 2 | 72010A400-023-G | FB,80Ohm@100MHz,+/-25%,4A,10mOhm,G,SMD1206 | TAIYO ELECTRIC IND.CO.LTD | FBMJ3216HS800-T | G | PWA BOM | In New BOM |
|  |  |  | Z1206C800APWST | FB,80Ohm@100MHz,+/-25%,4A,10mOhm,G,SMD1206 | KEMET ELECTRONICS CORPORATION | Z1206C800APWST | G | PWA BOM | In New BOM |
|  | L34,L36 | 2 | 72010A400-023-G | FB,80Ohm@100MHz,+/-25%,4A,10mOhm,G,SMD1206 | TAIYO ELECTRIC IND.CO.LTD | FBMJ3216HS800-T | N | PWA BOM | In Old BOM |
|  |  |  | Z1206C800APWST | FB,80Ohm@100MHz,+/-25%,4A,10mOhm,G,SMD1206 | KEMET | Z1206C800APWST |  | PWA BOM | In Old BOM |
| 40 | PBAC4,PAAC4,PSPC11,PIPC11,PFPC11,PEPC11 | 6 | 62010FF00-015-G | CAP,47pF,+/-5%,NPO(C0G),50V,G,SMD0402 | MURATA ELEC. NORTH AMERICA | GRM1555C1H470J | G | PWA BOM | In New BOM |
|  |  |  | 62010FF06-012-G | CAP,47pF,+/-5%,NPO(C0G),50V,G,SMD0402 | WALSIN TECHNOLOGY CORPORATION | 0402N470J500CT | G | PWA BOM | In New BOM |
|  |  |  | 62010FF00-026-G | CAP,47pF,+/-5%,NPO(C0G),50V,G,SMD0402 | SAMSUNG SEMICONDUCTOR | CL05C470JB5NNNC | G | PWA BOM | In New BOM |
|  |  |  | 62010FF00-023-G | CAP,47pF,+/-5%,NPO(C0G),50V,G,SMD0402 | TAIYO ELECTRIC IND.CO.LTD | UMK105CG470JV-F | G | PWA BOM | In New BOM |
|  | PBAC4,PAAC4,PSPC11,PIPC11,PFPC11,PEPC11 | 6 | 62010FF00-015-G | CAP,47pF,+/-5%,NPO(C0G),50V,G,SMD0402 | MURATA ELEC. NORTH AMERICA | GRM1555C1H470J | Y | PWA BOM | In Old BOM |
|  |  |  | 62010FF06-012-G | CAP,47pF,+/-5%,NPO(C0G),50V,G,SMD0402 | WALSIN | 0402N470J500CT | G | PWA BOM | In Old BOM |
|  |  |  | 62010FF00-026-G | CAP,47pF,+/-5%,NPO(C0G),50V,G,SMD0402 | SAMSUNG SEMICONDUCTOR | CL05C470JB5NNNC | G | PWA BOM | In Old BOM |
|  |  |  | 62010FF00-023-G | CAP,47pF,+/-5%,NPO(C0G),50V,G,SMD0402 | TAIYO ELECTRIC IND.CO.LTD | UMK105CG470JV-F | G | PWA BOM | In Old BOM |
| 41 | PSPC5,PIPC5,PFPC5,PEPC5,PBMC5,PBAC5,PAMC5,PAAC5,PBAC23,PAAC23,PBMC95,PAMC95,PBFC451,PBEC451,PAFC451,PAEC451 | 16 | 62010L800-015-G | CAP,1nF,+/-5%,NPO(C0G),50V,G,SMD0402 | MURATA ELEC. NORTH AMERICA | GRM1555C1H102J | G | PWA BOM | In New BOM |
|  |  |  | 62010L800-012-G | CAP,1nF,+/-5%,NPO(C0G),50V,G,SMD0402 | WALSIN TECHNOLOGY CORPORATION | 0402N102J500CT | G | PWA BOM | In New BOM |
|  |  |  | 62010L800-026-G | CAP,1nF,+/-5%,NPO(C0G),50V,G,SMD0402 | SAMSUNG SEMICONDUCTOR | CL05C102JB5NNNC | G | PWA BOM | In New BOM |
|  | PSPC5,PIPC5,PFPC5,PEPC5,PBMC5,PBAC5,PAMC5,PAAC5,PBAC23,PAAC23,PBMC95,PAMC95,PBFC451,PBEC451,PAFC451,PAEC451 | 16 | 62010L800-015-G | CAP,1nF,+/-5%,NPO(C0G),50V,G,SMD0402 | MURATA ELEC. NORTH AMERICA | GRM1555C1H102J | N | PWA BOM | In Old BOM |
|  |  |  | 62010L800-012-G | CAP,1nF,+/-5%,NPO(C0G),50V,G,SMD0402 | WALSIN | 0402N102J500CT | G | PWA BOM | In Old BOM |
|  |  |  | 62010L800-026-G | CAP,1nF,+/-5%,NPO(C0G),50V,G,SMD0402 | SAMSUNG SEMICONDUCTOR | CL05C102JB5NNNC | G | PWA BOM | In Old BOM |
| 42 | PBMC7,PBFC7,PBEC7,PBAC7,PAMC7,PAFC7,PAEC7,PAAC7 | 8 | 620102T00-015-G | CAP,150pF,+/-5%,NPO(C0G),50V,G,SMD0402 | MURATA ELEC. NORTH AMERICA | GRM1555C1H151J | G | PWA BOM | In New BOM |
|  |  |  | 620102T00-012-G | CAP,150pF,+/-5%,NPO(C0G),50V,G,SMD0402 | WALSIN TECHNOLOGY CORPORATION | 0402N151J500LT | G | PWA BOM | In New BOM |
|  |  |  | 620102T00-026-G | CAP,150pF,+/-5%,NPO(C0G),50V,G,SMD0402 | SAMSUNG SEMICONDUCTOR | CL05C151JB5NNNC | G | PWA BOM | In New BOM |
|  |  |  | 620102T00-023-G | CAP,150pF,+/-5%,NPO(C0G),50V,G,SMD0402 | TAIYO ELECTRIC IND.CO.LTD | UMK105CG151JV-F | G | PWA BOM | In New BOM |
|  | PBMC7,PBFC7,PBEC7,PBAC7,PAMC7,PAFC7,PAEC7,PAAC7 | 8 | 620102T00-015-G | CAP,150pF,+/-5%,NPO(C0G),50V,G,SMD0402 | MURATA ELEC. NORTH AMERICA | GRM1555C1H151J | Y | PWA BOM | In Old BOM |
|  |  |  | 620102T00-012-G | CAP,150pF,+/-5%,NPO(C0G),50V,G,SMD0402 | WALSIN TECHNOLOGY CORPORATION | 0402N151J500LT |  | PWA BOM | In Old BOM |
|  |  |  | 620102T00-026-G | CAP,150pF,+/-5%,NPO(C0G),50V,G,SMD0402 | SAMSUNG SEMICONDUCTOR | CL05C151JB5NNNC |  | PWA BOM | In Old BOM |
|  |  |  | 620102T00-023-G | CAP,150pF,+/-5%,NPO(C0G),50V,G,SMD0402 | TAIYO ELECTRIC IND.CO.LTD | UMK105CG151JV-F |  | PWA BOM | In Old BOM |
| 43 | PSRC2,PSPC12,PIPC12,PFPC12,PEPC12,PSIC18,PETC18,PERC18,PBFC25,PBEC25,PAFC25,PBMC26,PBAC26,PAMC26,PAAC26,PAEC516 | 16 | 620107L00-015-G | CAP,2.2nF,+/-10%,X7R,50V,G,SMD0402 | MURATA ELEC. NORTH AMERICA | GRM155R71H222K | G | PWA BOM | In New BOM |
|  |  |  | 620107L00-012-G | CAP,2.2nF,+/-10%,X7R,50V,G,SMD0402 | WALSIN TECHNOLOGY CORPORATION | 0402B222K500CT | G | PWA BOM | In New BOM |
|  |  |  | 620107L00-026-G | CAP,2.2nF,+/-10%,X7R,50V,G,SMD0402 | SAMSUNG SEMICONDUCTOR | CL05B222KB5NNNC | G | PWA BOM | In New BOM |
|  |  |  | 620107L03-023-G | CAP,2.2nF,+/-10%,X7R,50V,G,SMD0402 | TAIYO ELECTRIC IND.CO.LTD | UMK105B7222KV-F | G | PWA BOM | In New BOM |
|  | PSRC2,PSPC12,PIPC12,PFPC12,PEPC12,PSIC18,PETC18,PERC18,PBFC25,PBEC25,PAFC25,PBMC26,PBAC26,PAMC26,PAAC26,PAEC516 | 16 | 620107L00-015-G | CAP,2.2nF,+/-10%,X7R,50V,G,SMD0402 | MURATA ELEC. NORTH AMERICA | GRM155R71H222K | N | PWA BOM | In Old BOM |
|  |  |  | 620107L00-012-G | CAP,2.2nF,+/-10%,X7R,50V,G,SMD0402 | WALSIN | 0402B222K500CT | G | PWA BOM | In Old BOM |
|  |  |  | 620107L00-026-G | CAP,2.2nF,+/-10%,X7R,50V,G,SMD0402 | SAMSUNG SEMICONDUCTOR | CL05B222KB5NNNC | G | PWA BOM | In Old BOM |
|  |  |  | 620107L03-023-G | CAP,2.2nF,+/-10%,X7R,50V,G,SMD0402 | TAIYO ELECTRIC IND.CO.LTD | UMK105B7222KV-F | G | PWA BOM | In Old BOM |
| 44 | PBMC27,PBAC27,PAMC27,PAAC27,PBAC111,PAAC111 | 6 | 62011DA00-015-G | CAP,1uF,+/-10%,X7R,100V,G,SMD1206 | MURATA ELEC. NORTH AMERICA | GRM31CR72A105K | G | PWA BOM | In New BOM |
|  |  |  | 62011DA00-023-G | CAP,1uF,+/-10%,X7R,100V,G,SMD1206 | TAIYO ELECTRIC IND.CO.LTD | HMK316B7105KL-T | G | PWA BOM | In New BOM |
|  |  |  | 62011DA00-026-G | CAP,1uF,+/-10%,X7R,100V,G,SMD1206 | SAMSUNG SEMICONDUCTOR | CL31B105KCHNNNE | G | PWA BOM | In New BOM |
|  |  |  | 62011DA02-015-G | CAP,1uF,+/-10%,X7R,100V,G,SMD1206 | MURATA ELEC. NORTH AMERICA | GRM31CR72A105KA01K | G | PWA BOM | In New BOM |
|  | PBMC27,PBAC27,PAMC27,PAAC27,PBAC111,PAAC111 | 6 | 62011DA00-015-G | CAP,1uF,+/-10%,X7R,100V,G,SMD1206 | MURATA ELEC. NORTH AMERICA | GRM31CR72A105K | Y | PWA BOM | In Old BOM |
|  |  |  | 62011DA00-023-G | CAP,1uF,+/-10%,X7R,100V,G,SMD1206 | TAIYO | HMK316B7105KL-T | G | PWA BOM | In Old BOM |
|  |  |  | 62011DA00-026-G | CAP,1uF,+/-10%,X7R,100V,G,SMD1206 | SAMSUNG | CL31B105KCHNNNE | G | PWA BOM | In Old BOM |
|  |  |  | 62011DA02-015-G | CAP,1uF,+/-10%,X7R,100V,G,SMD1206 | MURATA | GRM31CR72A105KA01K | G | PWA BOM | In Old BOM |
| 45 | PIPC10,PFPC10,PEPC10,PBNC11,PANC11,PBNC13,PANC13,PUAC18,PSAC18,PRAC18,PQAC18,PPAC18,PIAC18,PFAC18,PEAC18,PBNC25,PANC25,PALC35,PALC40,PBLC56,PBLC60,PBAC125,PAAC125 | 23 | 620109700-015-G | CAP,3.3nF,+/-10%,X7R,50V,G,SMD0402 | MURATA ELEC. NORTH AMERICA | GRM155R71H332K | G | PWA BOM | In New BOM |
|  |  |  | 620109700-012-G | CAP,3.3nF,+/-10%,X7R,50V,G,SMD0402 | WALSIN TECHNOLOGY CORPORATION | 0402B332K500CT | G | PWA BOM | In New BOM |
|  |  |  | 620109700-026-G | CAP,3.3nF,+/-10%,X7R,50V,G,SMD0402 | SAMSUNG SEMICONDUCTOR | CL05B332KB5NNNC | G | PWA BOM | In New BOM |
|  | PIPC10,PFPC10,PEPC10,PBNC11,PANC11,PBNC13,PANC13,PUAC18,PSAC18,PRAC18,PQAC18,PPAC18,PIAC18,PFAC18,PEAC18,PBNC25,PANC25,PALC35,PALC40,PBLC56,PBLC60,PBAC125,PAAC125 | 23 | 620109700-015-G | CAP,3.3nF,+/-10%,X7R,50V,G,SMD0402 | MURATA ELEC. NORTH AMERICA | GRM155R71H332K | N | PWA BOM | In Old BOM |
|  |  |  | 620109700-012-G | CAP,3.3nF,+/-10%,X7R,50V,G,SMD0402 | WALSIN | 0402B332K500CT | G | PWA BOM | In Old BOM |
|  |  |  | 620109700-026-G | CAP,3.3nF,+/-10%,X7R,50V,G,SMD0402 | SAMSUNG SEMICONDUCTOR | CL05B332KB5NNNC | G | PWA BOM | In Old BOM |
| 46 | PBMC400,PBFC400,PBEC400,PBAC400,PAMC400,PAFC400,PAEC400,PAAC400 | 8 | 62010GS00-015-G | CAP,15nF,+/-10%,X7R,25V,G,SMD0603 | MURATA ELEC. NORTH AMERICA | GRM188R71E153K | G | PWA BOM | In New BOM |
|  |  |  | 620106B00-012-G | CAP,15nF,+/-10%,X7R,25V,G,SMD0603 | WALSIN TECHNOLOGY CORPORATION | 0603B153K250CT | G | PWA BOM | In New BOM |
|  |  |  | 620106B00-026-G | CAP,15nF,+/-10%,X7R,25V,G,SMD0603 | SAMSUNG SEMICONDUCTOR | CL10B153KA8NNNC | G | PWA BOM | In New BOM |
|  | PBMC400,PBFC400,PBEC400,PBAC400,PAMC400,PAFC400,PAEC400,PAAC400 | 8 | 62010GS00-015-G | CAP,15nF,+/-10%,X7R,25V,G,SMD0603 | MURATA ELEC. NORTH AMERICA | GRM188R71E153K | N | PWA BOM | In Old BOM |
|  |  |  | 620106B00-012-G | CAP,15nF,+/-10%,X7R,25V,G,SMD0603 | WALSIN | 0603B153K250CT | G | PWA BOM | In Old BOM |
|  |  |  | 620106B00-026-G | CAP,15nF,+/-10%,X7R,25V,G,SMD0603 | SAMSUNG SEMICONDUCTOR | CL10B153KA8NNNC | G | PWA BOM | In Old BOM |
| 47 | PBMD1,PBFD1,PBED1,PBAD1,PAMD1,PAFD1,PAED1,PAAD1 | 8 | 520103B00-185-G | Diode,Rectifier&Switching,MMBD1205,100V,200mA,G,SOT-23-3,SMD | FAIRCHILD SEMICONDUCTOR CORP | MMBD1205 | G | PWA BOM | In New BOM |
|  |  |  | MMBD3004A | Diode,Rectifier&Switching,100V,200mA,G,SOT-23-3,SMD | DIODES INCORPORATION | MMBD3004A |  | PWA BOM | In New BOM |
|  | PBMD1,PBFD1,PBED1,PBAD1,PAMD1,PAFD1,PAED1,PAAD1 | 8 | 520103B00-185-G | Diode,Rectifier&Switching,MMBD1205,100V,200mA,G,SOT-23-3,SMD | FAIRCHILD SEMICONDUCTOR CORP | MMBD1205 | N | PWA BOM | In Old BOM |
|  |  |  | BAW156HM | Diode,Rectifier&Switching,100V,200mA,G,SOT-23-3,SMD | ROHM | BAW156HM |  | PWA BOM | In Old BOM |
|  |  |  | 52010AP00-280-G | Diode,Rectifier&Switching,MMBD3004A,240V,225mA,SOT-23,3P,G | DIODES INC | MMBD3004A |  | PWA BOM | In Old BOM |
| 48 | PSUFS1,PBAFS1,PAAFS1,PSUFS2 | 4 | 730100M00-086-G | Fuse,Very fast acting,125V,10A,G,SMD | LITTELFUSE FAR EAST PTE LTD | 0451010.MRL | G | PWA BOM | In New BOM |
|  |  |  | CB61F10A-TR2 | Fuse,CB61F10A-TR2 | COOPER BUSSMANN, INC. | CB61F10A-TR2 | 2 | PWA BOM | In New BOM |
|  | PSUFS1,PBAFS1,PAAFS1,PSUFS2 | 4 | 730100M00-086-G | Fuse,Very fast acting,125V,10A,G,SMD | LITTELFUSE FAR EAST PTE LTD | 0451010.MRL | N | PWA BOM | In Old BOM |
| 49 | PBMQ1,PBFQ1,PBEQ1,PBAQ1,PAMQ1,PAFQ1,PAEQ1,PAAQ1,PBMQ2,PBFQ2,PBEQ2,PBAQ2,PAMQ2,PAFQ2,PAEQ2,PAAQ2 | 16 | 510201900-185-G | TRANS P,MMBT3906,40V,0.2A,G,SOT23-3,SMD | FAIRCHILD SEMICONDUCTOR CORP | MMBT3906 | G | PWA BOM | In New BOM |
|  |  |  | 510201900-031-G | TRANS P,MMBT3906,40V,0.2A,G,SOT23-3,SMD | NXP SEMICONDUCTORS | MMBT3906 | G | PWA BOM | In New BOM |
|  |  |  | 510200600-237-G | TRANS P,MMBT3906-7-F,40V,0.2A,G,SOT23-3,SMD | DIODES INCORPORATION | MMBT3906-7-F | G | PWA BOM | In New BOM |
|  | PBMQ1,PBFQ1,PBEQ1,PBAQ1,PAMQ1,PAFQ1,PAEQ1,PAAQ1,PBMQ2,PBFQ2,PBEQ2,PBAQ2,PAMQ2,PAFQ2,PAEQ2,PAAQ2 | 16 | 510201900-185-G | TRANS P,MMBT3906,40V,0.2A,G,SOT23-3,SMD | FAIRCHILD SEMICONDUCTOR CORP | MMBT3906 | N | PWA BOM | In Old BOM |
|  |  |  | 510201900-031-G | TRANS P,MMBT3906,40V,0.2A,G,SOT23-3,SMD | NXP SEMICONDUCTORS | MMBT3906 | G | PWA BOM | In Old BOM |
|  |  |  | 510200600-237-G | TRANS P,MMBT3906-7-F,40V,0.2A,G,SOT23-3,SMD | DIODES INCORPORATION | MMBT3906-7-F | G | PWA BOM | In Old BOM |
|  |  |  | 510200E00-223-G | TRANS P,MMBT3906LT1G,40V,0.2A,G,SOT23-3,SMD | ON SEMICONDUCTOR CORP | MMBT3906LT1G | G | PWA BOM | In Old BOM |
| 50 | PUAR1,PSIR1,PSAR1,PRAR1,PQAR1,PPAR1,PIAR1,PFAR1,PETR1,PERR1,PEAR1,PBMR1,PBFR1,PBER1,PBAR1,PAMR1,PAFR1,PAER1,PAAR1,PUAR3,PSIR3,PSAR3,PRAR3,PQAR3,PPAR3,PIAR3,PFAR3,PETR3,PERR3,PEAR3,PUAR9,PSIR9,PSAR9,PRAR9,PQAR9,PPAR9,PIAR9,PFAR9,PETR9,PERR9,PEAR9,PBNR10,PANR10,PBNR13,PANR13,PBAR66,PBMR68,PAMR70,PBER71,PAFR71,PAER71,PAAR71,PBFR72,PBMR78,PAMR78,R133,R142,R153,R163,R174,R184,R196,R205,R217,R226,R238,R247,R258,R268,R280,R289,PBER308,PBFR400,PBAR400,PAFR400,PAER400,PAAR400,R488,R497,R508,R518,R529,R539,R551,R560,R572,R581,R593,R602,R614,R623,R635,R644,R1028,R1742,R1743,R1744,R1747,R1748,R1749,R1755,R1761,R1762,R1763,R1764,R1765,R1766,R1767 | 108 | 610108300-017-G | RES,0 Ohm,+/-5%,1/10W,G,SMD0603 | KOA SPEER ELECTRONICS, INC. | RK73Z1JTTD | G | PWA BOM | In New BOM |
|  |  |  | 610108300-012-G | RES,0 Ohm,+/-5%,1/10W,G,SMD0603 | WALSIN TECHNOLOGY CORPORATION | WR06X000PTL | G | PWA BOM | In New BOM |
|  |  |  | 610108300-011-G | RES,0 Ohm,+/-5%,1/10W,G,SMD0603 | YAGEO CORPORATION COMPONENT | RC0603JR-070RL | G | PWA BOM | In New BOM |
|  |  |  | 610108300-044-G | RES,0 Ohm,+/-5%,1/10W,G,SMD0603 | TA-I TECHNOLOGY CO., LTD | RM06JTN0 | G | PWA BOM | In New BOM |
|  |  |  | 610108300-024-G | RES,0 Ohm,+/-5%,1/10W,G,SMD0603 | PANASONIC INDUSTRIAL CO.,LTD. | ERJ3GEY0R00V | G | PWA BOM | In New BOM |
|  | PUAR1,PSIR1,PSAR1,PRAR1,PQAR1,PPAR1,PIAR1,PFAR1,PETR1,PERR1,PEAR1,PBMR1,PBFR1,PBER1,PBAR1,PAMR1,PAFR1,PAER1,PAAR1,PUAR3,PSIR3,PSAR3,PRAR3,PQAR3,PPAR3,PIAR3,PFAR3,PETR3,PERR3,PEAR3,PUAR9,PSIR9,PSAR9,PRAR9,PQAR9,PPAR9,PIAR9,PFAR9,PETR9,PERR9,PEAR9,PBNR10,PANR10,PBNR13,PANR13,PBAR66,PBMR68,PAMR70,PBER71,PAFR71,PAER71,PAAR71,PBFR72,PBMR78,PAMR78,R133,R142,R153,R163,R174,R184,R196,R205,R217,R226,R238,R247,R258,R268,R280,R289,PBER308,PBFR400,PBAR400,PAFR400,PAER400,PAAR400,R488,R497,R508,R518,R529,R539,R551,R560,R572,R581,R593,R602,R614,R623,R635,R644,R1028,R1742,R1743,R1744,R1747,R1748,R1749,R1755,R1761,R1762,R1763,R1764,R1765,R1766,R1767,R1845 | 109 | 610108300-017-G | RES,0 Ohm,+/-5%,1/10W,G,SMD0603 | KOA SPEER ELECTRONICS, INC. | RK73Z1JTTD | N | PWA BOM | In Old BOM |
|  |  |  | 610108300-012-G | RES,0 Ohm,+/-5%,1/10W,G,SMD0603 | WALSIN | WR06X000PTL | G | PWA BOM | In Old BOM |
|  |  |  | 610108300-011-G | RES,0 Ohm,+/-5%,1/10W,G,SMD0603 | YAGEO | RC0603JR-070RL | G | PWA BOM | In Old BOM |
|  |  |  | 610108300-044-G | RES,0 Ohm,+/-5%,1/10W,G,SMD0603 | TA-I | RM06JTN0 | G | PWA BOM | In Old BOM |
|  |  |  | 610108300-024-G | RES,0 Ohm,+/-5%,1/10W,G,SMD0603 | PANASONIC INDUSTRIAL CO.,LTD. | ERJ3GEY0R00V | G | PWA BOM | In Old BOM |
| 51 | R1,R2,PSTR2,PSPR2,PSLR2,PSFR2,PSER2,PSDR2,PQPR2,PIPR2,PFPR2,PEPR2,PEER2,PEDR2,PBFR2,PBER2,PBAR2,PAFR2,PAER2,PAAR2,PBNR3,PBER3,PBAR3,PANR3,PAER3,PAAR3,PBNR4,PBFR4,PBAR4,PANR4,PAFR4,PAAR4,R6,PBAR6,PAMR6,R7,PSPR7,PIPR7,PFPR7,PEPR7,PBFR7,PAER7,PAAR7,PSRR8,PSPR8,PSLR8,PSFR8,PSDR8,PQPR8,PIPR8,PFRR8,PFPR8,PEPR8,PEER8,PEDR8,PAFR8,PAER8,PSTR9,PSLR9,PSFR9,PSER9,PSDR9,PQPR9,PFRR9,PEER9,PEDR9,PBER9,PBAR9,PAMR9,PHAR10,PBFR10,PAAR10,PBMR11,PBER11,PAFR11,PUAR12,PSIR12,PSAR12,PRAR12,PQAR12,PPAR12,PIAR12,PHAR12,PFAR12,PETR12,PERR12,PEAR12,PBNR12,PANR12,PBER13,PAAR13,PUAR14,PSRR14,PSPR14,PSAR14,PRAR14,PQAR14,PPAR14,PIPR14,PIAR14,PFPR14,PFAR14,PEPR14,PEAR14,PBMR14,PBFR14,PAFR14,PUAR15,PSTR15,PSRR15,PSLR15,PSFR15,PSER15,PSDR15,PSAR15,PRAR15,PQPR15,PQAR15,PPAR15,PIAR15,PFRR15,PFAR15,PEER15,PEDR15,PEAR15,PBFR15,PBER15,PBAR15,PAFR15,PAER15,PAAR15,PSIR16,PETR16,PERR16,PBMR16,PBAR16,PAMR16,PAER16,PALR17,PSTR18,PSLR18,PSFR18,PSER18,PSDR18,PQPR18,PFRR18,PEER18,PEDR18,PBMR18,PBFR18,PBER18,PBAR18,PAMR18,PAFR18,PAER18,PAAR18,PBLR19,PBNR20,PANR20,PSRR22,PSPR22,PIPR22,PFPR22,PEPR22,PBMR22,PBFR22,PBER22,PBAR22,PAMR22,PAFR22,PAER22,PAAR22,PHAR24,PHAR25,PBMR25,PBFR25,PBER25,PBAR25,PAMR25,PAFR25,PAER25,PAAR25,PBMR28,PBFR28,PBER28,PBAR28,PAMR28,PAFR28,PAER28,PAAR28,R29,R30,PBMR30,PBFR30,PBER30,PBAR30,PAMR30,PAFR30,PAER30,PAAR30,PHAR31,PHAR32,PBMR32,PBFR32,PBER32,PBAR32,PAMR32,PAFR32,PAER32,PAAR32,PHAR33,PBMR33,PBFR33,PBER33,PBAR33,PAMR33,PAFR33,PAER33,PAAR33,PHAR34,PBMR35,PBFR35,PBER35,PBAR35,PAMR35,PAFR35,PAER35,PAAR35,PBMR36,PBFR36,PBER36,PBAR36,PAMR36,PAFR36,PAER36,PAAR36,PBMR38,PBFR38,PBER38,PBAR38,PAMR38,PAFR38,PAER38,PAAR38,PBMR39,PBAR39,PAMR39,PAAR39,PBMR42,PBFR42,PBER42,PBAR42,PAMR42,PAFR42,PAER42,PAAR42,PBMR46,PAMR46,PBMR56,PBFR56,PBER56,PBAR56,PAMR56,PAFR56,PAER56,PAAR56,PBMR66,PAMR67,PAAR67,PBAR68,PAMR68,PAAR68,PBAR69,PAAR69,R70,PBMR70,PBAR70,R71,R72,PBAR72,PAAR72,R73,R74,R75,PAFR77,PAER77,PBFR78,PBER78,PAFR78,PAER78,R79,PBMR79,PBFR79,PBER79,PAMR79,PAFR79,PAER79,R80,PBFR80,R81,PBER81,PBAR81,PAFR81,PAER81,PAAR81,R82,PBFR82,PBER82,PAER82,R83,R84,R85,R86,R87,PBMR87,PBER87,PAMR87,PBER89,PBAR89,PAFR89,PAER89,PAAR89,PBFR90,PBER93,PAFR93,PAER93,PBFR94,PBER96,PAFR96,PAER96,PBFR97,PBAR101,PAAR101,PBMR103,PAMR103,PBMR104,PAMR104,PBER105,PAFR105,PAER105,PBFR106,PBER106,PAFR106,PAER106,PBFR107,PBAR109,PAAR109,PBMR110,PBAR110,PAMR110,PAAR110,PBMR111,PAMR111,PBER112,PAFR112,PAER112,PBFR113,PBER113,PAFR113,PAER113,PBFR114,PBMR115,PAMR115,PBMR116,PBAR116,PAMR116,PAAR116,PBER117,PBAR117,PAFR117,PAER117,PAAR117,PBFR118,PBER118,PAFR118,PAER118,PBFR119,PBAR121,PAAR121,PBAR122,PAAR122,PBFR302,PBER302,PBAR302,PAFR302,PAER302,PAAR302,R303,PBMR303,PBFR303,PBER303,PBAR303,PAMR303,PAFR303,PAER303,PAAR303,R306,R308,PBMR308,PBAR308,PAMR308,PAAR308,R309,PBMR309,PBAR309,PAMR309,PAAR309,PBFR310,PAFR310,PAER310,R311,PBER311,R312,PBFR312,PAFR312,PAER312,R313,PBER313,PBAR313,PAAR313,R314,R315,R316,R317,R320,R321,R322,R323,R324,R325,R326,R331,R363,R364,R368,R369,R414,R415,R428,R429,R430,R431,R433,R434,R437,R438,R439,R440,R467,R473,R474,R477,R478,R479,PSUR500,PBNR500,PBMR500,PBFR500,PBER500,PANR500,PAMR500,PAFR500,PAER500,PAAR500,PSUR501,PBNR501,PBMR501,PBFR501,PBER501,PANR501,PAMR501,PAFR501,PAER501,PAAR501,PBAR502,PBAR503,PBFR514,PBER514,PAFR514,PBFR515,PBER515,PAFR515,PAER515,PBFR516,PBER516,PAFR516,PAER516,PAER517,PBMR607,PBAR607,PAMR607,PAAR607,PBMR608,PBAR608,PAMR608,PAAR608,R670,R671,R674,R677,R717,R722,R723,R724,R726,R728,R744,R745,R747,R750,R754,R757,R760,R761,R768,R785,R798,R802,R810,R812,R813,R824,R826,R895,R896,R899,R900,R909,R911,R918,R919,R921,R923,R924,R926,R928,R930,R931,R941,R946,R947,R951,R952,R973,R974,R979,R987,R1004,R1005,R1073,R1082,R1086,R1099,R1100,R1116,R1117,R1130,R1131,R1132,R1133,R1134,R1143,R1145,R1146,R1158,R1160,R1166,R1167,R1168,R1170,R1177,R1178,R1179,R1180,R1182,R1187,R1188,R1191,R1192,R1194,R1200,R1201,R1203,R1204,R1207,R1208,R1214,R1215,R1216,R1226,R1228,R1233,R1235,R1236,R1238,R1241,R1242,R1243,R1244,R1245,R1246,R1247,R1248,R1249,R1250,R1259,R1260,R1281,R1282,R1283,R1284,R1285,R1286,R1289,R1290,R1291,R1292,R1293,R1297,R1321,R1322,R1330,R1339,R1344,R1360,R1362,R1369,R1370,R1372,R1373,R1375,R1376,R1406,R1407,R1432,R1433,R1434,R1435,R1436,R1437,R1438,R1439,R1442,R1443,R1445,R1472,R1473,R1478,R1491,R1496,R1497,R1501,R1502,R1503,R1510,R1514,R1519,R1522,R1527,R1528,R1531,R1532,R1549,R1552,R1554,R1555,R1556,R1599,R1600,R1720,R1721,R1722,R1724,R1725,R1752,R1753,R1776,R1787,R1788,R1803,R1804,R1805,R1806,R1807,R1808,R1809,R1810,R1812,R1813,R1814,R1815,R1816,R1817,R1818,R1819,R1825,R1826,R1832,R1833,R1835,R1837,R1840,R1841,R1842,R1843,R1848,R1849,PSPR3001,PIPR3001,PFPR3001,PEPR3001,PSPR3002,PIPR3002,PFPR3002,PEPR3002,PSRR3003,PSPR3003,PIPR3003,PFPR3003,PEPR3003,PSRR3005,PSRR3008 | 722 | 610107A00-017-G | RES,0 Ohm,+/-5%,1/16W,G,SMD0402 | KOA SPEER ELECTRONICS, INC. | RK73Z1ETTP | G | PWA BOM | In New BOM |
|  |  |  | 610107A00-012-G | RES,0 Ohm,+/-5%,1/16W,G,SMD0402 | WALSIN TECHNOLOGY CORPORATION | WR04X000PTL | G | PWA BOM | In New BOM |
|  |  |  | 610107A00-011-G | RES,0 Ohm,+/-5%,1/16W,G,SMD0402 | YAGEO CORPORATION COMPONENT | RC0402JR-070RL | G | PWA BOM | In New BOM |
|  |  |  | 610107A00-044-G | RES,0 Ohm,+/-5%,1/16W,G,SMD0402 | TA-I TECHNOLOGY CO., LTD | RM04JTN0 | G | PWA BOM | In New BOM |
|  |  |  | 610107A00-024-G | RES,0 Ohm,+/-5%,1/16W,G,SMD0402 | PANASONIC INDUSTRIAL CO.,LTD. | ERJ2GE0R00X | G | PWA BOM | In New BOM |
|  |  |  | 610107A00-029-G | RES,0 Ohm,+/-5%,1/16W,G,SMD0402 | VISHAY ENTER TECHNO LOGY.INC | CRCW04020000Z0ED | G | PWA BOM | In New BOM |
|  | R1,R2,PSTR2,PSPR2,PSLR2,PSFR2,PSER2,PSDR2,PQPR2,PIPR2,PFPR2,PEPR2,PEER2,PEDR2,PBFR2,PBER2,PBAR2,PAFR2,PAER2,PAAR2,PBNR3,PBER3,PBAR3,PANR3,PAER3,PAAR3,PBNR4,PBFR4,PBAR4,PANR4,PAFR4,PAAR4,R6,PBAR6,PAMR6,R7,PSPR7,PIPR7,PFPR7,PEPR7,PBFR7,PAER7,PAAR7,PSRR8,PSPR8,PSLR8,PSFR8,PSDR8,PQPR8,PIPR8,PFRR8,PFPR8,PEPR8,PEER8,PEDR8,PAFR8,PAER8,PSTR9,PSLR9,PSFR9,PSER9,PSDR9,PQPR9,PFRR9,PEER9,PEDR9,PBER9,PBAR9,PAMR9,PHAR10,PBFR10,PAAR10,PBMR11,PBER11,PAFR11,PUAR12,PSIR12,PSAR12,PRAR12,PQAR12,PPAR12,PIAR12,PHAR12,PFAR12,PETR12,PERR12,PEAR12,PBNR12,PANR12,PBER13,PAAR13,PUAR14,PSRR14,PSPR14,PSAR14,PRAR14,PQAR14,PPAR14,PIPR14,PIAR14,PFPR14,PFAR14,PEPR14,PEAR14,PBMR14,PBFR14,PAFR14,PUAR15,PSTR15,PSRR15,PSLR15,PSFR15,PSER15,PSDR15,PSAR15,PRAR15,PQPR15,PQAR15,PPAR15,PIAR15,PFRR15,PFAR15,PEER15,PEDR15,PEAR15,PBFR15,PBER15,PBAR15,PAFR15,PAER15,PAAR15,PSIR16,PETR16,PERR16,PBMR16,PBAR16,PAMR16,PAER16,PALR17,PSTR18,PSLR18,PSFR18,PSER18,PSDR18,PQPR18,PFRR18,PEER18,PEDR18,PBMR18,PBFR18,PBER18,PBAR18,PAMR18,PAFR18,PAER18,PAAR18,PBLR19,PBNR20,PANR20,PSRR22,PSPR22,PIPR22,PFPR22,PEPR22,PBMR22,PBFR22,PBER22,PBAR22,PAMR22,PAFR22,PAER22,PAAR22,PHAR24,PHAR25,PBMR25,PBFR25,PBER25,PBAR25,PAMR25,PAFR25,PAER25,PAAR25,PBMR28,PBFR28,PBER28,PBAR28,PAMR28,PAFR28,PAER28,PAAR28,R29,R30,PBMR30,PBFR30,PBER30,PBAR30,PAMR30,PAFR30,PAER30,PAAR30,PHAR31,PHAR32,PBMR32,PBFR32,PBER32,PBAR32,PAMR32,PAFR32,PAER32,PAAR32,PHAR33,PBMR33,PBFR33,PBER33,PBAR33,PAMR33,PAFR33,PAER33,PAAR33,PHAR34,PBMR35,PBFR35,PBER35,PBAR35,PAMR35,PAFR35,PAER35,PAAR35,PBMR36,PBFR36,PBER36,PBAR36,PAMR36,PAFR36,PAER36,PAAR36,PBMR38,PBFR38,PBER38,PBAR38,PAMR38,PAFR38,PAER38,PAAR38,PBMR39,PBAR39,PAMR39,PAAR39,PBMR42,PBFR42,PBER42,PBAR42,PAMR42,PAFR42,PAER42,PAAR42,PBMR46,PAMR46,PBMR56,PBFR56,PBER56,PBAR56,PAMR56,PAFR56,PAER56,PAAR56,PBMR66,PAMR67,PAAR67,PBAR68,PAMR68,PAAR68,PBAR69,PAAR69,R70,PBMR70,PBAR70,R71,R72,PBAR72,PAAR72,R73,R74,R75,PAFR77,PAER77,PBFR78,PBER78,PAFR78,PAER78,R79,PBMR79,PBFR79,PBER79,PAMR79,PAFR79,PAER79,R80,PBFR80,R81,PBER81,PBAR81,PAFR81,PAER81,PAAR81,R82,PBFR82,PBER82,PAER82,R83,R84,R85,R86,R87,PBMR87,PBER87,PAMR87,PBER89,PBAR89,PAFR89,PAER89,PAAR89,PBFR90,PBER93,PAFR93,PAER93,PBFR94,PBER96,PAFR96,PAER96,PBFR97,PBAR101,PAAR101,PBMR103,PAMR103,PBMR104,PAMR104,PBER105,PAFR105,PAER105,PBFR106,PBER106,PAFR106,PAER106,PBFR107,PBAR109,PAAR109,PBMR110,PBAR110,PAMR110,PAAR110,PBMR111,PAMR111,PBER112,PAFR112,PAER112,PBFR113,PBER113,PAFR113,PAER113,PBFR114,PBMR115,PAMR115,PBMR116,PBAR116,PAMR116,PAAR116,PBER117,PBAR117,PAFR117,PAER117,PAAR117,PBFR118,PBER118,PAFR118,PAER118,PBFR119,PBAR121,PAAR121,PBAR122,PAAR122,PBFR302,PBER302,PBAR302,PAFR302,PAER302,PAAR302,R303,PBMR303,PBFR303,PBER303,PBAR303,PAMR303,PAFR303,PAER303,PAAR303,R306,R308,PBMR308,PBAR308,PAMR308,PAAR308,R309,PBMR309,PBAR309,PAMR309,PAAR309,PBFR310,PAFR310,PAER310,R311,PBER311,R312,PBFR312,PAFR312,PAER312,R313,PBER313,PBAR313,PAAR313,R314,R315,R316,R317,R320,R321,R322,R323,R324,R325,R326,R331,R363,R364,R368,R369,R414,R415,R428,R429,R430,R431,R433,R434,R437,R438,R439,R440,R467,R473,R474,R477,R478,R479,PSUR500,PBNR500,PBMR500,PBFR500,PBER500,PANR500,PAMR500,PAFR500,PAER500,PAAR500,PSUR501,PBNR501,PBMR501,PBFR501,PBER501,PANR501,PAMR501,PAFR501,PAER501,PAAR501,PBAR502,PBAR503,PBFR514,PBER514,PAFR514,PBFR515,PBER515,PAFR515,PAER515,PBFR516,PBER516,PAFR516,PAER516,PAER517,PBMR607,PBAR607,PAMR607,PAAR607,PBMR608,PBAR608,PAMR608,PAAR608,R670,R671,R674,R677,R717,R722,R723,R724,R726,R728,R744,R745,R747,R750,R754,R757,R760,R761,R768,R785,R798,R802,R810,R812,R813,R824,R826,R895,R896,R899,R900,R909,R911,R918,R919,R921,R923,R924,R926,R928,R930,R931,R941,R946,R947,R951,R952,R973,R974,R979,R987,R1004,R1005,R1073,R1082,R1086,R1099,R1100,R1116,R1117,R1130,R1131,R1132,R1133,R1134,R1143,R1145,R1146,R1158,R1160,R1166,R1167,R1168,R1170,R1177,R1178,R1179,R1180,R1182,R1187,R1188,R1191,R1192,R1194,R1200,R1201,R1203,R1204,R1207,R1208,R1214,R1215,R1216,R1226,R1228,R1233,R1235,R1236,R1238,R1241,R1242,R1243,R1244,R1245,R1246,R1247,R1248,R1249,R1250,R1259,R1260,R1281,R1282,R1283,R1284,R1285,R1286,R1289,R1290,R1291,R1292,R1293,R1297,R1321,R1322,R1330,R1339,R1344,R1360,R1362,R1369,R1370,R1372,R1373,R1375,R1376,R1406,R1407,R1432,R1433,R1434,R1435,R1436,R1437,R1438,R1439,R1442,R1443,R1445,R1472,R1473,R1478,R1491,R1496,R1497,R1501,R1502,R1503,R1510,R1514,R1522,R1527,R1528,R1531,R1532,R1549,R1552,R1554,R1555,R1556,R1599,R1600,R1720,R1721,R1722,R1724,R1725,R1752,R1753,R1776,R1787,R1788,R1803,R1804,R1805,R1806,R1807,R1808,R1809,R1810,R1812,R1813,R1814,R1815,R1816,R1817,R1818,R1819,R1825,R1826,R1832,R1833,R1835,R1837,R1840,R1841,R1842,R1843,PSPR3001,PIPR3001,PFPR3001,PEPR3001,PSPR3002,PIPR3002,PFPR3002,PEPR3002,PSRR3003,PSPR3003,PIPR3003,PFPR3003,PEPR3003,PSRR3005,PSRR3008 | 719 | 610107A00-017-G | RES,0 Ohm,+/-5%,1/16W,G,SMD0402 | KOA SPEER ELECTRONICS, INC. | RK73Z1ETTP | N | PWA BOM | In Old BOM |
|  |  |  | 610107A00-012-G | RES,0 Ohm,+/-5%,1/16W,G,SMD0402 | WALSIN | WR04X000PTL | G | PWA BOM | In Old BOM |
|  |  |  | 610107A00-011-G | RES,0 Ohm,+/-5%,1/16W,G,SMD0402 | YAGEO | RC0402JR-070RL | G | PWA BOM | In Old BOM |
|  |  |  | 610107A00-044-G | RES,0 Ohm,+/-5%,1/16W,G,SMD0402 | TA-I | RM04JTN0 | G | PWA BOM | In Old BOM |
|  |  |  | 610107A00-024-G | RES,0 Ohm,+/-5%,1/16W,G,SMD0402 | PANASONIC INDUSTRIAL CO.,LTD. | ERJ2GE0R00X | G | PWA BOM | In Old BOM |
|  |  |  | 610107A00-029-G | RES,0 Ohm,+/-5%,1/16W,G,SMD0402 | VISHAY ENTER TECHNO LOGY.INC | CRCW04020000Z0ED | G | PWA BOM | In Old BOM |
| 52 | PBER7,PAMR7,PAMR8,PAFR9,PAFR10,PAER10,PBAR11,PAER11,PBFR12,PBAR12,PAAR12,PBMR13,PBFR13,PBER14,PAAR14,PBMR15,PBMR17,PBFR17,PBER17,PBAR17,PAMR17,PAFR17,PAER17,PAAR17,PBMR21,PBFR21,PBER21,PBAR21,PAMR21,PAFR21,PAER21,PAAR21,PBMR24,PBFR24,PBER24,PBAR24,PAMR24,PAFR24,PAER24,PAAR24,PBMR27,PBFR27,PBER27,PBAR27,PAMR27,PAFR27,PAER27,PAAR27 | 48 | 61010PS00-017-G | RES,200KOhm,+/-1%,1/16W,G,SMD0402 | KOA SPEER ELECTRONICS, INC. | RK73H1ETTP2003F | G | PWA BOM | In New BOM |
|  |  |  | 61010PS00-012-G | RES,200KOhm,+/-1%,1/16W,G,SMD0402 | WALSIN TECHNOLOGY CORPORATION | WR04X2003FTL | G | PWA BOM | In New BOM |
|  |  |  | 61010PS00-011-G | RES,200KOhm,+/-1%,1/16W,G,SMD0402 | YAGEO CORPORATION COMPONENT | RC0402FR-07200KL | G | PWA BOM | In New BOM |
|  |  |  | 61010PS00-044-G | RES,200KOhm,+/-1%,1/16W,G,SMD0402 | TA-I TECHNOLOGY CO., LTD | RM04FTN2003 | G | PWA BOM | In New BOM |
|  | PBER7,PAMR7,PAMR8,PAFR9,PAFR10,PAER10,PBAR11,PAER11,PBFR12,PBAR12,PAAR12,PBMR13,PBFR13,PBER14,PAAR14,PBMR15,PBMR17,PBFR17,PBER17,PBAR17,PAMR17,PAFR17,PAER17,PAAR17,PBMR21,PBFR21,PBER21,PBAR21,PAMR21,PAFR21,PAER21,PAAR21,PBMR24,PBFR24,PBER24,PBAR24,PAMR24,PAFR24,PAER24,PAAR24,PBMR27,PBFR27,PBER27,PBAR27,PAMR27,PAFR27,PAER27,PAAR27 | 48 | 61010PS00-017-G | RES,200KOhm,+/-1%,1/16W,G,SMD0402 | KOA SPEER ELECTRONICS, INC. | RK73H1ETTP2003F | N | PWA BOM | In Old BOM |
|  |  |  | 61010PS00-012-G | RES,200KOhm,+/-1%,1/16W,G,SMD0402 | WALSIN | WR04X2003FTL | G | PWA BOM | In Old BOM |
|  |  |  | 61010PS00-011-G | RES,200KOhm,+/-1%,1/16W,G,SMD0402 | YAGEO | RC0402FR-07200KL | G | PWA BOM | In Old BOM |
|  |  |  | 61010PS00-044-G | RES,200KOhm,+/-1%,1/16W,G,SMD0402 | TA-I | RM04FTN2003 | G | PWA BOM | In Old BOM |
| 53 | PBAR34,PAAR34,PBMR55,PBFR55,PBER55,PBAR55,PAMR55,PAFR55,PAER55,PAAR55 | 10 | 611003D00-017-G | RES,1KOhm,+/-0.1%,1/16W,G,SMD0402 | KOA SPEER ELECTRONICS, INC. | RN731ETTP1001B25 | G | PWA BOM | In New BOM |
|  |  |  | 611003D03-012-G | RES,1KOhm,+/-0.1%,1/16W,G,SMD0402 | WALSIN TECHNOLOGY CORPORATION | WF04U1001BTL | G | PWA BOM | In New BOM |
|  |  |  | 611003D02-011-G | RES,1KOhm,+/-0.1%,1/16W,G,SMD0402 | YAGEO CORPORATION COMPONENT | RT0402BRD071KL | G | PWA BOM | In New BOM |
|  |  |  | 611003D00-044-G | RES,1KOhm,+/-0.1%,1/16W,G,SMD0402 | TA-I TECHNOLOGY CO., LTD | RB04BTS1001 | G | PWA BOM | In New BOM |
|  | PBAR34,PAAR34,PBMR55,PBFR55,PBER55,PBAR55,PAMR55,PAFR55,PAER55,PAAR55 | 10 | 611003D00-017-G | RES,1KOhm,+/-0.1%,1/16W,G,SMD0402 | KOA SPEER ELECTRONICS, INC. | RN731ETTP1001B25 | Y | PWA BOM | In Old BOM |
|  |  |  | 611003D03-012-G | RES,1KOhm,+/-0.1%,1/16W,G,SMD0402 | WALSIN | WF04U1001BTL | G | PWA BOM | In Old BOM |
|  |  |  | 611003D02-011-G | RES,1KOhm,+/-0.1%,1/16W,G,SMD0402 | YAGEO | RT0402BRD071KL | G | PWA BOM | In Old BOM |
|  |  |  | 611003D00-044-G | RES,1KOhm,+/-0.1%,1/16W,G,SMD0402 | TA-I | RB04BTS1001 | G | PWA BOM | In Old BOM |
| 54 | PHAR9,PALR16,PBLR18,PBNR21,PANR21,PBMR40,PBFR40,PBER40,PBAR40,PAMR40,PAFR40,PAER40,PAAR40,R678,R679,R865,R866,R1016,R1022,R1155,R1169,R1181,R1193,R1205,R1217,R1258,R1329,R1333,R1334,R1335,R1444,R1498,R1500,R1824 | 34 | 61010L300-017-G | RES,1KOhm,+/-1%,1/16W,G,SMD0402 | KOA SPEER ELECTRONICS, INC. | RK73H1ETTP1001F | G | PWA BOM | In New BOM |
|  |  |  | 61010L300-012-G | RES,1KOhm,+/-1%,1/16W,G,SMD0402 | WALSIN TECHNOLOGY CORPORATION | WR04X1001FTL | G | PWA BOM | In New BOM |
|  |  |  | 61010L300-011-G | RES,1KOhm,+/-1%,1/16W,G,SMD0402 | YAGEO CORPORATION COMPONENT | RC0402FR-071KL | G | PWA BOM | In New BOM |
|  |  |  | 61010L300-044-G | RES,1KOhm,+/-1%,1/16W,G,SMD0402 | TA-I TECHNOLOGY CO., LTD | RM04FTN1001 | G | PWA BOM | In New BOM |
|  |  |  | 61010L300-024-G | RES,1KOhm,+/-1%,1/16W,G,SMD0402 | PANASONIC INDUSTRIAL CO.,LTD. | ERJ2RKF1001X | G | PWA BOM | In New BOM |
|  |  |  | 61010L300-029-G | RES,1KOhm,+/-1%,1/16W,G,SMD0402 | VISHAY ENTER TECHNO LOGY.INC | CRCW04021K00FKED | G | PWA BOM | In New BOM |
|  | PHAR9,PALR16,PBLR18,PBNR21,PANR21,PBMR40,PBFR40,PBER40,PBAR40,PAMR40,PAFR40,PAER40,PAAR40,R678,R679,R865,R866,R1016,R1022,R1155,R1169,R1181,R1193,R1205,R1217,R1258,R1329,R1333,R1334,R1335,R1444,R1498,R1500,R1824 | 34 | 61010L300-017-G | RES,1KOhm,+/-1%,1/16W,G,SMD0402 | KOA SPEER ELECTRONICS, INC. | RK73H1ETTP1001F | N | PWA BOM | In Old BOM |
|  |  |  | 61010L300-012-G | RES,1KOhm,+/-1%,1/16W,G,SMD0402 | WALSIN | WR04X1001FTL | G | PWA BOM | In Old BOM |
|  |  |  | 61010L300-011-G | RES,1KOhm,+/-1%,1/16W,G,SMD0402 | YAGEO | RC0402FR-071KL | G | PWA BOM | In Old BOM |
|  |  |  | 61010L300-044-G | RES,1KOhm,+/-1%,1/16W,G,SMD0402 | TA-I | RM04FTN1001 | G | PWA BOM | In Old BOM |
|  |  |  | 61010L300-024-G | RES,1KOhm,+/-1%,1/16W,G,SMD0402 | PANASONIC INDUSTRIAL CO.,LTD. | ERJ2RKF1001X | G | PWA BOM | In Old BOM |
|  |  |  | 61010L300-029-G | RES,1KOhm,+/-1%,1/16W,G,SMD0402 | VISHAY ENTER TECHNO LOGY.INC | CRCW04021K00FKED | G | PWA BOM | In Old BOM |
| 55 | PBMR41,PBFR41,PBER41,PBAR41,PAMR41,PAFR41,PAER41,PAAR41 | 8 | 611008W00-017-G | RES,73.2KOhm,+/-0.1%,1/16W,G,SMD0402 | KOA SPEER ELECTRONICS, INC. | RN731ETTP7322B25 | G | PWA BOM | In New BOM |
|  |  |  | 611008W00-012-G | RES,73.2KOhm,+/-0.1%,1/16W,G,SMD0402 | WALSIN TECHNOLOGY CORPORATION | WF04U7322BTL | G | PWA BOM | In New BOM |
|  |  |  | 611008W00-011-G | RES,73.2KOhm,+/-0.1%,1/16W,G,SMD0402 | YAGEO CORPORATION COMPONENT | RT0402BRD0773K2L | G | PWA BOM | In New BOM |
|  | PBMR41,PBFR41,PBER41,PBAR41,PAMR41,PAFR41,PAER41,PAAR41 | 8 | 611008W00-017-G | RES,73.2KOhm,+/-0.1%,1/16W,G,SMD0402 | KOA SPEER ELECTRONICS, INC. | RN731ETTP7322B25 |  | PWA BOM | In Old BOM |
|  |  |  | 611008W00-012-G | RES,73.2KOhm,+/-0.1%,1/16W,G,SMD0402 | WALSIN | WF04U7322BTL | G | PWA BOM | In Old BOM |
|  |  |  | 611008W00-011-G | RES,73.2KOhm,+/-0.1%,1/16W,G,SMD0402 | YAGEO | RT0402BRD0773K2L | G | PWA BOM | In Old BOM |
| 56 | PHAR8,PHAR14,PHAR15,PBMR45,PBAR45,PAMR45,PAER45,PAAR45,PBMR99,PAMR99,PBER101,PAFR101,PAER101,PBFR102,PBAR105,PAAR105 | 16 | 610103Y00-017-G | RES,10 Ohm,+/-1%,1/10W,G,SMD0603 | KOA SPEER ELECTRONICS, INC. | RK73H1JTTD10R0F | G | PWA BOM | In New BOM |
|  |  |  | 610103Y00-012-G | RES,10 Ohm,+/-1%,1/10W,G,SMD0603 | WALSIN TECHNOLOGY CORPORATION | WR06X10R0FTL | G | PWA BOM | In New BOM |
|  |  |  | 610103Y00-011-G | RES,10 Ohm,+/-1%,1/10W,G,SMD0603 | YAGEO CORPORATION COMPONENT | RC0603FR-0710RL | G | PWA BOM | In New BOM |
|  |  |  | 610103Y00-044-G | RES,10 Ohm,+/-1%,1/10W,G,SMD0603 | TA-I TECHNOLOGY CO., LTD | RM06FTN10R0 | G | PWA BOM | In New BOM |
|  |  |  | 610103Y00-024-G | RES,10 Ohm,+/-1%,1/10W,G,SMD0603 | PANASONIC INDUSTRIAL CO.,LTD. | ERJ3EKF10R0V | G | PWA BOM | In New BOM |
|  | PHAR8,PHAR14,PHAR15,PBMR45,PBAR45,PAMR45,PAER45,PAAR45,PBMR99,PAMR99,PBER101,PAFR101,PAER101,PBFR102,PBAR105,PAAR105 | 16 | 610103Y00-017-G | RES,10 Ohm,+/-1%,1/10W,G,SMD0603 | KOA SPEER ELECTRONICS, INC. | RK73H1JTTD10R0F |  | PWA BOM | In Old BOM |
|  |  |  | 610103Y00-012-G | RES,10 Ohm,+/-1%,1/10W,G,SMD0603 | WALSIN | WR06X10R0FTL | G | PWA BOM | In Old BOM |
|  |  |  | 610103Y00-011-G | RES,10 Ohm,+/-1%,1/10W,G,SMD0603 | YAGEO | RC0603FR-0710RL | G | PWA BOM | In Old BOM |
|  |  |  | 610103Y00-044-G | RES,10 Ohm,+/-1%,1/10W,G,SMD0603 | TA-I | RM06FTN10R0 | G | PWA BOM | In Old BOM |
|  |  |  | 610103Y00-024-G | RES,10 Ohm,+/-1%,1/10W,G,SMD0603 | PANASONIC INDUSTRIAL CO.,LTD. | ERJ3EKF10R0V | G | PWA BOM | In Old BOM |
| 57 | PBAR47,PAAR47 | 2 | 61010LD00-017-G | RES,6.8KOhm,+/-1%,1/16W,G,SMD0402 | KOA SPEER ELECTRONICS, INC. | RK73H1ETTP6801F | G | PWA BOM | In New BOM |
|  |  |  | 61010LD00-012-G | RES,6.8KOhm,+/-1%,1/16W,G,SMD0402 | WALSIN TECHNOLOGY CORPORATION | WR04X6801FTL | G | PWA BOM | In New BOM |
|  |  |  | 61010LD00-011-G | RES,6.8KOhm,+/-1%,1/16W,G,SMD0402 | YAGEO CORPORATION COMPONENT | RC0402FR-076K8L | G | PWA BOM | In New BOM |
|  |  |  | 61010LD00-044-G | RES,6.8KOhm,+/-1%,1/16W,G,SMD0402 | TA-I TECHNOLOGY CO., LTD | RM04FTN6801 | G | PWA BOM | In New BOM |
|  |  |  | 61010LD00-024-G | RES,6.8KOhm,+/-1%,1/16W,G,SMD0402 | PANASONIC INDUSTRIAL CO.,LTD. | ERJ2RKF6801X | G | PWA BOM | In New BOM |
|  | PBAR47,PAAR47 | 2 | 61010LD00-017-G | RES,6.8KOhm,+/-1%,1/16W,G,SMD0402 | KOA SPEER ELECTRONICS, INC. | RK73H1ETTP6801F | N | PWA BOM | In Old BOM |
|  |  |  | 61010LD00-012-G | RES,6.8KOhm,+/-1%,1/16W,G,SMD0402 | WALSIN | WR04X6801FTL | G | PWA BOM | In Old BOM |
|  |  |  | 61010LD00-011-G | RES,6.8KOhm,+/-1%,1/16W,G,SMD0402 | YAGEO | RC0402FR-076K8L | G | PWA BOM | In Old BOM |
|  |  |  | 61010LD00-044-G | RES,6.8KOhm,+/-1%,1/16W,G,SMD0402 | TA-I | RM04FTN6801 | G | PWA BOM | In Old BOM |
|  |  |  | 61010LD00-024-G | RES,6.8KOhm,+/-1%,1/16W,G,SMD0402 | PANASONIC INDUSTRIAL CO.,LTD. | ERJ2RKF6801X | G | PWA BOM | In Old BOM |
| 58 | PBAR57,PAAR57,R932,R980,R981,R982,R983,R984 | 8 | 61100QV00-017-G | RES,49.9 Ohm,+/-0.5%,1/16W,G,SMD0402 | KOA SPEER ELECTRONICS, INC. | RN731ETTP49R9D50 | G | PWA BOM | In New BOM |
|  |  |  | 61100QV00-012-G | RES,49.9 Ohm,+/-0.5%,1/16W,G,SMD0402 | WALSIN TECHNOLOGY CORPORATION | WF04T49R9DTL | G | PWA BOM | In New BOM |
|  |  |  | 61100QV00-011-G | RES,49.9 Ohm,+/-0.5%,1/16W,G,SMD0402 | YAGEO CORPORATION COMPONENT | RT0402DRE0749R9L | G | PWA BOM | In New BOM |
|  |  |  | 61100QV00-044-G | RES,49.9 Ohm,+/-0.5%,1/16W,G,SMD0402 | TA-I TECHNOLOGY CO., LTD | RB04DTS49R9 | G | PWA BOM | In New BOM |
|  | PBAR57,PAAR57,R932,R980,R981,R982,R983,R984 | 8 | 61100QV00-017-G | RES,49.9 Ohm,+/-0.5%,1/16W,G,SMD0402 | KOA SPEER ELECTRONICS, INC. | RN731ETTP49R9D50 |  | PWA BOM | In Old BOM |
|  |  |  | 61100QV00-012-G | RES,49.9 Ohm,+/-0.5%,1/16W,G,SMD0402 | WALSIN | WF04T49R9DTL | G | PWA BOM | In Old BOM |
|  |  |  | 61100QV00-011-G | RES,49.9 Ohm,+/-0.5%,1/16W,G,SMD0402 | YAGEO | RT0402DRE0749R9L | G | PWA BOM | In Old BOM |
|  |  |  | 61100QV00-044-G | RES,49.9 Ohm,+/-0.5%,1/16W,G,SMD0402 | TA-I | RB04DTS49R9 | G | PWA BOM | In Old BOM |
| 59 | PBFR45,PBER45,PAFR45,PBER61,PAFR61,PAER61,PBFR62,PBER62,PAFR62,PAER62,PBMR63,PBFR63,PBAR63,PAMR63,PAAR63,PBMR64,PBAR64,PAMR64,PAAR64,PBFR518,PBER518,PAFR518,PBFR519,PBER519,PAFR519,PAER519,PAER520 | 27 | 610113800-017-G | RES,10 Ohm,+/-1%,1/16W,G,SMD0402 | KOA SPEER ELECTRONICS, INC. | RK73H1ETTP10R0F | G | PWA BOM | In New BOM |
|  |  |  | 610113800-012-G | RES,10 Ohm,+/-1%,1/16W,G,SMD0402 | WALSIN TECHNOLOGY CORPORATION | WR04X10R0FTL | G | PWA BOM | In New BOM |
|  |  |  | 610113800-011-G | RES,10 Ohm,+/-1%,1/16W,G,SMD0402 | YAGEO CORPORATION COMPONENT | RC0402FR-0710RL | G | PWA BOM | In New BOM |
|  |  |  | 610113800-044-G | RES,10 Ohm,+/-1%,1/16W,G,SMD0402 | TA-I TECHNOLOGY CO., LTD | RM04FTN10R0 | G | PWA BOM | In New BOM |
|  | PALR19,PALR20,PBLR23,PBLR24,PBFR45,PBER45,PAFR45,PBER61,PAFR61,PAER61,PBFR62,PBER62,PAFR62,PAER62,PBMR63,PBFR63,PBAR63,PAMR63,PAAR63,PBMR64,PBAR64,PAMR64,PAAR64,PBFR518,PBER518,PAFR518,PBFR519,PBER519,PAFR519,PAER519,PAER520 | 31 | 610113800-017-G | RES,10 Ohm,+/-1%,1/16W,G,SMD0402 | KOA SPEER ELECTRONICS, INC. | RK73H1ETTP10R0F | N | PWA BOM | In Old BOM |
|  |  |  | 610113800-012-G | RES,10 Ohm,+/-1%,1/16W,G,SMD0402 | WALSIN | WR04X10R0FTL | G | PWA BOM | In Old BOM |
|  |  |  | 610113800-011-G | RES,10 Ohm,+/-1%,1/16W,G,SMD0402 | YAGEO | RC0402FR-0710RL | G | PWA BOM | In Old BOM |
|  |  |  | 610113800-044-G | RES,10 Ohm,+/-1%,1/16W,G,SMD0402 | TA-I | RM04FTN10R0 | G | PWA BOM | In Old BOM |
| 60 | PBER72,PAFR72,PAER72,PBFR73,PBMR74,PAMR74,PBAR77,PAAR77 | 8 | 610108U00-017-G | RES,10KOhm,+/-1%,1/10W,G,SMD0603 | KOA SPEER ELECTRONICS, INC. | RK73H1JTTD1002F | G | PWA BOM | In New BOM |
|  |  |  | 610108U00-012-G | RES,10KOhm,+/-1%,1/10W,G,SMD0603 | WALSIN TECHNOLOGY CORPORATION | WR06X1002FTL | G | PWA BOM | In New BOM |
|  |  |  | 610108U00-011-G | RES,10KOhm,+/-1%,1/10W,G,SMD0603 | YAGEO CORPORATION COMPONENT | RC0603FR-0710KL | G | PWA BOM | In New BOM |
|  |  |  | 610108U00-044-G | RES,10KOhm,+/-1%,1/10W,G,SMD0603 | TA-I TECHNOLOGY CO., LTD | RM06FTN1002 | G | PWA BOM | In New BOM |
|  |  |  | 610108U00-024-G | RES,10KOhm,+/-1%,1/10W,G,SMD0603 | PANASONIC INDUSTRIAL CO.,LTD. | ERJ3EKF1002V | G | PWA BOM | In New BOM |
|  | PBER72,PAFR72,PAER72,PBFR73,PBMR74,PAMR74,PBAR77,PAAR77 | 8 | 610108U00-017-G | RES,10KOhm,+/-1%,1/10W,G,SMD0603 | KOA SPEER ELECTRONICS, INC. | RK73H1JTTD1002F |  | PWA BOM | In Old BOM |
|  |  |  | 610108U00-012-G | RES,10KOhm,+/-1%,1/10W,G,SMD0603 | WALSIN | WR06X1002FTL | G | PWA BOM | In Old BOM |
|  |  |  | 610108U00-011-G | RES,10KOhm,+/-1%,1/10W,G,SMD0603 | YAGEO | RC0603FR-0710KL | G | PWA BOM | In Old BOM |
|  |  |  | 610108U00-044-G | RES,10KOhm,+/-1%,1/10W,G,SMD0603 | TA-I | RM06FTN1002 | G | PWA BOM | In Old BOM |
|  |  |  | 610108U00-024-G | RES,10KOhm,+/-1%,1/10W,G,SMD0603 | PANASONIC INDUSTRIAL CO.,LTD. | ERJ3EKF1002V | G | PWA BOM | In Old BOM |
| 61 | PANR5,PSTR6,PSLR6,PSFR6,PSER6,PSDR6,PQPR6,PFRR6,PEER6,PEDR6,PBNR6,PUAR7,PSIR7,PSAR7,PRAR7,PQAR7,PPAR7,PIAR7,PFAR7,PETR7,PERR7,PEAR7,PHAR22,PHAR39,PBER74,PAFR74,PAER74,PBMR75,PBFR75,PAMR75,PBAR78,PAAR78,PBMR300,PBFR300,PBER300,PBAR300,PAMR300,PAFR300,PAER300,PAAR300,PBMR305,PBFR305,PBER305,PBAR305,PAMR305,PAFR305,PAER305,PAAR305,PBMR306,PBFR306,PBER306,PBAR306,PAMR306,PAFR306,PAER306,PAAR306,PBMR307,PBFR307,PBER307,PBAR307,PAMR307,PAFR307,PAER307,PAAR307,R330,R351,R353,R357,R359,R480,R481,R482,R483,R719,R864,R908,R912,R913,R914,R915,R916,R920,R1075,R1076,R1077,R1078,R1118,R1136,R1137,R1441,R1482,R1490,R1534,R1535,R1536,R1537,R1538,R1539,R1540,PSRR3001 | 100 | 61010G500-017-G | RES,10KOhm,+/-1%,1/16W,G,SMD0402 | KOA SPEER ELECTRONICS, INC. | RK73H1ETTP1002F | G | PWA BOM | In New BOM |
|  |  |  | 61010G500-012-G | RES,10KOhm,+/-1%,1/16W,G,SMD0402 | WALSIN TECHNOLOGY CORPORATION | WR04X1002FTL | G | PWA BOM | In New BOM |
|  |  |  | 61010G500-011-G | RES,10KOhm,+/-1%,1/16W,G,SMD0402 | YAGEO CORPORATION COMPONENT | RC0402FR-0710KL | G | PWA BOM | In New BOM |
|  |  |  | 61010G500-044-G | RES,10KOhm,+/-1%,1/16W,G,SMD0402 | TA-I TECHNOLOGY CO., LTD | RM04FTN1002 | G | PWA BOM | In New BOM |
|  |  |  | 61010G500-029-G | RES,10KOhm,+/-1%,1/16W,G,SMD0402 | VISHAY ENTER TECHNO LOGY.INC | CRCW040210K0FKED | G | PWA BOM | In New BOM |
|  |  |  | 61010G500-024-G | RES,10KOhm,+/-1%,1/16W,G,SMD0402 | PANASONIC INDUSTRIAL CO.,LTD. | ERJ2RKF1002X | G | PWA BOM | In New BOM |
|  | PANR5,PSTR6,PSLR6,PSFR6,PSER6,PSDR6,PQPR6,PFRR6,PEER6,PEDR6,PBNR6,PUAR7,PSIR7,PSAR7,PRAR7,PQAR7,PPAR7,PIAR7,PFAR7,PETR7,PERR7,PEAR7,PHAR22,PHAR39,PBER74,PAFR74,PAER74,PBMR75,PBFR75,PAMR75,PBAR78,PAAR78,PBMR300,PBFR300,PBER300,PBAR300,PAMR300,PAFR300,PAER300,PAAR300,PBMR305,PBFR305,PBER305,PBAR305,PAMR305,PAFR305,PAER305,PAAR305,PBMR306,PBFR306,PBER306,PBAR306,PAMR306,PAFR306,PAER306,PAAR306,PBMR307,PBFR307,PBER307,PBAR307,PAMR307,PAFR307,PAER307,PAAR307,R330,R351,R353,R357,R359,R480,R481,R482,R483,R719,R864,R908,R912,R913,R914,R915,R916,R920,R1075,R1076,R1077,R1078,R1118,R1136,R1137,R1441,R1482,R1490,R1534,R1535,R1536,R1537,R1538,R1539,R1540,PSRR3001 | 100 | 61010G500-017-G | RES,10KOhm,+/-1%,1/16W,G,SMD0402 | KOA SPEER ELECTRONICS, INC. | RK73H1ETTP1002F | N | PWA BOM | In Old BOM |
|  |  |  | 61010G500-012-G | RES,10KOhm,+/-1%,1/16W,G,SMD0402 | WALSIN | WR04X1002FTL | G | PWA BOM | In Old BOM |
|  |  |  | 61010G500-011-G | RES,10KOhm,+/-1%,1/16W,G,SMD0402 | YAGEO | RC0402FR-0710KL | G | PWA BOM | In Old BOM |
|  |  |  | 61010G500-044-G | RES,10KOhm,+/-1%,1/16W,G,SMD0402 | TA-I | RM04FTN1002 | G | PWA BOM | In Old BOM |
|  |  |  | 61010G500-029-G | RES,10KOhm,+/-1%,1/16W,G,SMD0402 | VISHAY ENTER TECHNO LOGY.INC | CRCW040210K0FKED | G | PWA BOM | In Old BOM |
|  |  |  | 61010G500-024-G | RES,10KOhm,+/-1%,1/16W,G,SMD0402 | PANASONIC INDUSTRIAL CO.,LTD. | ERJ2RKF1002X | G | PWA BOM | In Old BOM |
| 62 | PBMR81,PAMR81,PBER83,PAFR83,PAER83,PBFR84,PBAR84,PAAR84 | 8 | 61011A500-017-G | RES,1.74KOhm,+/-1%,1/16W,G,SMD0402 | KOA SPEER ELECTRONICS, INC. | RK73H1ETTP1741F | G | PWA BOM | In New BOM |
|  |  |  | 61011A500-012-G | RES,1.74KOhm,+/-1%,1/16W,G,SMD0402 | WALSIN TECHNOLOGY CORPORATION | WR04X1741FTL | G | PWA BOM | In New BOM |
|  |  |  | 61011A500-011-G | RES,1.74KOhm,+/-1%,1/16W,G,SMD0402 | YAGEO CORPORATION COMPONENT | RC0402FR-071K74L | G | PWA BOM | In New BOM |
|  |  |  | 61011A500-044-G | RES,1.74KOhm,+/-1%,1/16W,G,SMD0402 | TA-I TECHNOLOGY CO., LTD | RM04FTN1741 | G | PWA BOM | In New BOM |
|  |  |  | 61011A500-024-G | RES,1.74KOhm,+/-1%,1/16W,G,SMD0402 | PANASONIC INDUSTRIAL CO.,LTD. | ERJ2RKF1741X | G | PWA BOM | In New BOM |
|  | PBMR81,PAMR81,PBER83,PAFR83,PAER83,PBFR84,PBAR84,PAAR84 | 8 | 61011A500-017-G | RES,1.74KOhm,+/-1%,1/16W,G,SMD0402 | KOA SPEER ELECTRONICS, INC. | RK73H1ETTP1741F | N | PWA BOM | In Old BOM |
|  |  |  | 61011A500-012-G | RES,1.74KOhm,+/-1%,1/16W,G,SMD0402 | WALSIN | WR04X1741FTL | G | PWA BOM | In Old BOM |
|  |  |  | 61011A500-011-G | RES,1.74KOhm,+/-1%,1/16W,G,SMD0402 | YAGEO | RC0402FR-071K74L | G | PWA BOM | In Old BOM |
|  |  |  | 61011A500-044-G | RES,1.74KOhm,+/-1%,1/16W,G,SMD0402 | TA-I | RM04FTN1741 | G | PWA BOM | In Old BOM |
|  |  |  | 61011A500-024-G | RES,1.74KOhm,+/-1%,1/16W,G,SMD0402 | PANASONIC INDUSTRIAL CO.,LTD. | ERJ2RKF1741X | G | PWA BOM | In Old BOM |
| 63 | PSPR6,PIPR6,PFPR6,PEPR6,PALR14,PALR15,PALR19,PBLR20,PALR20,PBLR21,PBLR23,PBLR24,PBER68,PBMR82,PAMR82,PBAR85,PAAR85,PAFR87,PAER87,PBFR88,PBMR91,PAMR91,PBAR93,PAAR93,PBMR94,PAMR94,PBAR96,PAAR96,R1484,R1745,R1785 | 31 | 61100LR00-017-G | RES,100 Ohm,+/-1%,1/16W,G,SMD0402 | KOA SPEER ELECTRONICS, INC. | RN731ETTP1000F50 | G | PWA BOM | In New BOM |
|  |  |  | 61100LR00-012-G | RES,100 Ohm,+/-1%,1/16W,G,SMD0402 | WALSIN TECHNOLOGY CORPORATION | WF04T1000FTL | G | PWA BOM | In New BOM |
|  |  |  | 61100LR01-011-G | RES,100 Ohm,+/-1%,1/16W,G,SMD0402 | YAGEO CORPORATION COMPONENT | RT0402FRE07100RL | G | PWA BOM | In New BOM |
|  |  |  | 61100LR00-044-G | RES,100 Ohm,+/-1%,1/16W,G,SMD0402 | TA-I TECHNOLOGY CO., LTD | RB04FTS1000 | G | PWA BOM | In New BOM |
|  | PSPR6,PIPR6,PFPR6,PEPR6,PALR14,PALR15,PBLR20,PBLR21,PBER68,PBMR82,PAMR82,PBAR85,PAAR85,PAFR87,PAER87,PBFR88,PBMR91,PAMR91,PBAR93,PAAR93,PBMR94,PAMR94,PBAR96,PAAR96,R1484,R1745,R1785 | 27 | 61100LR00-017-G | RES,100 Ohm,+/-1%,1/16W,G,SMD0402 | KOA SPEER ELECTRONICS, INC. | RN731ETTP1000F50 |  | PWA BOM | In Old BOM |
|  |  |  | 61100LR00-012-G | RES,100 Ohm,+/-1%,1/16W,G,SMD0402 | WALSIN | WF04T1000FTL | G | PWA BOM | In Old BOM |
|  |  |  | 61100LR01-011-G | RES,100 Ohm,+/-1%,1/16W,G,SMD0402 | YAGEO | RT0402FRE07100RL | G | PWA BOM | In Old BOM |
|  |  |  | 61100LR00-044-G | RES,100 Ohm,+/-1%,1/16W,G,SMD0402 | TA-I | RB04FTS1000 | G | PWA BOM | In Old BOM |
| 64 | PBER85,PAFR85,PBMR86,PBFR86,PBAR86,PAMR86,PAAR86,PAER672 | 8 | 61010CB00-017-G | RES,49.9 Ohm,+/-1%,1/10W,G,SMD0603 | KOA SPEER ELECTRONICS, INC. | RK73H1JTTD49R9F | G | PWA BOM | In New BOM |
|  |  |  | 61010CB00-012-G | RES,49.9 Ohm,+/-1%,1/10W,G,SMD0603 | WALSIN TECHNOLOGY CORPORATION | WR06X49R9FTL | G | PWA BOM | In New BOM |
|  |  |  | 61010CB00-011-G | RES,49.9 Ohm,+/-1%,1/10W,G,SMD0603 | YAGEO CORPORATION COMPONENT | RC0603FR-0749R9L | G | PWA BOM | In New BOM |
|  |  |  | 61010CB00-044-G | RES,49.9 Ohm,+/-1%,1/10W,G,SMD0603 | TA-I TECHNOLOGY CO., LTD | RM06FTN49R9 | G | PWA BOM | In New BOM |
|  |  |  | 61010CB00-024-G | RES,49.9 Ohm,+/-1%,1/10W,G,SMD0603 | PANASONIC INDUSTRIAL CO.,LTD. | ERJ3EKF49R9V | G | PWA BOM | In New BOM |
|  | PBER85,PAFR85,PBMR86,PBFR86,PBAR86,PAMR86,PAAR86,PAER672 | 8 | 61010CB00-017-G | RES,49.9 Ohm,+/-1%,1/10W,G,SMD0603 | KOA SPEER ELECTRONICS, INC. | RK73H1JTTD49R9F | N | PWA BOM | In Old BOM |
|  |  |  | 61010CB00-012-G | RES,49.9 Ohm,+/-1%,1/10W,G,SMD0603 | WALSIN | WR06X49R9FTL | G | PWA BOM | In Old BOM |
|  |  |  | 61010CB00-011-G | RES,49.9 Ohm,+/-1%,1/10W,G,SMD0603 | YAGEO | RC0603FR-0749R9L | G | PWA BOM | In Old BOM |
|  |  |  | 61010CB00-044-G | RES,49.9 Ohm,+/-1%,1/10W,G,SMD0603 | TA-I | RM06FTN49R9 | G | PWA BOM | In Old BOM |
|  |  |  | 61010CB00-024-G | RES,49.9 Ohm,+/-1%,1/10W,G,SMD0603 | PANASONIC INDUSTRIAL CO.,LTD. | ERJ3EKF49R9V | G | PWA BOM | In Old BOM |
| 65 | PHAR4,PBMR90,PAMR90,PBER92,PBAR92,PAFR92,PAER92,PAAR92,PBFR93,PBAR102,PAAR102 | 11 | 610130Y00-017-G | RES,1 Ohm,+/-1%,1/3W,G,SMD1206 | KOA SPEER ELECTRONICS, INC. | SR732BTTD1R00F | G | PWA BOM | In New BOM |
|  |  |  | 610122P00-012-G | RES,1 Ohm,+/-1%,1/2W,G,SMD1206 | WALSIN TECHNOLOGY CORPORATION | WF12P1R00FTL | G | PWA BOM | In New BOM |
|  |  |  | 610122P00-011-G | RES,1 Ohm,+/-1%,1/2W,G,SMD1206 | YAGEO CORPORATION COMPONENT | RC1206FR-7W1RL | G | PWA BOM | In New BOM |
|  |  |  | 610122P00-044-G | RES,1 Ohm,+/-1%,1/2W,G,SMD1206 | TA-I TECHNOLOGY CO., LTD | RMH12FT1R00 | G | PWA BOM | In New BOM |
|  | PHAR4,PBMR90,PAMR90,PBER92,PBAR92,PAFR92,PAER92,PAAR92,PBFR93,PBAR102,PAAR102 | 11 | 610130Y00-017-G | RES,1 Ohm,+/-1%,1/3W,G,SMD1206 | KOA SPEER ELECTRONICS, INC. | SR732BTTD1R00F |  | PWA BOM | In Old BOM |
|  |  |  | 610122P00-012-G | RES,1 Ohm,+/-1%,1/2W,G,SMD1206 | WALSIN | WF12P1R00FTL | G | PWA BOM | In Old BOM |
|  |  |  | 610122P00-011-G | RES,1 Ohm,+/-1%,1/2W,G,SMD1206 | YAGEO | RC1206FR-7W1RL | G | PWA BOM | In Old BOM |
|  |  |  | 610122P00-044-G | RES,1 Ohm,+/-1%,1/2W,G,SMD1206 | TA-I | RMH12FT1R00 | G | PWA BOM | In Old BOM |
| 66 | PBMR26,PAMR26,PBMR97,PAMR97,PBMR98,PAMR98,PBER99,PAFR99,PAER99,PBMR100,PBFR100,PBER100,PAMR100,PAFR100,PAER100,PBFR101,PBMR102,PBER102,PAMR102,PAFR102,PAER102,PBFR103,PBAR103,PAAR103,PBER104,PBAR104,PAFR104,PAER104,PAAR104,PBFR105,PBAR106,PAAR106,PBAR108,PAAR108 | 34 | 611003200-017-G | RES,10KOhm,+/-0.1%,1/16W,G,SMD0402 | KOA SPEER ELECTRONICS, INC. | RN731ETTP1002B25 | G | PWA BOM | In New BOM |
|  |  |  | 611003200-012-G | RES,10KOhm,+/-0.1%,1/16W,G,SMD0402 | WALSIN TECHNOLOGY CORPORATION | WF04U1002BTL | G | PWA BOM | In New BOM |
|  |  |  | 611003200-011-G | RES,10KOhm,+/-0.1%,1/16W,G,SMD0402 | YAGEO CORPORATION COMPONENT | RT0402BRE0710KL | G | PWA BOM | In New BOM |
|  |  |  | 611003200-044-G | RES,10KOhm,+/-0.1%,1/16W,G,SMD0402 | TA-I TECHNOLOGY CO., LTD | RB04BTP1002 | G | PWA BOM | In New BOM |
|  | PBMR26,PAMR26,PBMR97,PAMR97,PBMR98,PAMR98,PBER99,PAFR99,PAER99,PBMR100,PBFR100,PBER100,PAMR100,PAFR100,PAER100,PBFR101,PBMR102,PBER102,PAMR102,PAFR102,PAER102,PBFR103,PBAR103,PAAR103,PBER104,PBAR104,PAFR104,PAER104,PAAR104,PBFR105,PBAR106,PAAR106,PBAR108,PAAR108 | 34 | 611003200-017-G | RES,10KOhm,+/-0.1%,1/16W,G,SMD0402 | KOA SPEER ELECTRONICS, INC. | RN731ETTP1002B25 | Y | PWA BOM | In Old BOM |
|  |  |  | 611003200-012-G | RES,10KOhm,+/-0.1%,1/16W,G,SMD0402 | WALSIN | WF04U1002BTL | G | PWA BOM | In Old BOM |
|  |  |  | 611003200-011-G | RES,10KOhm,+/-0.1%,1/16W,G,SMD0402 | YAGEO | RT0402BRE0710KL | G | PWA BOM | In Old BOM |
|  |  |  | 611003200-044-G | RES,10KOhm,+/-0.1%,1/16W,G,SMD0402 | TA-I | RB04BTP1002 | G | PWA BOM | In Old BOM |
| 67 | PBMR107,PAMR107,PBER109,PAFR109,PAER109,PBFR110,PBAR113,PAAR113,R1844 | 9 | 61011B300-017-G | RES,1MOhm,+/-1%,1/16W,G,SMD0402 | KOA SPEER ELECTRONICS, INC. | RK73H1ETTP1004F | G | PWA BOM | In New BOM |
|  |  |  | 61011B300-012-G | RES,1MOhm,+/-1%,1/16W,G,SMD0402 | WALSIN TECHNOLOGY CORPORATION | WR04X1004FTL | G | PWA BOM | In New BOM |
|  |  |  | 61011B300-011-G | RES,1MOhm,+/-1%,1/16W,G,SMD0402 | YAGEO CORPORATION COMPONENT | RC0402FR-071ML | G | PWA BOM | In New BOM |
|  |  |  | 61011B300-044-G | RES,1MOhm,+/-1%,1/16W,G,SMD0402 | TA-I TECHNOLOGY CO., LTD | RM04FTN1004 | G | PWA BOM | In New BOM |
|  | PBMR107,PAMR107,PBER109,PAFR109,PAER109,PBFR110,PBAR113,PAAR113,R1844 | 9 | 61011B300-017-G | RES,1MOhm,+/-1%,1/16W,G,SMD0402 | KOA SPEER ELECTRONICS, INC. | RK73H1ETTP1004F | N | PWA BOM | In Old BOM |
|  |  |  | 61011B300-012-G | RES,1MOhm,+/-1%,1/16W,G,SMD0402 | WALSIN | WR04X1004FTL | G | PWA BOM | In Old BOM |
|  |  |  | 61011B300-011-G | RES,1MOhm,+/-1%,1/16W,G,SMD0402 | YAGEO | RC0402FR-071ML | G | PWA BOM | In Old BOM |
|  |  |  | 61011B300-044-G | RES,1MOhm,+/-1%,1/16W,G,SMD0402 | TA-I | RM04FTN1004 | G | PWA BOM | In Old BOM |
| 68 | PBMR109,PAMR109,PBER111,PAFR111,PAER111,PBFR112,PBAR115,PAAR115 | 8 | 61011GU00-017-G | RES,274 Ohm,+/-1%,1/16W,G,SMD0402 | KOA SPEER ELECTRONICS, INC. | RK73H1ETTP2740F | G | PWA BOM | In New BOM |
|  |  |  | 61011GU00-012-G | RES,274 Ohm,+/-1%,1/16W,G,SMD0402 | WALSIN TECHNOLOGY CORPORATION | WR04X2740FTL | G | PWA BOM | In New BOM |
|  |  |  | 61011GU00-011-G | RES,274 Ohm,+/-1%,1/16W,G,SMD0402 | YAGEO CORPORATION COMPONENT | RC0402FR-07274RL | G | PWA BOM | In New BOM |
|  |  |  | 61011GU00-044-G | RES,274 Ohm,+/-1%,1/16W,G,SMD0402 | TA-I TECHNOLOGY CO., LTD | RM04FTN2740 | G | PWA BOM | In New BOM |
|  | PBMR109,PAMR109,PBER111,PAFR111,PAER111,PBFR112,PBAR115,PAAR115 | 8 | 61011GU00-017-G | RES,274 Ohm,+/-1%,1/16W,G,SMD0402 | KOA SPEER ELECTRONICS, INC. | RK73H1ETTP2740F | N | PWA BOM | In Old BOM |
|  |  |  | 61011GU00-012-G | RES,274 Ohm,+/-1%,1/16W,G,SMD0402 | WALSIN | WR04X2740FTL | G | PWA BOM | In Old BOM |
|  |  |  | 61011GU00-011-G | RES,274 Ohm,+/-1%,1/16W,G,SMD0402 | YAGEO | RC0402FR-07274RL | G | PWA BOM | In Old BOM |
|  |  |  | 61011GU00-044-G | RES,274 Ohm,+/-1%,1/16W,G,SMD0402 | TA-I | RM04FTN2740 | G | PWA BOM | In Old BOM |
| 69 | PBMR113,PAMR113,PBER115,PAFR115,PAER115,PBFR116,PBAR119,PAAR119 | 8 | 61100RU00-017-G | RES,59 Ohm,+/-1%,1/16W,G,SMD0402 | KOA SPEER ELECTRONICS, INC. | RN731ETTP59R0F25 | G | PWA BOM | In New BOM |
|  |  |  | 61100RU00-011-G | RES,59 Ohm,+/-1%,1/16W,G,SMD0402 | YAGEO CORPORATION COMPONENT | RT0402FRE0759RL | G | PWA BOM | In New BOM |
|  | PBMR113,PAMR113,PBER115,PAFR115,PAER115,PBFR116,PBAR119,PAAR119 | 8 | 61100RU00-017-G | RES,59 Ohm,+/-1%,1/16W,G,SMD0402 | KOA SPEER ELECTRONICS, INC. | RN731ETTP59R0F25 |  | PWA BOM | In Old BOM |
|  |  |  | 61100RU00-011-G | RES,59 Ohm,+/-1%,1/16W,G,SMD0402 | YAGEO | RT0402FRE0759RL | G | PWA BOM | In Old BOM |
| 70 | PBMR117,PAMR117,PBER119,PAFR119,PAER119,PBFR120,PBAR123,PAAR123 | 8 | 610114P00-017-G | RES,715 Ohm,+/-1%,1/16W,G,SMD0402 | KOA SPEER ELECTRONICS, INC. | RK73H1ETTP7150F | G | PWA BOM | In New BOM |
|  |  |  | 610114P00-012-G | RES,715 Ohm,+/-1%,1/16W,G,SMD0402 | WALSIN TECHNOLOGY CORPORATION | WR04X7150FTL | G | PWA BOM | In New BOM |
|  |  |  | 610114P00-011-G | RES,715 Ohm,+/-1%,1/16W,G,SMD0402 | YAGEO CORPORATION COMPONENT | RC0402FR-07715RL | G | PWA BOM | In New BOM |
|  | PBMR117,PAMR117,PBER119,PAFR119,PAER119,PBFR120,PBAR123,PAAR123 | 8 | 610114P00-017-G | RES,715 Ohm,+/-1%,1/16W,G,SMD0402 | KOA SPEER ELECTRONICS, INC. | RK73H1ETTP7150F | N | PWA BOM | In Old BOM |
|  |  |  | 610114P00-012-G | RES,715 Ohm,+/-1%,1/16W,G,SMD0402 | WALSIN | WR04X7150FTL | G | PWA BOM | In Old BOM |
|  |  |  | 610114P00-011-G | RES,715 Ohm,+/-1%,1/16W,G,SMD0402 | YAGEO | RC0402FR-07715RL | G | PWA BOM | In Old BOM |
| 71 | PHAR79,PBMR118,PAMR118,PBER120,PAFR120,PAER120,PBFR121,PBAR124,PAAR124 | 9 | 61011L200-017-G | RES,3.65KOhm,+/-1%,1/16W,G,SMD0402 | KOA SPEER ELECTRONICS, INC. | RK73H1ETTP3651F | G | PWA BOM | In New BOM |
|  |  |  | 61011L200-012-G | RES,3.65KOhm,+/-1%,1/16W,G,SMD0402 | WALSIN TECHNOLOGY CORPORATION | WR04X3651FTL | G | PWA BOM | In New BOM |
|  |  |  | 61011L200-011-G | RES,3.65KOhm,+/-1%,1/16W,G,SMD0402 | YAGEO CORPORATION COMPONENT | RC0402FR-073K65L | G | PWA BOM | In New BOM |
|  |  |  | 61011L200-044-G | RES,3.65KOhm,+/-1%,1/16W,G,SMD0402 | TA-I TECHNOLOGY CO., LTD | RM04FTN3651 | G | PWA BOM | In New BOM |
|  | PHAR79,PBMR118,PAMR118,PBER120,PAFR120,PAER120,PBFR121,PBAR124,PAAR124 | 9 | 61011L200-017-G | RES,3.65KOhm,+/-1%,1/16W,G,SMD0402 | KOA SPEER ELECTRONICS, INC. | RK73H1ETTP3651F | N | PWA BOM | In Old BOM |
|  |  |  | 61011L200-012-G | RES,3.65KOhm,+/-1%,1/16W,G,SMD0402 | WALSIN | WR04X3651FTL | G | PWA BOM | In Old BOM |
|  |  |  | 61011L200-011-G | RES,3.65KOhm,+/-1%,1/16W,G,SMD0402 | YAGEO | RC0402FR-073K65L | G | PWA BOM | In Old BOM |
|  |  |  | 61011L200-044-G | RES,3.65KOhm,+/-1%,1/16W,G,SMD0402 | TA-I | RM04FTN3651 | G | PWA BOM | In Old BOM |
| 72 | PBMR304,PBAR304,PAMR304,PAAR304 | 4 | 61011BH00-017-G | RES,22.1 Ohm,+/-1%,1/16W,G,SMD0402 | KOA SPEER ELECTRONICS, INC. | RK73H1ETTP22R1F | G | PWA BOM | In New BOM |
|  |  |  | 61011BH00-012-G | RES,22.1 Ohm,+/-1%,1/16W,G,SMD0402 | WALSIN TECHNOLOGY CORPORATION | WR04X22R1FTL | G | PWA BOM | In New BOM |
|  |  |  | 61011BH00-011-G | RES,22.1 Ohm,+/-1%,1/16W,G,SMD0402 | YAGEO CORPORATION COMPONENT | RC0402FR-0722R1L | G | PWA BOM | In New BOM |
|  |  |  | 61011BH00-044-G | RES,22.1 Ohm,+/-1%,1/16W,G,SMD0402 | TA-I TECHNOLOGY CO., LTD | RM04FTN22R1 | G | PWA BOM | In New BOM |
|  | PBMR304,PBAR304,PAMR304,PAAR304 | 4 | 61011BH00-017-G | RES,22.1 Ohm,+/-1%,1/16W,G,SMD0402 | KOA SPEER ELECTRONICS, INC. | RK73H1ETTP22R1F | N | PWA BOM | In Old BOM |
|  |  |  | 61011BH00-012-G | RES,22.1 Ohm,+/-1%,1/16W,G,SMD0402 | WALSIN | WR04X22R1FTL | G | PWA BOM | In Old BOM |
|  |  |  | 61011BH00-011-G | RES,22.1 Ohm,+/-1%,1/16W,G,SMD0402 | YAGEO | RC0402FR-0722R1L | G | PWA BOM | In Old BOM |
|  |  |  | 61011BH00-044-G | RES,22.1 Ohm,+/-1%,1/16W,G,SMD0402 | TA-I | RM04FTN22R1 | G | PWA BOM | In Old BOM |
| 73 | PUAR13,PSAR13,PRAR13,PQAR13,PPAR13,PIAR13,PFAR13,PEAR13,PSIR14,PETR14,PERR14,PALR18,PSTR20,PSLR20,PSFR20,PSER20,PSDR20,PQPR20,PFRR20,PEER20,PEDR20,PBLR22,PBMR452,PBNR502,PBFR502,PBER502,PANR502,PAMR502,PAFR502,PAAR502,PBAR504,PAER514,PSPR3000,PIPR3000,PFPR3000,PEPR3000,PSRR3009 | 37 | 61012JH00-017-G | RES,470 Ohm,+/-5%,1/8W,G,SMD0805 | KOA SPEER ELECTRONICS, INC. | RK73B2ATTD471J | G | PWA BOM | In New BOM |
|  |  |  | 61012JH00-012-G | RES,470 Ohm,+/-5%,1/8W,G,SMD0805 | WALSIN TECHNOLOGY CORPORATION | WR08X471JTL | G | PWA BOM | In New BOM |
|  |  |  | 61012JH00-011-G | RES,470 Ohm,+/-5%,1/8W,G,SMD0805 | YAGEO CORPORATION COMPONENT | RC0805JR-07470RL | G | PWA BOM | In New BOM |
|  |  |  | 61012JH00-044-G | RES,470 Ohm,+/-5%,1/8W,G,SMD0805 | TA-I TECHNOLOGY CO., LTD | RM10JTN471 | G | PWA BOM | In New BOM |
|  | PUAR13,PSAR13,PRAR13,PQAR13,PPAR13,PIAR13,PFAR13,PEAR13,PSIR14,PETR14,PERR14,PALR18,PSTR20,PSLR20,PSFR20,PSER20,PSDR20,PQPR20,PFRR20,PEER20,PEDR20,PBLR22,PBMR452,PBNR502,PBFR502,PBER502,PANR502,PAMR502,PAFR502,PAAR502,PBAR504,PAER514,PSPR3000,PIPR3000,PFPR3000,PEPR3000,PSRR3009 | 37 | 61012JH00-017-G | RES,470 Ohm,+/-5%,1/8W,G,SMD0805 | KOA SPEER ELECTRONICS, INC. | RK73B2ATTD471J | N | PWA BOM | In Old BOM |
|  |  |  | 61012JH00-012-G | RES,470 Ohm,+/-5%,1/8W,G,SMD0805 | WALSIN | WR08X471JTL | G | PWA BOM | In Old BOM |
|  |  |  | 61012JH00-011-G | RES,470 Ohm,+/-5%,1/8W,G,SMD0805 | YAGEO | RC0805JR-07470RL | G | PWA BOM | In Old BOM |
|  |  |  | 61012JH00-044-G | RES,470 Ohm,+/-5%,1/8W,G,SMD0805 | TA-I | RM10JTN471 | G | PWA BOM | In Old BOM |
| 74 | R347,R348,R350,PBFR510,PBER510,PAFR510,PAER510,PBMR600,PBAR600,PAMR600,PAAR600 | 11 | 610114J00-017-G | RES,2KOhm,+/-1%,1/16W,G,SMD0402 | KOA SPEER ELECTRONICS, INC. | RK73H1ETTP2001F | G | PWA BOM | In New BOM |
|  |  |  | 610114J00-012-G | RES,2KOhm,+/-1%,1/16W,G,SMD0402 | WALSIN TECHNOLOGY CORPORATION | WR04X2001FTL | G | PWA BOM | In New BOM |
|  |  |  | 610114J00-011-G | RES,2KOhm,+/-1%,1/16W,G,SMD0402 | YAGEO CORPORATION COMPONENT | RC0402FR-072KL | G | PWA BOM | In New BOM |
|  |  |  | 610114J00-044-G | RES,2KOhm,+/-1%,1/16W,G,SMD0402 | TA-I TECHNOLOGY CO., LTD | RM04FTN2001 | G | PWA BOM | In New BOM |
|  |  |  | 610114J00-024-G | RES,2KOhm,+/-1%,1/16W,G,SMD0402 | PANASONIC INDUSTRIAL CO.,LTD. | ERJ2RKF2001X | G | PWA BOM | In New BOM |
|  |  |  | 610114J00-029-G | RES,2KOhm,+/-1%,1/16W,G,SMD0402 | VISHAY ENTER TECHNO LOGY.INC | CRCW04022K00FKED | G | PWA BOM | In New BOM |
|  | R347,R348,R350,PBFR510,PBER510,PAFR510,PAER510,PBMR600,PBAR600,PAMR600,PAAR600 | 11 | 610114J00-017-G | RES,2KOhm,+/-1%,1/16W,G,SMD0402 | KOA SPEER ELECTRONICS, INC. | RK73H1ETTP2001F | N | PWA BOM | In Old BOM |
|  |  |  | 610114J00-012-G | RES,2KOhm,+/-1%,1/16W,G,SMD0402 | WALSIN | WR04X2001FTL | G | PWA BOM | In Old BOM |
|  |  |  | 610114J00-011-G | RES,2KOhm,+/-1%,1/16W,G,SMD0402 | YAGEO | RC0402FR-072KL | G | PWA BOM | In Old BOM |
|  |  |  | 610114J00-044-G | RES,2KOhm,+/-1%,1/16W,G,SMD0402 | TA-I | RM04FTN2001 | G | PWA BOM | In Old BOM |
|  |  |  | 610114J00-024-G | RES,2KOhm,+/-1%,1/16W,G,SMD0402 | PANASONIC INDUSTRIAL CO.,LTD. | ERJ2RKF2001X | G | PWA BOM | In Old BOM |
|  |  |  | 610114J00-029-G | RES,2KOhm,+/-1%,1/16W,G,SMD0402 | VISHAY ENTER TECHNO LOGY.INC | CRCW04022K00FKED | G | PWA BOM | In Old BOM |
| 75 | PBFR511,PBER511,PAFR511,PAER511,PBMR603,PBAR603,PAMR603,PAAR603,PBMR604,PBAR604,PAMR604,PAAR604,PAFR634,PBFR659,PBER659,PAER684,R1559 | 17 | 61010L100-017-G | RES,100KOhm,+/-1%,1/16W,G,SMD0402 | KOA SPEER ELECTRONICS, INC. | RK73H1ETTP1003F | G | PWA BOM | In New BOM |
|  |  |  | 61010L100-012-G | RES,100KOhm,+/-1%,1/16W,G,SMD0402 | WALSIN TECHNOLOGY CORPORATION | WR04X1003FTL | G | PWA BOM | In New BOM |
|  |  |  | 61010L100-011-G | RES,100KOhm,+/-1%,1/16W,G,SMD0402 | YAGEO CORPORATION COMPONENT | RC0402FR-07100KL | G | PWA BOM | In New BOM |
|  |  |  | 61010L100-044-G | RES,100KOhm,+/-1%,1/16W,G,SMD0402 | TA-I TECHNOLOGY CO., LTD | RM04FTN1003 | G | PWA BOM | In New BOM |
|  |  |  | 61010L106-029-G | RES,100KOhm,+/-1%,1/16W,G,SMD0402 | VISHAY ENTER TECHNO LOGY.INC | CRCW0402100KFKEDC | G | PWA BOM | In New BOM |
|  |  |  | 61010L100-024-G | RES,100KOhm,+/-1%,1/16W,G,SMD0402 | PANASONIC INDUSTRIAL CO.,LTD. | ERJ2RKF1003X | G | PWA BOM | In New BOM |
|  | PBFR511,PBER511,PAFR511,PAER511,PBMR603,PBAR603,PAMR603,PAAR603,PBMR604,PBAR604,PAMR604,PAAR604,PAFR634,PBFR659,PBER659,PAER684 | 16 | 61010L100-017-G | RES,100KOhm,+/-1%,1/16W,G,SMD0402 | KOA SPEER ELECTRONICS, INC. | RK73H1ETTP1003F | N | PWA BOM | In Old BOM |
|  |  |  | 61010L100-012-G | RES,100KOhm,+/-1%,1/16W,G,SMD0402 | WALSIN | WR04X1003FTL | G | PWA BOM | In Old BOM |
|  |  |  | 61010L100-011-G | RES,100KOhm,+/-1%,1/16W,G,SMD0402 | YAGEO | RC0402FR-07100KL | G | PWA BOM | In Old BOM |
|  |  |  | 61010L100-044-G | RES,100KOhm,+/-1%,1/16W,G,SMD0402 | TA-I | RM04FTN1003 | G | PWA BOM | In Old BOM |
|  |  |  | 61010L106-029-G | RES,100KOhm,+/-1%,1/16W,G,SMD0402 | VISHAY ENTER TECHNO LOGY.INC | CRCW0402100KFKEDC | G | PWA BOM | In Old BOM |
|  |  |  | 61010L100-024-G | RES,100KOhm,+/-1%,1/16W,G,SMD0402 | PANASONIC INDUSTRIAL CO.,LTD. | ERJ2RKF1003X | G | PWA BOM | In Old BOM |
| 76 | PBMR605,PBAR605,PAMR605,PAAR605 | 4 | 61013A200-017-G | RES,6.8 Ohm,+/-1%,1/4W,G,SMD1206 | KOA SPEER ELECTRONICS, INC. | RK73H2BTTD6R80F | G | PWA BOM | In New BOM |
|  |  |  | 61013A200-011-G | RES,6.8 Ohm,+/-1%,1/4W,G,SMD1206 | YAGEO CORPORATION COMPONENT | RC1206FR-076R8L | G | PWA BOM | In New BOM |
|  |  |  | 61013A200-044-G | RES,6.8 Ohm,+/-1%,1/4W,G,SMD1206 | TA-I TECHNOLOGY CO., LTD | RM12FTN6R8 | G | PWA BOM | In New BOM |
|  |  |  | 61013A200-029-G | RES,6.8 Ohm,+/-1%,1/4W,G,SMD1206 | VISHAY ENTER TECHNO LOGY.INC | CRCW12066R80FKEA | G | PWA BOM | In New BOM |
|  | PBMR605,PBAR605,PAMR605,PAAR605 | 4 | 61013A200-017-G | RES,6.8 Ohm,+/-1%,1/4W,G,SMD1206 | KOA SPEER ELECTRONICS, INC. | RK73H2BTTD6R80F |  | PWA BOM | In Old BOM |
|  |  |  | 61013A200-011-G | RES,6.8 Ohm,+/-1%,1/4W,G,SMD1206 | YAGEO | RC1206FR-076R8L | G | PWA BOM | In Old BOM |
|  |  |  | 61013A200-044-G | RES,6.8 Ohm,+/-1%,1/4W,G,SMD1206 | TA-I | RM12FTN6R8 | G | PWA BOM | In Old BOM |
|  |  |  | 61013A200-029-G | RES,6.8 Ohm,+/-1%,1/4W,G,SMD1206 | VISHAY ENTER TECHNO LOGY.INC | CRCW12066R80FKEA | G | PWA BOM | In Old BOM |
| 77 | PBFR512,PBER512,PAFR512,PAER512,PBMR606,PBAR606,PAMR606,PAAR606 | 8 | 61011MG00-017-G | RES,42.2KOhm,+/-1%,1/16W,G,SMD0402 | KOA SPEER ELECTRONICS, INC. | RK73H1ETTP4222F | G | PWA BOM | In New BOM |
|  |  |  | 61011MG00-012-G | RES,42.2KOhm,+/-1%,1/16W,G,SMD0402 | WALSIN TECHNOLOGY CORPORATION | WR04X4222FTL | G | PWA BOM | In New BOM |
|  |  |  | 61011MG00-011-G | RES,42.2KOhm,+/-1%,1/16W,G,SMD0402 | YAGEO CORPORATION COMPONENT | RC0402FR-0742K2L | G | PWA BOM | In New BOM |
|  |  |  | 61011MG00-044-G | RES,42.2KOhm,+/-1%,1/16W,G,SMD0402 | TA-I TECHNOLOGY CO., LTD | RM04FTN4222 | G | PWA BOM | In New BOM |
|  | PBFR512,PBER512,PAFR512,PAER512,PBMR606,PBAR606,PAMR606,PAAR606 | 8 | 61011MG00-017-G | RES,42.2KOhm,+/-1%,1/16W,G,SMD0402 | KOA SPEER ELECTRONICS, INC. | RK73H1ETTP4222F | N | PWA BOM | In Old BOM |
|  |  |  | 61011MG00-012-G | RES,42.2KOhm,+/-1%,1/16W,G,SMD0402 | WALSIN | WR04X4222FTL | G | PWA BOM | In Old BOM |
|  |  |  | 61011MG00-011-G | RES,42.2KOhm,+/-1%,1/16W,G,SMD0402 | YAGEO | RC0402FR-0742K2L | G | PWA BOM | In Old BOM |
|  |  |  | 61011MG00-044-G | RES,42.2KOhm,+/-1%,1/16W,G,SMD0402 | TA-I | RM04FTN4222 | G | PWA BOM | In Old BOM |
| 78 | PBFC59,PBEC59,PAFC59,PAEC59 | 4 | 62010WW01-015-G | CAP,1.8nF,+/-10%,X7R,50V,G,SMD0402 | MURATA ELEC. NORTH AMERICA | GRM155R71H182KA01D | G | PWA BOM | In New BOM |
|  |  |  | 62010WW00-026-G | CAP,1.8nF,+/-10%,X7R,50V,G,SMD0402 | SAMSUNG SEMICONDUCTOR | CL05B182KB5NNNC | G | PWA BOM | In New BOM |
|  | PBFC59,PBEC59,PAFC59,PAEC59 | 4 | 62010WW01-015-G | CAP,1.8nF,+/-10%,X7R,50V,G,SMD0402 | MURATA ELEC. NORTH AMERICA | GRM155R71H182KA01D | N | PWA BOM | In Old BOM |
|  |  |  | 62010WW00-026-G | CAP,1.8nF,+/-10%,X7R,50V,G,SMD0402 | SAMSUNG | CL05B182KB5NNNC | G | PWA BOM | In Old BOM |
| 79 | PBFC60,PBEC60,PAFC60,PAEC60,PBMC61,PAMC61 | 6 | 62011FQ00-015-G | CAP,5.6nF,+/-10%,X7R,50V,G,SMD0402 | MURATA ELEC. NORTH AMERICA | GRM155R71H562K | G | PWA BOM | In New BOM |
|  |  |  | 62011FQ00-026-G | CAP,5.6nF,+/-10%,X7R,50V,G,SMD0402 | SAMSUNG SEMICONDUCTOR | CL05B562KB5NNNC | G | PWA BOM | In New BOM |
|  |  |  | 62011FQ00-023-G | CAP,5.6nF,+/-10%,X7R,50V,G,SMD0402 | TAIYO ELECTRIC IND.CO.LTD | UMK105B7562KV-F | G | PWA BOM | In New BOM |
|  | PBFC60,PBEC60,PAFC60,PAEC60,PBMC61,PAMC61 | 6 | 62011FQ00-015-G | CAP,5.6nF,+/-10%,X7R,50V,G,SMD0402 | MURATA ELEC. NORTH AMERICA | GRM155R71H562K | N | PWA BOM | In Old BOM |
|  |  |  | 62011FQ00-026-G | CAP,5.6nF,+/-10%,X7R,50V,G,SMD0402 | SAMSUNG | CL05B562KB5NNNC | G | PWA BOM | In Old BOM |
|  |  |  | 62011FQ00-023-G | CAP,5.6nF,+/-10%,X7R,50V,G,SMD0402 | TAIYO | UMK105B7562KV-F | G | PWA BOM | In Old BOM |
| 80 | PBFL1,PBEL1,PAFL1,PAEL1,PBML2,PAML2 | 6 | 63035NF00-57M-G | IND,1.5uH@100KHz,+/-10%,12A,6mOhm,SHLD,G,SMD | Eaton Corporation | HCV1206-1R5-R | G | PWA BOM | In New BOM |
|  |  |  | HMS1360-1R5 | IND,HMS1360-1R5 | DELTA ELECTRONICS INDUSTRIAL CO.,LTD | HMS1360-1R5 | G | PWA BOM | In New BOM |
|  | PBFL1,PBEL1,PAFL1,PAEL1,PBML2,PAML2 | 6 | 63035NF00-57M-G | IND,1.5uH@100KHz,+/-10%,12A,6mOhm,SHLD,G,SMD | Eaton Corporation | HCV1206-1R5-R |  | PWA BOM | In Old BOM |
|  |  |  | HMS1360-1R5 | IND,HMS1360-1R5 | Delta | HMS1360-1R5 | G | PWA BOM | In Old BOM |
| 81 | PBER4,PAER4,R972,R1090 | 4 | 610117V00-017-G | RES,680 Ohm,+/-1%,1/16W,G,SMD0402 | KOA SPEER ELECTRONICS, INC. | RK73H1ETTP6800F | G | PWA BOM | In New BOM |
|  |  |  | 610117V00-012-G | RES,680 Ohm,+/-1%,1/16W,G,SMD0402 | WALSIN TECHNOLOGY CORPORATION | WR04X6800FTL | G | PWA BOM | In New BOM |
|  |  |  | 610117V00-011-G | RES,680 Ohm,+/-1%,1/16W,G,SMD0402 | YAGEO CORPORATION COMPONENT | RC0402FR-07680RL | G | PWA BOM | In New BOM |
|  |  |  | 610117V00-044-G | RES,680 Ohm,+/-1%,1/16W,G,SMD0402 | TA-I TECHNOLOGY CO., LTD | RM04FTN6800 | G | PWA BOM | In New BOM |
|  | PBER4,PAER4,R972,R1090 | 4 | 610117V00-017-G | RES,680 Ohm,+/-1%,1/16W,G,SMD0402 | KOA SPEER ELECTRONICS, INC. | RK73H1ETTP6800F | N | PWA BOM | In Old BOM |
|  |  |  | 610117V00-012-G | RES,680 Ohm,+/-1%,1/16W,G,SMD0402 | WALSIN | WR04X6800FTL | G | PWA BOM | In Old BOM |
|  |  |  | 610117V00-011-G | RES,680 Ohm,+/-1%,1/16W,G,SMD0402 | YAGEO | RC0402FR-07680RL | G | PWA BOM | In Old BOM |
|  |  |  | 610117V00-044-G | RES,680 Ohm,+/-1%,1/16W,G,SMD0402 | TA-I | RM04FTN6800 | G | PWA BOM | In Old BOM |
| 82 | PBFR26,PBER26,PAFR26,PAER26 | 4 | 61100RN00-017-G | RES,15.4KOhm,+/-0.1%,1/16W,G,SMD0402 | KOA SPEER ELECTRONICS, INC. | RN731ETTP1542B25 | G | PWA BOM | In New BOM |
|  |  |  | 61100RN00-012-G | RES,15.4KOhm,+/-0.1%,1/16W,G,SMD0402 | WALSIN TECHNOLOGY CORPORATION | WF04U1542BTL | G | PWA BOM | In New BOM |
|  |  |  | 61100RN00-011-G | RES,15.4KOhm,+/-0.1%,1/16W,G,SMD0402 | YAGEO CORPORATION COMPONENT | RT0402BRD0715K4L | G | PWA BOM | In New BOM |
|  |  |  | 61100RN00-044-G | RES,15.4KOhm,+/-0.1%,1/16W,G,SMD0402 | TA-I TECHNOLOGY CO., LTD | RB04BTP1542 | G | PWA BOM | In New BOM |
|  | PBFR26,PBER26,PAFR26,PAER26 | 4 | 61100RN00-017-G | RES,15.4KOhm,+/-0.1%,1/16W,G,SMD0402 | KOA SPEER ELECTRONICS, INC. | RN731ETTP1542B25 | Y | PWA BOM | In Old BOM |
|  |  |  | 61100RN00-012-G | RES,15.4KOhm,+/-0.1%,1/16W,G,SMD0402 | WALSIN | WF04U1542BTL | G | PWA BOM | In Old BOM |
|  |  |  | 61100RN00-011-G | RES,15.4KOhm,+/-0.1%,1/16W,G,SMD0402 | YAGEO | RT0402BRD0715K4L | G | PWA BOM | In Old BOM |
|  |  |  | 61100RN00-044-G | RES,15.4KOhm,+/-0.1%,1/16W,G,SMD0402 | TA-I | RB04BTP1542 | G | PWA BOM | In Old BOM |
| 83 | PBFR47,PBER47,PAFR47,PAER47,R781,R782,R1018,R1024,R1730 | 9 | 61011DR00-017-G | RES,2.2KOhm,+/-1%,1/16W,G,SMD0402 | KOA SPEER ELECTRONICS, INC. | RK73H1ETTP2201F | G | PWA BOM | In New BOM |
|  |  |  | 61011DR00-012-G | RES,2.2KOhm,+/-1%,1/16W,G,SMD0402 | WALSIN TECHNOLOGY CORPORATION | WR04X2201FTL | G | PWA BOM | In New BOM |
|  |  |  | 61011DR00-011-G | RES,2.2KOhm,+/-1%,1/16W,G,SMD0402 | YAGEO CORPORATION COMPONENT | RC0402FR-072K2L | G | PWA BOM | In New BOM |
|  |  |  | 61011DR00-044-G | RES,2.2KOhm,+/-1%,1/16W,G,SMD0402 | TA-I TECHNOLOGY CO., LTD | RM04FTN2201 | G | PWA BOM | In New BOM |
|  |  |  | 61011DR00-029-G | RES,2.2KOhm,+/-1%,1/16W,G,SMD0402 | VISHAY ENTER TECHNO LOGY.INC | CRCW04022K20FKED | G | PWA BOM | In New BOM |
|  | PBFR47,PBER47,PAFR47,PAER47,R781,R782,R1018,R1024,R1730 | 9 | 61011DR00-017-G | RES,2.2KOhm,+/-1%,1/16W,G,SMD0402 | KOA SPEER ELECTRONICS, INC. | RK73H1ETTP2201F | N | PWA BOM | In Old BOM |
|  |  |  | 61011DR00-012-G | RES,2.2KOhm,+/-1%,1/16W,G,SMD0402 | WALSIN | WR04X2201FTL | G | PWA BOM | In Old BOM |
|  |  |  | 61011DR00-011-G | RES,2.2KOhm,+/-1%,1/16W,G,SMD0402 | YAGEO | RC0402FR-072K2L | G | PWA BOM | In Old BOM |
|  |  |  | 61011DR00-044-G | RES,2.2KOhm,+/-1%,1/16W,G,SMD0402 | TA-I | RM04FTN2201 | G | PWA BOM | In Old BOM |
|  |  |  | 61011DR00-029-G | RES,2.2KOhm,+/-1%,1/16W,G,SMD0402 | VISHAY ENTER TECHNO LOGY.INC | CRCW04022K20FKED | G | PWA BOM | In Old BOM |
| 84 | PBER58,PAFR58,PAER58,PBFR59,PBMR61,PAMR61 | 6 | 610108V00-017-G | RES,2KOhm,+/-1%,1/10W,G,SMD0603 | KOA SPEER ELECTRONICS, INC. | RK73H1JTTD2001F | G | PWA BOM | In New BOM |
|  |  |  | 610108V00-012-G | RES,2KOhm,+/-1%,1/10W,G,SMD0603 | WALSIN TECHNOLOGY CORPORATION | WR06X2001FTL | G | PWA BOM | In New BOM |
|  |  |  | 610108V00-011-G | RES,2KOhm,+/-1%,1/10W,G,SMD0603 | YAGEO CORPORATION COMPONENT | RC0603FR-072KL | G | PWA BOM | In New BOM |
|  |  |  | 610108V00-044-G | RES,2KOhm,+/-1%,1/10W,G,SMD0603 | TA-I TECHNOLOGY CO., LTD | RM06FTN2001 | G | PWA BOM | In New BOM |
|  |  |  | 610108V00-024-G | RES,2KOhm,+/-1%,1/10W,G,SMD0603 | PANASONIC INDUSTRIAL CO.,LTD. | ERJ3EKF2001V | G | PWA BOM | In New BOM |
|  | PBER58,PAFR58,PAER58,PBFR59,PBMR61,PAMR61 | 6 | 610108V00-017-G | RES,2KOhm,+/-1%,1/10W,G,SMD0603 | KOA SPEER ELECTRONICS, INC. | RK73H1JTTD2001F | N | PWA BOM | In Old BOM |
|  |  |  | 610108V00-012-G | RES,2KOhm,+/-1%,1/10W,G,SMD0603 | WALSIN | WR06X2001FTL | G | PWA BOM | In Old BOM |
|  |  |  | 610108V00-011-G | RES,2KOhm,+/-1%,1/10W,G,SMD0603 | YAGEO | RC0603FR-072KL | G | PWA BOM | In Old BOM |
|  |  |  | 610108V00-044-G | RES,2KOhm,+/-1%,1/10W,G,SMD0603 | TA-I | RM06FTN2001 | G | PWA BOM | In Old BOM |
|  |  |  | 610108V00-024-G | RES,2KOhm,+/-1%,1/10W,G,SMD0603 | PANASONIC INDUSTRIAL CO.,LTD. | ERJ3EKF2001V | G | PWA BOM | In Old BOM |
| 85 | PBER66,PAFR66,PAER66,PBFR67,PBER67,PAFR67,PAER67,PBFR68 | 8 | 61010RW00-017-G | RES,23.2KOhm,+/-1%,1/10W,G,SMD0603 | KOA SPEER ELECTRONICS, INC. | RK73H1JTTD2322F | G | PWA BOM | In New BOM |
|  |  |  | 61010RW00-012-G | RES,23.2KOhm,+/-1%,1/10W,G,SMD0603 | WALSIN TECHNOLOGY CORPORATION | WR06X2322FTL | G | PWA BOM | In New BOM |
|  |  |  | 61010RW00-011-G | RES,23.2KOhm,+/-1%,1/10W,G,SMD0603 | YAGEO CORPORATION COMPONENT | RC0603FR-0723K2L | G | PWA BOM | In New BOM |
|  |  |  | 61010RW00-044-G | RES,23.2KOhm,+/-1%,1/10W,G,SMD0603 | TA-I TECHNOLOGY CO., LTD | RM06FTN2322 | G | PWA BOM | In New BOM |
|  |  |  | 61010RW00-029-G | RES,23.2KOhm,+/-1%,1/10W,G,SMD0603 | VISHAY ENTER TECHNO LOGY.INC | CRCW060323K2FKEA | G | PWA BOM | In New BOM |
|  |  |  | 61010RW00-024-G | RES,23.2KOhm,+/-1%,1/10W,G,SMD0603 | PANASONIC INDUSTRIAL CO.,LTD. | ERJ3EKF2322V | G | PWA BOM | In New BOM |
|  | PBER66,PAFR66,PAER66,PBFR67,PBER67,PAFR67,PAER67,PBFR68 | 8 | 61010RW00-017-G | RES,23.2KOhm,+/-1%,1/10W,G,SMD0603 | KOA SPEER ELECTRONICS, INC. | RK73H1JTTD2322F | N | PWA BOM | In Old BOM |
|  |  |  | 61010RW00-012-G | RES,23.2KOhm,+/-1%,1/10W,G,SMD0603 | WALSIN | WR06X2322FTL | G | PWA BOM | In Old BOM |
|  |  |  | 61010RW00-011-G | RES,23.2KOhm,+/-1%,1/10W,G,SMD0603 | YAGEO | RC0603FR-0723K2L | G | PWA BOM | In Old BOM |
|  |  |  | 61010RW00-044-G | RES,23.2KOhm,+/-1%,1/10W,G,SMD0603 | TA-I | RM06FTN2322 | G | PWA BOM | In Old BOM |
|  |  |  | 61010RW00-029-G | RES,23.2KOhm,+/-1%,1/10W,G,SMD0603 | VISHAY ENTER TECHNO LOGY.INC | CRCW060323K2FKEA | G | PWA BOM | In Old BOM |
|  |  |  | 61010RW00-024-G | RES,23.2KOhm,+/-1%,1/10W,G,SMD0603 | PANASONIC INDUSTRIAL CO.,LTD. | ERJ3EKF2322V | G | PWA BOM | In Old BOM |
| 86 | PBFR513,PBER513,PAFR513,PAER513 | 4 | 61015NJ00-017-G | RES,6.04 Ohm,+/-1%,1/4W,G,SMD1206 | KOA SPEER ELECTRONICS, INC. | RK73H2BTTD6R04F | G | PWA BOM | In New BOM |
|  |  |  | 61015NJ00-012-G | RES,6.04 Ohm,+/-1%,1/4W,G,SMD1206 | WALSIN TECHNOLOGY CORPORATION | WR12W6R04FTL | G | PWA BOM | In New BOM |
|  |  |  | 61015NJ00-011-G | RES,6.04 Ohm,+/-1%,1/4W,G,SMD1206 | YAGEO CORPORATION COMPONENT | RC1206FR-076R04L | G | PWA BOM | In New BOM |
|  | PBFR513,PBER513,PAFR513,PAER513 | 4 | 61015NJ00-017-G | RES,6.04 Ohm,+/-1%,1/4W,G,SMD1206 | KOA SPEER ELECTRONICS, INC. | RK73H2BTTD6R04F |  | PWA BOM | In Old BOM |
|  |  |  | 61015NJ00-012-G | RES,6.04 Ohm,+/-1%,1/4W,G,SMD1206 | WALSIN | WR12W6R04FTL | G | PWA BOM | In Old BOM |
|  |  |  | 61015NJ00-011-G | RES,6.04 Ohm,+/-1%,1/4W,G,SMD1206 | YAGEO | RC1206FR-076R04L | G | PWA BOM | In Old BOM |
| 87 | PBFR3,PAFR3 | 2 | 610117U00-017-G | RES,820 Ohm,+/-1%,1/16W,G,SMD0402 | KOA SPEER ELECTRONICS, INC. | RK73H1ETTP8200F | G | PWA BOM | In New BOM |
|  |  |  | 610117U00-012-G | RES,820 Ohm,+/-1%,1/16W,G,SMD0402 | WALSIN TECHNOLOGY CORPORATION | WR04X8200FTL | G | PWA BOM | In New BOM |
|  |  |  | 610117U00-011-G | RES,820 Ohm,+/-1%,1/16W,G,SMD0402 | YAGEO CORPORATION COMPONENT | RC0402FR-07820RL | G | PWA BOM | In New BOM |
|  |  |  | 610117U00-044-G | RES,820 Ohm,+/-1%,1/16W,G,SMD0402 | TA-I TECHNOLOGY CO., LTD | RM04FTN8200 | G | PWA BOM | In New BOM |
|  | PBFR3,PAFR3 | 2 | 610117U00-017-G | RES,820 Ohm,+/-1%,1/16W,G,SMD0402 | KOA SPEER ELECTRONICS, INC. | RK73H1ETTP8200F | N | PWA BOM | In Old BOM |
|  |  |  | 610117U00-012-G | RES,820 Ohm,+/-1%,1/16W,G,SMD0402 | WALSIN | WR04X8200FTL | G | PWA BOM | In Old BOM |
|  |  |  | 610117U00-011-G | RES,820 Ohm,+/-1%,1/16W,G,SMD0402 | YAGEO | RC0402FR-07820RL | G | PWA BOM | In Old BOM |
|  |  |  | 610117U00-044-G | RES,820 Ohm,+/-1%,1/16W,G,SMD0402 | TA-I | RM04FTN8200 | G | PWA BOM | In Old BOM |
| 88 | PSTC2,PSLC2,PSFC2,PSEC2,PSDC2,PQPC2,PFRC2,PEEC2,PEDC2,PANC2,PSTC3,PSLC3,PSFC3,PSEC3,PSDC3,PQPC3,PFRC3,PEEC3,PEDC3,PBNC3,PANC3,PBNC4,PANC4,PBNC5,PANC5,PSPC6,PIPC6,PFPC6,PEPC6,PBNC6,PSPC7,PIPC7,PFPC7,PEPC7,PSPC8,PIPC8,PFPC8,PEPC8,PSPC9,PIPC9,PFPC9,PEPC9,PSTC17,PSTC18,PALC38,PALC39,PBLC54,PBLC55,PSPC3004,PIPC3004,PFPC3004,PEPC3004,PSPC3005,PIPC3005,PFPC3005,PEPC3005,PSPC3006,PIPC3006,PFPC3006,PEPC3006,PSPC3007,PIPC3007,PFPC3007,PEPC3007,PSPC3009,PIPC3009,PFPC3009,PEPC3009 | 68 | 62012GG00-015-G | CAP,10uF,+/-10%,X7S,25V,G,SMD0805 | MURATA ELEC. NORTH AMERICA | GRM21BC71E106K | G | PWA BOM | In New BOM |
|  |  |  | 62012GG00-012-G | CAP,10uF,+/-10%,X7S,25V,G,SMD0805 | WALSIN TECHNOLOGY CORPORATION | 0805A106K250CT | G | PWA BOM | In New BOM |
|  | PSTC2,PSLC2,PSFC2,PSEC2,PSDC2,PQPC2,PFRC2,PEEC2,PEDC2,PANC2,PSTC3,PSLC3,PSFC3,PSEC3,PSDC3,PQPC3,PFRC3,PEEC3,PEDC3,PBNC3,PANC3,PBNC4,PANC4,PBNC5,PANC5,PSPC6,PIPC6,PFPC6,PEPC6,PBNC6,PSPC7,PIPC7,PFPC7,PEPC7,PSPC8,PIPC8,PFPC8,PEPC8,PSPC9,PIPC9,PFPC9,PEPC9,PSTC17,PSTC18,PALC38,PALC39,PBLC54,PBLC55,PSPC3004,PIPC3004,PFPC3004,PEPC3004,PSPC3005,PIPC3005,PFPC3005,PEPC3005,PSPC3006,PIPC3006,PFPC3006,PEPC3006,PSPC3007,PIPC3007,PFPC3007,PEPC3007,PSPC3009,PIPC3009,PFPC3009,PEPC3009 | 68 | 62012GG00-015-G | CAP,10uF,+/-10%,X7S,25V,G,SMD0805 | MURATA ELEC. NORTH AMERICA | GRM21BC71E106K |  | PWA BOM | In Old BOM |
|  |  |  | 62012GG00-012-G | CAP,10uF,+/-10%,X7S,25V,G,SMD0805 | WALSIN | 0805A106K250CT | G | PWA BOM | In Old BOM |
| 89 | PALL2,PBLL4 | 2 | 630351600-034-G | IND,470nH@100KHz,+/-20%,30A,1.68mOhm,SHLD,G,SMD | CYNTEC CO. LTD | PCMB104T-R47MS | G | PWA BOM | In New BOM |
|  |  |  | 63035YA00-051-G | Coil Ind,Shielded(SHLD),470nH@100KHz,+/-20%,28A,1.5mOhm,SMD,11.5*10.3*4.0,,,G | PULSE ELECTRONICS (SINGAPORE) | PA4342.471NLT | G | PWA BOM | In New BOM |
|  |  |  | 63035Y900-129-G | IND,470nH@100KHz,+/-20%,30A,1.68mOhm,SHLD,G,SMD | MAG.LAYERS, SCIENTIFIC-TECHNICS (KUNSHAN) CO., LTD. | SPS-10DZ-R47M-X2 | G | PWA BOM | In New BOM |
|  | PALL2,PBLL4 | 2 | 630351600-034-G | IND,470nH@100KHz,+/-20%,30A,1.68mOhm,SHLD,G,SMD | CYNTEC CO. LTD | PCMB104T-R47MS |  | PWA BOM | In Old BOM |
|  |  |  | 63035YA00-051-G | Coil Ind,Shielded(SHLD),470nH@100KHz,+/-20%,28A,1.5mOhm,SMD,11.5*10.3*4.0,,,G | PULSE ELECTRONICS (SINGAPORE) | PA4342.471NLT | G | PWA BOM | In Old BOM |
|  |  |  | SPS-10DZ-R47M-X2 | Coil Ind,SPS-10DZ-R47M-X2 | MAG.LAYERS, SCIENTIFIC-TECHNICS (KUNSHAN) CO., LTD. | SPS-10DZ-R47M-X2 | G | PWA BOM | In Old BOM |
| 90 | PBMR3,PAMR12 | 2 | 61011QD00-017-G | RES,330 Ohm,+/-1%,1/16W,G,SMD0402 | KOA SPEER ELECTRONICS, INC. | RK73H1ETTP3300F | G | PWA BOM | In New BOM |
|  |  |  | 61011QD00-012-G | RES,330 Ohm,+/-1%,1/16W,G,SMD0402 | WALSIN TECHNOLOGY CORPORATION | WR04X3300FTL | G | PWA BOM | In New BOM |
|  |  |  | 61011QD00-011-G | RES,330 Ohm,+/-1%,1/16W,G,SMD0402 | YAGEO CORPORATION COMPONENT | RC0402FR-07330RL | G | PWA BOM | In New BOM |
|  |  |  | 61011QD00-044-G | RES,330 Ohm,+/-1%,1/16W,G,SMD0402 | TA-I TECHNOLOGY CO., LTD | RM04FTN3300 | G | PWA BOM | In New BOM |
|  | PBMR3,PAMR12 | 2 | 61011QD00-017-G | RES,330 Ohm,+/-1%,1/16W,G,SMD0402 | KOA SPEER ELECTRONICS, INC. | RK73H1ETTP3300F | N | PWA BOM | In Old BOM |
|  |  |  | 61011QD00-012-G | RES,330 Ohm,+/-1%,1/16W,G,SMD0402 | WALSIN | WR04X3300FTL | G | PWA BOM | In Old BOM |
|  |  |  | 61011QD00-011-G | RES,330 Ohm,+/-1%,1/16W,G,SMD0402 | YAGEO | RC0402FR-07330RL | G | PWA BOM | In Old BOM |
|  |  |  | 61011QD00-044-G | RES,330 Ohm,+/-1%,1/16W,G,SMD0402 | TA-I | RM04FTN3300 | G | PWA BOM | In Old BOM |
| 91 | PBMR47,PAMR47 | 2 | 61011HT00-017-G | RES,1.8KOhm,+/-1%,1/16W,G,SMD0402 | KOA SPEER ELECTRONICS, INC. | RK73H1ETTP1801F | G | PWA BOM | In New BOM |
|  |  |  | 61011HT00-012-G | RES,1.8KOhm,+/-1%,1/16W,G,SMD0402 | WALSIN TECHNOLOGY CORPORATION | WR04X1801FTL | G | PWA BOM | In New BOM |
|  |  |  | 61011HT00-011-G | RES,1.8KOhm,+/-1%,1/16W,G,SMD0402 | YAGEO CORPORATION COMPONENT | RC0402FR-071K8L | G | PWA BOM | In New BOM |
|  |  |  | 61011HT00-044-G | RES,1.8KOhm,+/-1%,1/16W,G,SMD0402 | TA-I TECHNOLOGY CO., LTD | RM04FTN1801 | G | PWA BOM | In New BOM |
|  |  |  | 61011HT00-029-G | RES,1.8KOhm,+/-1%,1/16W,G,SMD0402 | VISHAY ENTER TECHNO LOGY.INC | CRCW04021K80FKED | G | PWA BOM | In New BOM |
|  |  |  | ERA2RKF1801X | RES,1.8KOhm,+/-1%,1/16W,G,SMD0402 | PANASONIC INDUSTRIAL CO.,LTD. | ERA2RKF1801X | G | PWA BOM | In New BOM |
|  | PBMR47,PAMR47 | 2 | 61011HT00-017-G | RES,1.8KOhm,+/-1%,1/16W,G,SMD0402 | KOA SPEER ELECTRONICS, INC. | RK73H1ETTP1801F | N | PWA BOM | In Old BOM |
|  |  |  | 61011HT00-012-G | RES,1.8KOhm,+/-1%,1/16W,G,SMD0402 | WALSIN | WR04X1801FTL | G | PWA BOM | In Old BOM |
|  |  |  | 61011HT00-011-G | RES,1.8KOhm,+/-1%,1/16W,G,SMD0402 | YAGEO | RC0402FR-071K8L | G | PWA BOM | In Old BOM |
|  |  |  | 61011HT00-044-G | RES,1.8KOhm,+/-1%,1/16W,G,SMD0402 | TA-I | RM04FTN1801 | G | PWA BOM | In Old BOM |
|  |  |  | 61011HT00-029-G | RES,1.8KOhm,+/-1%,1/16W,G,SMD0402 | VISHAY ENTER TECHNO LOGY.INC | CRCW04021K80FKED | G | PWA BOM | In Old BOM |
|  |  |  | ERA2RKF1801X | RES,1.8KOhm,+/-1%,1/16W,G,SMD0402 | PANASONIC INDUSTRIAL CO.,LTD. | ERA2RKF1801X | G | PWA BOM | In Old BOM |
| 92 | PAMR66,PBMR69,PBMR76,PAMR76 | 4 | 61010R900-017-G | RES,27.4KOhm,+/-1%,1/10W,G,SMD0603 | KOA SPEER ELECTRONICS, INC. | RK73H1JTTD2742F | G | PWA BOM | In New BOM |
|  |  |  | 61010R900-012-G | RES,27.4KOhm,+/-1%,1/10W,G,SMD0603 | WALSIN TECHNOLOGY CORPORATION | WR06X2742FTL | G | PWA BOM | In New BOM |
|  |  |  | 61010R900-011-G | RES,27.4KOhm,+/-1%,1/10W,G,SMD0603 | YAGEO CORPORATION COMPONENT | RC0603FR-0727K4L | G | PWA BOM | In New BOM |
|  | PAMR66,PBMR69,PBMR76,PAMR76 | 4 | 61010R900-017-G | RES,27.4KOhm,+/-1%,1/10W,G,SMD0603 | KOA SPEER ELECTRONICS, INC. | RK73H1JTTD2742F | N | PWA BOM | In Old BOM |
|  |  |  | 61010R900-012-G | RES,27.4KOhm,+/-1%,1/10W,G,SMD0603 | WALSIN | WR06X2742FTL | G | PWA BOM | In Old BOM |
|  |  |  | 61010R900-011-G | RES,27.4KOhm,+/-1%,1/10W,G,SMD0603 | YAGEO | RC0603FR-0727K4L | G | PWA BOM | In Old BOM |
| 93 | PANR6,PBNR7,R355,R356,R361,R362 | 6 | 61011JH00-017-G | RES,19.1KOhm,+/-1%,1/16W,G,SMD0402 | KOA SPEER ELECTRONICS, INC. | RK73H1ETTP1912F | G | PWA BOM | In New BOM |
|  |  |  | 61011JH00-012-G | RES,19.1KOhm,+/-1%,1/16W,G,SMD0402 | WALSIN TECHNOLOGY CORPORATION | WR04X1912FTL | G | PWA BOM | In New BOM |
|  |  |  | 61011JH00-011-G | RES,19.1KOhm,+/-1%,1/16W,G,SMD0402 | YAGEO CORPORATION COMPONENT | RC0402FR-0719K1L | G | PWA BOM | In New BOM |
|  |  |  | 61011JH00-044-G | RES,19.1KOhm,+/-1%,1/16W,G,SMD0402 | TA-I TECHNOLOGY CO., LTD | RM04FTN1912 | G | PWA BOM | In New BOM |
|  | PANR6,PBNR7,R355,R356,R361,R362 | 6 | 61011JH00-017-G | RES,19.1KOhm,+/-1%,1/16W,G,SMD0402 | KOA SPEER ELECTRONICS, INC. | RK73H1ETTP1912F | N | PWA BOM | In Old BOM |
|  |  |  | 61011JH00-012-G | RES,19.1KOhm,+/-1%,1/16W,G,SMD0402 | WALSIN | WR04X1912FTL | G | PWA BOM | In Old BOM |
|  |  |  | 61011JH00-011-G | RES,19.1KOhm,+/-1%,1/16W,G,SMD0402 | YAGEO | RC0402FR-0719K1L | G | PWA BOM | In Old BOM |
|  |  |  | 61011JH00-044-G | RES,19.1KOhm,+/-1%,1/16W,G,SMD0402 | TA-I | RM04FTN1912 | G | PWA BOM | In Old BOM |
| 94 | PFRR3,PBNR5,PANR7 | 3 | 610114S00-017-G | RES,4.99KOhm,+/-1%,1/16W,G,SMD0402 | KOA SPEER ELECTRONICS, INC. | RK73H1ETTP4991F | G | PWA BOM | In New BOM |
|  |  |  | 610114S00-012-G | RES,4.99KOhm,+/-1%,1/16W,G,SMD0402 | WALSIN TECHNOLOGY CORPORATION | WR04X4991FTL | G | PWA BOM | In New BOM |
|  |  |  | 610114S00-011-G | RES,4.99KOhm,+/-1%,1/16W,G,SMD0402 | YAGEO CORPORATION COMPONENT | RC0402FR-074K99L | G | PWA BOM | In New BOM |
|  |  |  | 610114S00-044-G | RES,4.99KOhm,+/-1%,1/16W,G,SMD0402 | TA-I TECHNOLOGY CO., LTD | RM04FTN4991 | G | PWA BOM | In New BOM |
|  |  |  | 610114S00-024-G | RES,4.99KOhm,+/-1%,1/16W,G,SMD0402 | PANASONIC INDUSTRIAL CO.,LTD. | ERJ2RKF4991X | G | PWA BOM | In New BOM |
|  | PFRR3,PBNR5,PANR7 | 3 | 610114S00-017-G | RES,4.99KOhm,+/-1%,1/16W,G,SMD0402 | KOA SPEER ELECTRONICS, INC. | RK73H1ETTP4991F | N | PWA BOM | In Old BOM |
|  |  |  | 610114S00-012-G | RES,4.99KOhm,+/-1%,1/16W,G,SMD0402 | WALSIN | WR04X4991FTL | G | PWA BOM | In Old BOM |
|  |  |  | 610114S00-011-G | RES,4.99KOhm,+/-1%,1/16W,G,SMD0402 | YAGEO | RC0402FR-074K99L | G | PWA BOM | In Old BOM |
|  |  |  | 610114S00-044-G | RES,4.99KOhm,+/-1%,1/16W,G,SMD0402 | TA-I | RM04FTN4991 | G | PWA BOM | In Old BOM |
|  |  |  | 610114S00-024-G | RES,4.99KOhm,+/-1%,1/16W,G,SMD0402 | PANASONIC INDUSTRIAL CO.,LTD. | ERJ2RKF4991X | G | PWA BOM | In Old BOM |
| 95 | PBNR11,PANR11 | 2 | 610114B00-017-G | RES,2.49KOhm,+/-1%,1/16W,G,SMD0402 | KOA SPEER ELECTRONICS, INC. | RK73H1ETTP2491F | G | PWA BOM | In New BOM |
|  |  |  | 610114B00-012-G | RES,2.49KOhm,+/-1%,1/16W,G,SMD0402 | WALSIN TECHNOLOGY CORPORATION | WR04X2491FTL | G | PWA BOM | In New BOM |
|  |  |  | 610114B00-011-G | RES,2.49KOhm,+/-1%,1/16W,G,SMD0402 | YAGEO CORPORATION COMPONENT | RC0402FR-072K49L | G | PWA BOM | In New BOM |
|  |  |  | 610114B00-024-G | RES,2.49KOhm,+/-1%,1/16W,G,SMD0402 | PANASONIC | ERJ2RKF2491X | G | PWA BOM | In New BOM |
|  |  |  | 610114B00-029-G | RES,2.49KOhm,+/-1%,1/16W,G,SMD0402 | VISHAY ENTER TECHNO LOGY.INC | CRCW04022K49FKED | G | PWA BOM | In New BOM |
|  | PBNR11,PANR11 | 2 | 610114B00-017-G | RES,2.49KOhm,+/-1%,1/16W,G,SMD0402 | KOA SPEER ELECTRONICS, INC. | RK73H1ETTP2491F | N | PWA BOM | In Old BOM |
|  |  |  | 610114B00-012-G | RES,2.49KOhm,+/-1%,1/16W,G,SMD0402 | WALSIN | WR04X2491FTL | G | PWA BOM | In Old BOM |
|  |  |  | 610114B00-011-G | RES,2.49KOhm,+/-1%,1/16W,G,SMD0402 | YAGEO | RC0402FR-072K49L | G | PWA BOM | In Old BOM |
|  |  |  | 610114B00-024-G | RES,2.49KOhm,+/-1%,1/16W,G,SMD0402 | PANASONIC | ERJ2RKF2491X | G | PWA BOM | In Old BOM |
|  |  |  | 610114B00-029-G | RES,2.49KOhm,+/-1%,1/16W,G,SMD0402 | VISHAY ENTER TECHNO LOGY.INC | CRCW04022K49FKED | G | PWA BOM | In Old BOM |
| 96 | PBNR14,PANR14 | 2 | 61011CJ00-017-G | RES,365 Ohm,+/-1%,1/16W,G,SMD0402 | KOA SPEER ELECTRONICS, INC. | RK73H1ETTP3650F | G | PWA BOM | In New BOM |
|  |  |  | 61011CJ00-012-G | RES,365 Ohm,+/-1%,1/16W,G,SMD0402 | WALSIN TECHNOLOGY CORPORATION | WR04X3650FTL | G | PWA BOM | In New BOM |
|  |  |  | 61011CJ00-011-G | RES,365 Ohm,+/-1%,1/16W,G,SMD0402 | YAGEO CORPORATION COMPONENT | RC0402FR-07365RL | G | PWA BOM | In New BOM |
|  |  |  | 61011CJ00-024-G | RES,365 Ohm,+/-1%,1/16W,G,SMD0402 | PANASONIC | ERJ2RKF3650X | G | PWA BOM | In New BOM |
|  |  |  | 61011CJ00-029-G | RES,365 Ohm,+/-1%,1/16W,G,SMD0402 | VISHAY ENTER TECHNO LOGY.INC | CRCW0402365RFKEDC | G | PWA BOM | In New BOM |
|  | PBNR14,PANR14 | 2 | 61011CJ00-017-G | RES,365 Ohm,+/-1%,1/16W,G,SMD0402 | KOA SPEER ELECTRONICS, INC. | RK73H1ETTP3650F | N | PWA BOM | In Old BOM |
|  |  |  | 61011CJ00-012-G | RES,365 Ohm,+/-1%,1/16W,G,SMD0402 | WALSIN | WR04X3650FTL | G | PWA BOM | In Old BOM |
|  |  |  | 61011CJ00-011-G | RES,365 Ohm,+/-1%,1/16W,G,SMD0402 | YAGEO | RC0402FR-07365RL | G | PWA BOM | In Old BOM |
|  |  |  | 61011CJ00-024-G | RES,365 Ohm,+/-1%,1/16W,G,SMD0402 | PANASONIC | ERJ2RKF3650X | G | PWA BOM | In Old BOM |
|  |  |  | 61011CJ00-029-G | RES,365 Ohm,+/-1%,1/16W,G,SMD0402 | VISHAY ENTER TECHNO LOGY.INC | CRCW0402365RFKEDC | G | PWA BOM | In Old BOM |
| 97 | PBNR15,PANR15 | 2 | 610112G00-017-G | RES,20 Ohm,+/-1%,1/16W,G,SMD0402 | KOA SPEER ELECTRONICS, INC. | RK73H1ETTP20R0F | G | PWA BOM | In New BOM |
|  |  |  | 610112G00-012-G | RES,20 Ohm,+/-1%,1/16W,G,SMD0402 | WALSIN TECHNOLOGY CORPORATION | WR04X20R0FTL | G | PWA BOM | In New BOM |
|  |  |  | 610112G00-011-G | RES,20 Ohm,+/-1%,1/16W,G,SMD0402 | YAGEO CORPORATION COMPONENT | RC0402FR-0720RL | G | PWA BOM | In New BOM |
|  |  |  | 610112G00-044-G | RES,20 Ohm,+/-1%,1/16W,G,SMD0402 | TA-I TECHNOLOGY CO., LTD | RM04FTN20R0 | G | PWA BOM | In New BOM |
|  |  |  | 610112G00-024-G | RES,20 Ohm,+/-1%,1/16W,G,SMD0402 | PANASONIC INDUSTRIAL CO.,LTD. | ERJ2RKF20R0X | G | PWA BOM | In New BOM |
|  | PBNR15,PANR15 | 2 | 610112G00-017-G | RES,20 Ohm,+/-1%,1/16W,G,SMD0402 | KOA SPEER ELECTRONICS, INC. | RK73H1ETTP20R0F | N | PWA BOM | In Old BOM |
|  |  |  | 610112G00-012-G | RES,20 Ohm,+/-1%,1/16W,G,SMD0402 | WALSIN | WR04X20R0FTL | G | PWA BOM | In Old BOM |
|  |  |  | 610112G00-011-G | RES,20 Ohm,+/-1%,1/16W,G,SMD0402 | YAGEO | RC0402FR-0720RL | G | PWA BOM | In Old BOM |
|  |  |  | 610112G00-044-G | RES,20 Ohm,+/-1%,1/16W,G,SMD0402 | TA-I | RM04FTN20R0 | G | PWA BOM | In Old BOM |
|  |  |  | 610112G00-024-G | RES,20 Ohm,+/-1%,1/16W,G,SMD0402 | PANASONIC INDUSTRIAL CO.,LTD. | ERJ2RKF20R0X | G | PWA BOM | In Old BOM |
| 98 | PSRR16,PBNR16,PANR16,PBNR18,PANR18 | 5 | 611005R00-017-G | RES,100 Ohm,+/-0.1%,1/16W,G,SMD0402 | KOA SPEER ELECTRONICS, INC. | RN731ETTP1000B25 | G | PWA BOM | In New BOM |
|  |  |  | 611005R00-012-G | RES,100 Ohm,+/-0.1%,1/16W,G,SMD0402 | WALSIN TECHNOLOGY CORPORATION | WF04U1000BTL | G | PWA BOM | In New BOM |
|  |  |  | 611005R00-011-G | RES,100 Ohm,+/-0.1%,1/16W,G,SMD0402 | YAGEO CORPORATION COMPONENT | RT0402BRE07100RL | G | PWA BOM | In New BOM |
|  |  |  | 611005R00-044-G | RES,100 Ohm,+/-0.1%,1/16W,G,SMD0402 | TA-I TECHNOLOGY CO., LTD | RB04BTP1000 | G | PWA BOM | In New BOM |
|  | PSRR16,PBNR16,PANR16,PBNR18,PANR18 | 5 | 611005R00-017-G | RES,100 Ohm,+/-0.1%,1/16W,G,SMD0402 | KOA SPEER ELECTRONICS, INC. | RN731ETTP1000B25 | Y | PWA BOM | In Old BOM |
|  |  |  | 611005R00-012-G | RES,100 Ohm,+/-0.1%,1/16W,G,SMD0402 | WALSIN | WF04U1000BTL | G | PWA BOM | In Old BOM |
|  |  |  | 611005R00-011-G | RES,100 Ohm,+/-0.1%,1/16W,G,SMD0402 | YAGEO | RT0402BRE07100RL | G | PWA BOM | In Old BOM |
|  |  |  | 611005R00-044-G | RES,100 Ohm,+/-0.1%,1/16W,G,SMD0402 | TA-I | RB04BTP1000 | G | PWA BOM | In Old BOM |
| 99 | PBNR17,PANR17 | 2 | 61011B600-017-G | RES,5.36KOhm,+/-1%,1/16W,G,SMD0402 | KOA SPEER ELECTRONICS, INC. | RK73H1ETTP5361F | G | PWA BOM | In New BOM |
|  |  |  | 61011B600-012-G | RES,5.36KOhm,+/-1%,1/16W,G,SMD0402 | WALSIN TECHNOLOGY CORPORATION | WR04X5361FTL | G | PWA BOM | In New BOM |
|  |  |  | 61011B600-011-G | RES,5.36KOhm,+/-1%,1/16W,G,SMD0402 | YAGEO CORPORATION COMPONENT | RC0402FR-075K36L | G | PWA BOM | In New BOM |
|  |  |  | 61011B600-044-G | RES,5.36KOhm,+/-1%,1/16W,G,SMD0402 | TA-I TECHNOLOGY CO., LTD | RM04FTN5361 | G | PWA BOM | In New BOM |
|  | PBNR17,PANR17 | 2 | 61011B600-017-G | RES,5.36KOhm,+/-1%,1/16W,G,SMD0402 | KOA SPEER ELECTRONICS, INC. | RK73H1ETTP5361F | N | PWA BOM | In Old BOM |
|  |  |  | 61011B600-012-G | RES,5.36KOhm,+/-1%,1/16W,G,SMD0402 | WALSIN | WR04X5361FTL | G | PWA BOM | In Old BOM |
|  |  |  | 61011B600-011-G | RES,5.36KOhm,+/-1%,1/16W,G,SMD0402 | YAGEO | RC0402FR-075K36L | G | PWA BOM | In Old BOM |
|  |  |  | 61011B600-044-G | RES,5.36KOhm,+/-1%,1/16W,G,SMD0402 | TA-I | RM04FTN5361 | G | PWA BOM | In Old BOM |
| 100 | PSRR20,PBNR23,PANR23,PHAR28,PHAR29,PHAR30,R668,R669,R683,R762,R763,R764,R765,R766,R767,R769,R770,R772,R773,R774,R775,R776,R777,R778,R779,R780,R783,R784,R786,R787,R788,R791,R795,R800,R801,R804,R805,R806,R807,R808,R809,R811,R814,R817,R820,R822,R823,R825,R827,R828,R830,R893,R894,R901,R902,R922,R942,R943,R944,R945,R949,R950,R955,R956,R957,R958,R959,R1017,R1023,R1129,R1135,R1138,R1148,R1149,R1150,R1151,R1152,R1156,R1159,R1162,R1164,R1165,R1172,R1174,R1175,R1176,R1184,R1185,R1186,R1190,R1195,R1197,R1198,R1199,R1210,R1211,R1212,R1213,R1218,R1219,R1220,R1221,R1222,R1223,R1224,R1240,R1256,R1257,R1295,R1296,R1461,R1463,R1464,R1465,R1467,R1469,R1470,R1471,R1474,R1475,R1476,R1477,R1495,R1504,R1507,R1508,R1509,R1511,R1512,R1515,R1520,R1521,R1550,R1551,R1558,R1589,R1590,R1592,R1593,R1603,R1604,R1605,R1606,R1779,R1780,R1781,R1782,R1786,R1789,R1801,R1820,R1821,R1834 | 153 | 61010LA00-017-G | RES,4.7KOhm,+/-1%,1/16W,G,SMD0402 | KOA SPEER ELECTRONICS, INC. | RK73H1ETTP4701F | G | PWA BOM | In New BOM |
|  |  |  | 61010LA00-012-G | RES,4.7KOhm,+/-1%,1/16W,G,SMD0402 | WALSIN TECHNOLOGY CORPORATION | WR04X4701FTL | G | PWA BOM | In New BOM |
|  |  |  | 61010LA00-011-G | RES,4.7KOhm,+/-1%,1/16W,G,SMD0402 | YAGEO CORPORATION COMPONENT | RC0402FR-074K7L | G | PWA BOM | In New BOM |
|  |  |  | 61010LA00-044-G | RES,4.7KOhm,+/-1%,1/16W,G,SMD0402 | TA-I TECHNOLOGY CO., LTD | RM04FTN4701 | G | PWA BOM | In New BOM |
|  | PSRR20,PBNR23,PANR23,PHAR28,PHAR29,PHAR30,R668,R669,R683,R762,R763,R764,R765,R766,R767,R769,R770,R772,R773,R774,R775,R776,R777,R778,R779,R780,R783,R784,R786,R787,R788,R791,R795,R800,R801,R804,R805,R806,R807,R808,R809,R811,R814,R817,R820,R822,R823,R825,R827,R828,R830,R893,R894,R901,R902,R922,R942,R943,R944,R945,R949,R950,R955,R956,R957,R958,R959,R1017,R1023,R1129,R1135,R1138,R1148,R1149,R1150,R1151,R1152,R1156,R1159,R1162,R1164,R1165,R1172,R1174,R1175,R1176,R1184,R1185,R1186,R1190,R1195,R1197,R1198,R1199,R1210,R1211,R1212,R1213,R1218,R1219,R1220,R1221,R1222,R1223,R1224,R1240,R1256,R1257,R1295,R1296,R1461,R1463,R1464,R1465,R1467,R1469,R1470,R1471,R1474,R1475,R1476,R1477,R1495,R1504,R1507,R1508,R1509,R1511,R1512,R1515,R1520,R1521,R1550,R1551,R1589,R1590,R1592,R1593,R1603,R1604,R1605,R1606,R1779,R1780,R1781,R1782,R1786,R1789,R1801,R1820,R1821,R1834 | 152 | 61010LA00-017-G | RES,4.7KOhm,+/-1%,1/16W,G,SMD0402 | KOA SPEER ELECTRONICS, INC. | RK73H1ETTP4701F | N | PWA BOM | In Old BOM |
|  |  |  | 61010LA00-012-G | RES,4.7KOhm,+/-1%,1/16W,G,SMD0402 | WALSIN | WR04X4701FTL | G | PWA BOM | In Old BOM |
|  |  |  | 61010LA00-011-G | RES,4.7KOhm,+/-1%,1/16W,G,SMD0402 | YAGEO | RC0402FR-074K7L | G | PWA BOM | In Old BOM |
|  |  |  | 61010LA00-044-G | RES,4.7KOhm,+/-1%,1/16W,G,SMD0402 | TA-I | RM04FTN4701 | G | PWA BOM | In Old BOM |
| 101 | PBNR24,PANR24 | 2 | 61011CS00-017-G | RES,750KOhm,+/-1%,1/16W,G,SMD0402 | KOA SPEER ELECTRONICS, INC. | RK73H1ETTP7503F | G | PWA BOM | In New BOM |
|  |  |  | 61011CS00-012-G | RES,750KOhm,+/-1%,1/16W,G,SMD0402 | WALSIN TECHNOLOGY CORPORATION | WR04X7503FTL | G | PWA BOM | In New BOM |
|  |  |  | 61011CS00-011-G | RES,750KOhm,+/-1%,1/16W,G,SMD0402 | YAGEO CORPORATION COMPONENT | RC0402FR-07750KL | G | PWA BOM | In New BOM |
|  | PBNR24,PANR24 | 2 | 61011CS00-017-G | RES,750KOhm,+/-1%,1/16W,G,SMD0402 | KOA SPEER ELECTRONICS, INC. | RK73H1ETTP7503F |  | PWA BOM | In Old BOM |
|  |  |  | 61011CS00-012-G | RES,750KOhm,+/-1%,1/16W,G,SMD0402 | WALSIN | WR04X7503FTL | G | PWA BOM | In Old BOM |
|  |  |  | 61011CS00-011-G | RES,750KOhm,+/-1%,1/16W,G,SMD0402 | YAGEO | RC0402FR-07750KL | G | PWA BOM | In Old BOM |
| 102 | PANR26 | 1 | 61011BS00-017-G | RES,2.05KOhm,+/-1%,1/16W,G,SMD0402 | KOA SPEER ELECTRONICS, INC. | RK73H1ETTP2051F | G | PWA BOM | In New BOM |
|  |  |  | 61011BS00-012-G | RES,2.05KOhm,+/-1%,1/16W,G,SMD0402 | WALSIN TECHNOLOGY CORPORATION | WR04X2051FTL | G | PWA BOM | In New BOM |
|  |  |  | 61011BS00-011-G | RES,2.05KOhm,+/-1%,1/16W,G,SMD0402 | YAGEO CORPORATION COMPONENT | RC0402FR-072K05L | G | PWA BOM | In New BOM |
|  |  |  | 61011BS00-044-G | RES,2.05KOhm,+/-1%,1/16W,G,SMD0402 | TA-I TECHNOLOGY CO., LTD | RM04FTN2051 | G | PWA BOM | In New BOM |
|  | PANR26 | 1 | 61011BS00-017-G | RES,2.05KOhm,+/-1%,1/16W,G,SMD0402 | KOA SPEER ELECTRONICS, INC. | RK73H1ETTP2051F | N | PWA BOM | In Old BOM |
|  |  |  | 61011BS00-012-G | RES,2.05KOhm,+/-1%,1/16W,G,SMD0402 | WALSIN | WR04X2051FTL | G | PWA BOM | In Old BOM |
|  |  |  | 61011BS00-011-G | RES,2.05KOhm,+/-1%,1/16W,G,SMD0402 | YAGEO | RC0402FR-072K05L | G | PWA BOM | In Old BOM |
|  |  |  | 61011BS00-044-G | RES,2.05KOhm,+/-1%,1/16W,G,SMD0402 | TA-I | RM04FTN2051 | G | PWA BOM | In Old BOM |
| 103 | PBNR26 | 1 | 610118R00-017-G | RES,1.54KOhm,+/-1%,1/16W,G,SMD0402 | KOA SPEER ELECTRONICS, INC. | RK73H1ETTP1541F | G | PWA BOM | In New BOM |
|  |  |  | 610118R00-012-G | RES,1.54KOhm,+/-1%,1/16W,G,SMD0402 | WALSIN TECHNOLOGY CORPORATION | WR04X1541FTL | G | PWA BOM | In New BOM |
|  |  |  | 610118R00-011-G | RES,1.54KOhm,+/-1%,1/16W,G,SMD0402 | YAGEO CORPORATION COMPONENT | RC0402FR-071K54L | G | PWA BOM | In New BOM |
|  |  |  | 610118R00-044-G | RES,1.54KOhm,+/-1%,1/16W,G,SMD0402 | TA-I TECHNOLOGY CO., LTD | RM04FTN1541 | G | PWA BOM | In New BOM |
|  | PBNR26 | 1 | 610118R00-017-G | RES,1.54KOhm,+/-1%,1/16W,G,SMD0402 | KOA SPEER ELECTRONICS, INC. | RK73H1ETTP1541F | N | PWA BOM | In Old BOM |
|  |  |  | 610118R00-012-G | RES,1.54KOhm,+/-1%,1/16W,G,SMD0402 | WALSIN | WR04X1541FTL | G | PWA BOM | In Old BOM |
|  |  |  | 610118R00-011-G | RES,1.54KOhm,+/-1%,1/16W,G,SMD0402 | YAGEO | RC0402FR-071K54L | G | PWA BOM | In Old BOM |
|  |  |  | 610118R00-044-G | RES,1.54KOhm,+/-1%,1/16W,G,SMD0402 | TA-I | RM04FTN1541 | G | PWA BOM | In Old BOM |
| 104 | PCIE1,PCIE5 | 2 | 10061913-102HLF | CONN,PCIE-8X,V/T,Bla,1mm,30u,G,SMD-98 | FCI CONNECTORS HONGKONG LTD. | 10061913-102HLF | G | PWA BOM | In New BOM |
|  |  |  | 2041366-4 | CONN,PCIE-8X,V/T,Bla,1mm,30u,G,SMD-98 | TYCO ELECTRONICS CORPORATION | 2041366-4 | G | PWA BOM | In New BOM |
|  | PCIE1,PCIE5 | 2 | 10061913-102HLF | CONN,PCIE-8X,V/T,Bla,1mm,30u,G,SMD-98 | FCI CONNECTORS HONGKONG LTD. | 10061913-102HLF |  | PWA BOM | In Old BOM |
| 105 | PCIE2,PCIE3,PCIE4 | 3 | 10061913-103HLF | CONN,PCIE-16X,V/T,Bla,1mm,30u,G,SMD-164 | FCI CONNECTORS HONGKONG LTD. | 10061913-103HLF | G | PWA BOM | In New BOM |
|  |  |  | 2041366-6 | CONN,PCIE-16X,V/T,Bla,1mm,30u,G,SMD-164 | TYCO ELECTRONICS CORPORATION | 2041366-6 | G | PWA BOM | In New BOM |
|  | PCIE2,PCIE3,PCIE4 | 3 | 10061913-103HLF | CONN,PCIE-16X,V/T,Bla,1mm,30u,G,SMD-164 | FCI CONNECTORS HONGKONG LTD. | 10061913-103HLF |  | PWA BOM | In Old BOM |
| 106 | PUAC19,PSIC19,PSAC19,PRAC19,PQAC19,PPAC19,PIAC19,PFAC19,PETC19,PERC19,PEAC19 | 11 | 62012G600-015-G | CAP,2.2uF,+/-10%,X7S,25V,G,SMD0603 | MURATA ELEC. NORTH AMERICA | GRM188C71E225K | G | PWA BOM | In New BOM |
|  |  |  | 62012G600-012-G | CAP,2.2uF,+/-10%,X7S,25V,G,SMD0603 | WALSIN TECHNOLOGY CORPORATION | 0603A225K250CT | G | PWA BOM | In New BOM |
|  | PUAC19,PSIC19,PSAC19,PRAC19,PQAC19,PPAC19,PIAC19,PFAC19,PETC19,PERC19,PEAC19 | 11 | 62012G600-015-G | CAP,2.2uF,+/-10%,X7S,25V,G,SMD0603 | MURATA ELEC. NORTH AMERICA | GRM188C71E225K |  | PWA BOM | In Old BOM |
|  |  |  | 62012G600-012-G | CAP,2.2uF,+/-10%,X7S,25V,G,SMD0603 | WALSIN | 0603A225K250CT | G | PWA BOM | In Old BOM |
| 107 | PUAL1,PSAL1,PRAL1,PQAL1,PPAL1,PIAL1,PFAL1,PEAL1 | 8 | 630335M00-088-G | IND,820nH@100KHz,+/-20%,13A,8mOhm,SHLD,G,SMD | COOPER BUSSMANN, INC. | HCM0703-R82-R | G | PWA BOM | In New BOM |
|  |  |  | 63035Y800-051-G | Coil Ind,Shielded(SHLD),820nH@100KHz,+/-20%,13A,8mOhm,SMD,7.6*6.9*3.0,,,G | PULSE ELECTRONICS (SINGAPORE) | PA4341.821NLT | G | PWA BOM | In New BOM |
|  |  |  | 63032RP05-129-G | IND,820nH@100KHz,+/-20%,13A,8mOhm,SHLD,G,SMD | MAG.LAYERS, SCIENTIFIC-TECHNICS (KUNSHAN) CO., LTD. | SPS-06CZ-R82M-V1 | G | PWA BOM | In New BOM |
|  | PUAL1,PSAL1,PRAL1,PQAL1,PPAL1,PIAL1,PFAL1,PEAL1 | 8 | 630335M00-088-G | IND,820nH@100KHz,+/-20%,13A,8mOhm,SHLD,G,SMD | COOPER BUSSMANN, INC. | HCM0703-R82-R |  | PWA BOM | In Old BOM |
|  |  |  | 63035Y800-051-G | Coil Ind,Shielded(SHLD),820nH@100KHz,+/-20%,13A,8mOhm,SMD,7.6*6.9*3.0,,,G | PULSE ELECTRONICS (SINGAPORE) | PA4341.821NLT | G | PWA BOM | In Old BOM |
|  |  |  | SPS-06CZ-R82M-V1 | Ind,SPS-06CZ-R82M-V1 | MAG.LAYERS, SCIENTIFIC-TECHNICS (KUNSHAN) CO., LTD. | SPS-06CZ-R82M-V1 | G | PWA BOM | In Old BOM |
| 108 | PUAR2,PSAR2,PRAR2,PQAR2,PPAR2,PIAR2,PFAR2,PEAR2 | 8 | 610114200-017-G | RES,10.7KOhm,+/-1%,1/16W,G,SMD0402 | KOA SPEER ELECTRONICS, INC. | RK73H1ETTP1072F | G | PWA BOM | In New BOM |
|  |  |  | 610114200-012-G | RES,10.7KOhm,+/-1%,1/16W,G,SMD0402 | WALSIN TECHNOLOGY CORPORATION | WR04X1072FTL | G | PWA BOM | In New BOM |
|  |  |  | 610114200-011-G | RES,10.7KOhm,+/-1%,1/16W,G,SMD0402 | YAGEO CORPORATION COMPONENT | RC0402FR-0710K7L | G | PWA BOM | In New BOM |
|  |  |  | 610114200-044-G | RES,10.7KOhm,+/-1%,1/16W,G,SMD0402 | TA-I TECHNOLOGY CO., LTD | RM04FTN1072 | G | PWA BOM | In New BOM |
|  | PUAR2,PSAR2,PRAR2,PQAR2,PPAR2,PIAR2,PFAR2,PEAR2 | 8 | 610114200-017-G | RES,10.7KOhm,+/-1%,1/16W,G,SMD0402 | KOA SPEER ELECTRONICS, INC. | RK73H1ETTP1072F | N | PWA BOM | In Old BOM |
|  |  |  | 610114200-012-G | RES,10.7KOhm,+/-1%,1/16W,G,SMD0402 | WALSIN | WR04X1072FTL | G | PWA BOM | In Old BOM |
|  |  |  | 610114200-011-G | RES,10.7KOhm,+/-1%,1/16W,G,SMD0402 | YAGEO | RC0402FR-0710K7L | G | PWA BOM | In Old BOM |
|  |  |  | 610114200-044-G | RES,10.7KOhm,+/-1%,1/16W,G,SMD0402 | TA-I | RM04FTN1072 | G | PWA BOM | In Old BOM |
| 109 | PUAR4,PSAR4,PRAR4,PQAR4,PPAR4,PIAR4,PFAR4,PEAR4,PUAR6,PSAR6,PRAR6,PQAR6,PPAR6,PIAR6,PFAR6,PEAR6 | 16 | 611004D00-017-G | RES,1.5KOhm,+/-0.1%,1/16W,G,SMD0402 | KOA SPEER ELECTRONICS, INC. | RN731ETTP1501B25 | G | PWA BOM | In New BOM |
|  |  |  | 611004D01-011-G | RES,1.5KOhm,+/-0.1%,1/16W,G,SMD0402 | YAGEO CORPORATION COMPONENT | RT0402BRD071K5L | G | PWA BOM | In New BOM |
|  | PUAR4,PSAR4,PRAR4,PQAR4,PPAR4,PIAR4,PFAR4,PEAR4,PUAR6,PSAR6,PRAR6,PQAR6,PPAR6,PIAR6,PFAR6,PEAR6 | 16 | 611004D00-017-G | RES,1.5KOhm,+/-0.1%,1/16W,G,SMD0402 | KOA SPEER ELECTRONICS, INC. | RN731ETTP1501B25 |  | PWA BOM | In Old BOM |
|  |  |  | 611004D01-011-G | RES,1.5KOhm,+/-0.1%,1/16W,G,SMD0402 | YAGEO | RT0402BRD071K5L | G | PWA BOM | In Old BOM |
| 110 | PUAR5,PSIR5,PSAR5,PRAR5,PQAR5,PPAR5,PIAR5,PFAR5,PETR5,PERR5,PEAR5 | 11 | 61011JY00-017-G | RES,39.2KOhm,+/-1%,1/16W,G,SMD0402 | KOA SPEER ELECTRONICS, INC. | RK73H1ETTP3922F | G | PWA BOM | In New BOM |
|  |  |  | 61011JY00-012-G | RES,39.2KOhm,+/-1%,1/16W,G,SMD0402 | WALSIN TECHNOLOGY CORPORATION | WR04X3922FTL | G | PWA BOM | In New BOM |
|  |  |  | 61011JY00-011-G | RES,39.2KOhm,+/-1%,1/16W,G,SMD0402 | YAGEO CORPORATION COMPONENT | RC0402FR-0739K2L | G | PWA BOM | In New BOM |
|  |  |  | 61011JY00-044-G | RES,39.2KOhm,+/-1%,1/16W,G,SMD0402 | TA-I TECHNOLOGY CO., LTD | RM04FTN3922 | G | PWA BOM | In New BOM |
|  |  |  | 61011JY00-029-G | RES,39.2KOhm,+/-1%,1/16W,G,SMD0402 | VISHAY ENTER TECHNO LOGY.INC | CRCW040239K2FKED | G | PWA BOM | In New BOM |
|  | PUAR5,PSIR5,PSAR5,PRAR5,PQAR5,PPAR5,PIAR5,PFAR5,PETR5,PERR5,PEAR5 | 11 | 61011JY00-017-G | RES,39.2KOhm,+/-1%,1/16W,G,SMD0402 | KOA SPEER ELECTRONICS, INC. | RK73H1ETTP3922F | N | PWA BOM | In Old BOM |
|  |  |  | 61011JY00-012-G | RES,39.2KOhm,+/-1%,1/16W,G,SMD0402 | WALSIN | WR04X3922FTL | G | PWA BOM | In Old BOM |
|  |  |  | 61011JY00-011-G | RES,39.2KOhm,+/-1%,1/16W,G,SMD0402 | YAGEO | RC0402FR-0739K2L | G | PWA BOM | In Old BOM |
|  |  |  | 61011JY00-044-G | RES,39.2KOhm,+/-1%,1/16W,G,SMD0402 | TA-I | RM04FTN3922 | G | PWA BOM | In Old BOM |
|  |  |  | 61011JY00-029-G | RES,39.2KOhm,+/-1%,1/16W,G,SMD0402 | VISHAY ENTER TECHNO LOGY.INC | CRCW040239K2FKED | G | PWA BOM | In Old BOM |
| 111 | PUAR8,PSAR8,PRAR8,PQAR8,PPAR8,PIAR8,PFAR8,PEAR8,PUAR11,PSAR11,PRAR11,PQAR11,PPAR11,PIAR11,PFAR11,PEAR11 | 16 | 610117F00-017-G | RES,5.76KOhm,+/-1%,1/16W,G,SMD0402 | KOA SPEER ELECTRONICS, INC. | RK73H1ETTP5761F | G | PWA BOM | In New BOM |
|  |  |  | 610117F00-012-G | RES,5.76KOhm,+/-1%,1/16W,G,SMD0402 | WALSIN TECHNOLOGY CORPORATION | WR04X5761FTL | G | PWA BOM | In New BOM |
|  |  |  | 610117F00-011-G | RES,5.76KOhm,+/-1%,1/16W,G,SMD0402 | YAGEO CORPORATION COMPONENT | RC0402FR-075K76L | G | PWA BOM | In New BOM |
|  |  |  | 610117F00-044-G | RES,5.76KOhm,+/-1%,1/16W,G,SMD0402 | TA-I TECHNOLOGY CO., LTD | RM04FTN5761 | G | PWA BOM | In New BOM |
|  | PUAR8,PSAR8,PRAR8,PQAR8,PPAR8,PIAR8,PFAR8,PEAR8,PUAR11,PSAR11,PRAR11,PQAR11,PPAR11,PIAR11,PFAR11,PEAR11 | 16 | 610117F00-017-G | RES,5.76KOhm,+/-1%,1/16W,G,SMD0402 | KOA SPEER ELECTRONICS, INC. | RK73H1ETTP5761F | N | PWA BOM | In Old BOM |
|  |  |  | 610117F00-012-G | RES,5.76KOhm,+/-1%,1/16W,G,SMD0402 | WALSIN | WR04X5761FTL | G | PWA BOM | In Old BOM |
|  |  |  | 610117F00-011-G | RES,5.76KOhm,+/-1%,1/16W,G,SMD0402 | YAGEO | RC0402FR-075K76L | G | PWA BOM | In Old BOM |
|  |  |  | 610117F00-044-G | RES,5.76KOhm,+/-1%,1/16W,G,SMD0402 | TA-I | RM04FTN5761 | G | PWA BOM | In Old BOM |
| 112 | PUAR10,PSAR10,PRAR10,PQAR10,PPAR10,PIAR10,PFAR10,PEAR10 | 8 | 610128200-017-G | RES,26.1 Ohm,+/-1%,1/16W,G,SMD0402 | KOA SPEER ELECTRONICS, INC. | RK73H1ETTP26R1F | G | PWA BOM | In New BOM |
|  |  |  | 610128200-012-G | RES,26.1 Ohm,+/-1%,1/16W,G,SMD0402 | WALSIN TECHNOLOGY CORPORATION | WR04X26R1FTL | G | PWA BOM | In New BOM |
|  |  |  | 610128200-011-G | RES,26.1 Ohm,+/-1%,1/16W,G,SMD0402 | YAGEO CORPORATION COMPONENT | RC0402FR-0726R1L | G | PWA BOM | In New BOM |
|  |  |  | 610128200-044-G | RES,26.1 Ohm,+/-1%,1/16W,G,SMD0402 | TA-I TECHNOLOGY CO., LTD | RM04FTN26R1 | G | PWA BOM | In New BOM |
|  | PUAR10,PSAR10,PRAR10,PQAR10,PPAR10,PIAR10,PFAR10,PEAR10 | 8 | 610128200-017-G | RES,26.1 Ohm,+/-1%,1/16W,G,SMD0402 | KOA SPEER ELECTRONICS, INC. | RK73H1ETTP26R1F | N | PWA BOM | In Old BOM |
|  |  |  | 610128200-012-G | RES,26.1 Ohm,+/-1%,1/16W,G,SMD0402 | WALSIN | WR04X26R1FTL | G | PWA BOM | In Old BOM |
|  |  |  | 610128200-011-G | RES,26.1 Ohm,+/-1%,1/16W,G,SMD0402 | YAGEO | RC0402FR-0726R1L | G | PWA BOM | In Old BOM |
|  |  |  | 610128200-044-G | RES,26.1 Ohm,+/-1%,1/16W,G,SMD0402 | TA-I | RM04FTN26R1 | G | PWA BOM | In Old BOM |
| 113 | PSTC4,PSLC4,PSFC4,PSEC4,PSDC4,PQPC4,PFRC4,PEEC4,PEDC4,PSPC3003,PIPC3003,PFPC3003,PEPC3003,PSRC3010 | 14 | 62012T300-015-G | CAP,1uF,+/-10%,X7S,25V,G,SMD0402 | MURATA ELEC. NORTH AMERICA | GRM155C71E105KE11D | G | PWA BOM | In New BOM |
|  |  |  | 620138700-026-G | CAP,1uF,+/-10%,X6S,25V,G,SMD0402 | SAMSUNG | CL05X105KA5NQNC |  | PWA BOM | In New BOM |
|  |  |  | GRM155C81E105KE11D | CAP,1uF,+/-10%,X6S,25V,G,SMD0402 | MURATA | GRM155C81E105KE11D |  | PWA BOM | In New BOM |
|  | PSTC4,PSLC4,PSFC4,PSEC4,PSDC4,PQPC4,PFRC4,PEEC4,PEDC4,PSPC3003,PIPC3003,PFPC3003,PEPC3003,PSRC3010 | 14 | 62012T300-015-G | CAP,1uF,+/-10%,X7S,25V,G,SMD0402 | MURATA ELEC. NORTH AMERICA | GRM155C71E105KE11D |  | PWA BOM | In Old BOM |
| 114 | PETL1,PERL1,PSFL2,PEEL2,PEDL2 | 5 | 63032CD00-088-G | IND,2.2uH@100KHz,+/-20%,8A,20mOhm,SHLD,G,SMD | COOPER BUSSMANN, INC. | HCM0703-2R2-R | G | PWA BOM | In New BOM |
|  |  |  | CMLE063T-2R2MS | IND,CMLE063T-2R2MS | CYNTEC CO. LTD | CMLE063T-2R2MS | G | PWA BOM | In New BOM |
|  | PETL1,PERL1,PSFL2,PEEL2,PEDL2 | 5 | 63032CD00-088-G | IND,2.2uH@100KHz,+/-20%,8A,20mOhm,SHLD,G,SMD | COOPER BUSSMANN, INC. | HCM0703-2R2-R |  | PWA BOM | In Old BOM |
|  |  |  | 63033JK00-15A-G | IND,2.2uH@100KHz,+/-20%,9A,16.5mOhm,SHLD,G,SMD | The Inter-Technical Group, Inc. | SMHC2511A-2R2MHF | G | PWA BOM | In Old BOM |
| 115 | PSPR4,PIPR4,PFPR4,PEPR4,PSTR5,PSLR5,PSFR5,PSER5,PSDR5,PQPR5,PFRR5,PEER5,PEDR5 | 13 | 61011HA00-017-G | RES,1 Ohm,+/-1%,1/16W,G,SMD0402 | KOA SPEER ELECTRONICS, INC. | RK73H1ETTP1R00F | G | PWA BOM | In New BOM |
|  |  |  | 61011HA00-012-G | RES,1 Ohm,+/-1%,1/16W,G,SMD0402 | WALSIN TECHNOLOGY CORPORATION | WR04W1R00FTL | G | PWA BOM | In New BOM |
|  |  |  | 61011HA00-011-G | RES,1 Ohm,+/-1%,1/16W,G,SMD0402 | YAGEO CORPORATION COMPONENT | RC0402FR-071RL | G | PWA BOM | In New BOM |
|  |  |  | 61011HA00-044-G | RES,1 Ohm,+/-1%,1/16W,G,SMD0402 | TA-I TECHNOLOGY CO., LTD | RM04FTN1R00 | G | PWA BOM | In New BOM |
|  |  |  | 61011HA00-029-G | RES,1 Ohm,+/-1%,1/16W,G,SMD0402 | VISHAY ENTER TECHNO LOGY.INC | CRCW04021R00FNED | G | PWA BOM | In New BOM |
|  | PSPR4,PIPR4,PFPR4,PEPR4,PSTR5,PSLR5,PSFR5,PSER5,PSDR5,PQPR5,PFRR5,PEER5,PEDR5 | 13 | 61011HA00-017-G | RES,1 Ohm,+/-1%,1/16W,G,SMD0402 | KOA SPEER ELECTRONICS, INC. | RK73H1ETTP1R00F | N | PWA BOM | In Old BOM |
|  |  |  | 61011HA00-012-G | RES,1 Ohm,+/-1%,1/16W,G,SMD0402 | WALSIN | WR04W1R00FTL | G | PWA BOM | In Old BOM |
|  |  |  | 61011HA00-011-G | RES,1 Ohm,+/-1%,1/16W,G,SMD0402 | YAGEO | RC0402FR-071RL | G | PWA BOM | In Old BOM |
|  |  |  | 61011HA00-044-G | RES,1 Ohm,+/-1%,1/16W,G,SMD0402 | TA-I | RM04FTN1R00 | G | PWA BOM | In Old BOM |
|  |  |  | 61011HA00-029-G | RES,1 Ohm,+/-1%,1/16W,G,SMD0402 | VISHAY ENTER TECHNO LOGY.INC | CRCW04021R00FNED | G | PWA BOM | In Old BOM |
| 116 | PEER19 | 1 | 611003400-017-G | RES,12.7KOhm,+/-0.1%,1/16W,G,SMD0402 | KOA SPEER ELECTRONICS, INC. | RN731ETTP1272B25 | G | PWA BOM | In New BOM |
|  |  |  | 61013AS00-012-G | RES,12.7KOhm,+/-0.1%,1/16W,G,SMD0402 | WALSIN TECHNOLOGY CORPORATION | WF04H1272BTL | G | PWA BOM | In New BOM |
|  |  |  | 611003400-011-G | RES,12.7KOhm,+/-0.1%,1/16W,G,SMD0402 | YAGEO CORPORATION COMPONENT | RT0402BRD0712K7L | G | PWA BOM | In New BOM |
|  |  |  | 611003400-024-G | RES,12.7KOhm,+/-0.1%,1/16W,G,SMD0402 | PANASONIC INDUSTRIAL CO.,LTD. | ERA2AEB1272X | G | PWA BOM | In New BOM |
|  |  |  | 611003400-029-G | RES,12.7KOhm,+/-0.1%,1/16W,G,SMD0402 | VISHAY ENTER TECHNO LOGY.INC | TNPW040212K7BEED | G | PWA BOM | In New BOM |
|  | PEER19 | 1 | 611003400-017-G | RES,12.7KOhm,+/-0.1%,1/16W,G,SMD0402 | KOA SPEER ELECTRONICS, INC. | RN731ETTP1272B25 | Y | PWA BOM | In Old BOM |
|  |  |  | 61013AS00-012-G | RES,12.7KOhm,+/-0.1%,1/16W,G,SMD0402 | WALSIN | WF04H1272BTL | G | PWA BOM | In Old BOM |
|  |  |  | 611003400-011-G | RES,12.7KOhm,+/-0.1%,1/16W,G,SMD0402 | YAGEO | RT0402BRD0712K7L | G | PWA BOM | In Old BOM |
|  |  |  | 611003400-024-G | RES,12.7KOhm,+/-0.1%,1/16W,G,SMD0402 | PANASONIC INDUSTRIAL CO.,LTD. | ERA2AEB1272X | G | PWA BOM | In Old BOM |
|  |  |  | 611003400-029-G | RES,12.7KOhm,+/-0.1%,1/16W,G,SMD0402 | VISHAY ENTER TECHNO LOGY.INC | TNPW040212K7BEED | G | PWA BOM | In Old BOM |
| 117 | PSRCE3000,PSRCE3001,PSPCE3003,PIPCE3003,PFPCE3003,PEPCE3003,PSPCE3004,PIPCE3004,PFPCE3004,PEPCE3004,PSPCE3005,PIPCE3005,PFPCE3005,PEPCE3005 | 14 | 62120CM00-024-G | SPEA CAP,220uF,+10%~-35%,6.3V,105C,G,SMD2816,ESR<=15mOhm | PANASONIC INDUSTRIAL CO.,LTD. | EEFCX0J221YR | G | PWA BOM | In New BOM |
|  | PSRCE3000,PSRCE3001,PSPCE3003,PIPCE3003,PFPCE3003,PEPCE3003,PSPCE3004,PIPCE3004,PFPCE3004,PEPCE3004,PSPCE3005,PIPCE3005,PFPCE3005,PEPCE3005 | 14 | 62120CM00-024-G | SPEA CAP,220uF,+10%~-35%,6.3V,105C,G,SMD2816,ESR<=15mOhm | PANASONIC INDUSTRIAL CO.,LTD. | EEFCX0J221YR | N | PWA BOM | In Old BOM |
|  |  |  | 622203H00-025-G | SPET CAP,220uF,+/-20%,6.3V,105_x0003_,G,SMD2816,ESR<=15mOhm | KEMET ELECTRONICS CORPORATION | T520V227M006ATE015 | G | PWA BOM | In Old BOM |
|  |  |  | 622203H00-028-G | SPET CAP,220uF,+/-20%,6.3V,105C,G,SMD2816,ESR<=15mOhm | NEC | PSKV0J227M015C | G | PWA BOM | In Old BOM |
| 118 | PSPL1,PIPL1,PFPL1,PEPL1 | 4 | 63032CC00-088-G | IND,1uH@100KHz,+/-20%,11A,10mOhm,SHLD,G,SMD | COOPER BUSSMANN, INC. | HCM0703-1R0-R | G | PWA BOM | In New BOM |
|  |  |  | CMMS063T1R0MS | IND,CMMS063T1R0MS | CYNTEC CO. LTD | CMMS063T1R0MS |  | PWA BOM | In New BOM |
|  |  |  | PA4341.102NLT | IND,PA4341.102NLT | PULSE ELECTRONICS (SINGAPORE) | PA4341.102NLT |  | PWA BOM | In New BOM |
|  | PSPL1,PIPL1,PFPL1,PEPL1 | 4 | 63032CC00-088-G | IND,1uH@100KHz,+/-20%,11A,10mOhm,SHLD,G,SMD | COOPER BUSSMANN, INC. | HCM0703-1R0-R |  | PWA BOM | In Old BOM |
|  |  |  | 63033LP00-15A-G | IND,1uH@100KHz,+/-20%,12.5A,8mOhm,SHLD,G,SMD | The Inter-Technical Group, Inc. | SMHC2511A-1R0MHF | G | PWA BOM | In Old BOM |
| 119 | PSPL2,PIPL2,PFPL2,PEPL2 | 4 | 630341400-088-G | IND,22nH@1MHz,+/-20%,19A,368uOhm,SHLD,G,SMD | COOPER BUSSMANN, INC. | FP0404R1-R022-R | G | PWA BOM | In New BOM |
|  |  |  | HCB0430-220 | IND,HCB0430-220 | DELTA ELECTRONICS INDUSTRIAL CO.,LTD | HCB0430-220 | G | PWA BOM | In New BOM |
|  | PSPL2,PIPL2,PFPL2,PEPL2 | 4 | 630341400-088-G | IND,22nH@1MHz,+/-20%,19A,368uOhm,SHLD,G,SMD | COOPER BUSSMANN, INC. | FP0404R1-R022-R |  | PWA BOM | In Old BOM |
|  |  |  | HCB0430-220 | IND,HCB0430-220 | Delta | HCB0430-220 | G | PWA BOM | In Old BOM |
| 120 | PSPR5,PIPR5,PFPR5,PEPR5 | 4 | 61011H300-017-G | RES,316 Ohm,+/-1%,1/16W,G,SMD0402 | KOA SPEER ELECTRONICS, INC. | RK73H1ETTP3160F | G | PWA BOM | In New BOM |
|  |  |  | 61011H300-012-G | RES,316 Ohm,+/-1%,1/16W,G,SMD0402 | WALSIN TECHNOLOGY CORPORATION | WR04X3160FTL | G | PWA BOM | In New BOM |
|  |  |  | 61011H300-011-G | RES,316 Ohm,+/-1%,1/16W,G,SMD0402 | YAGEO CORPORATION COMPONENT | RC0402FR-07316RL | G | PWA BOM | In New BOM |
|  | PSPR5,PIPR5,PFPR5,PEPR5 | 4 | 61011H300-017-G | RES,316 Ohm,+/-1%,1/16W,G,SMD0402 | KOA SPEER ELECTRONICS, INC. | RK73H1ETTP3160F | N | PWA BOM | In Old BOM |
|  |  |  | 61011H300-012-G | RES,316 Ohm,+/-1%,1/16W,G,SMD0402 | WALSIN | WR04X3160FTL | G | PWA BOM | In Old BOM |
|  |  |  | 61011H300-011-G | RES,316 Ohm,+/-1%,1/16W,G,SMD0402 | YAGEO | RC0402FR-07316RL | G | PWA BOM | In Old BOM |
| 121 | PSPR9,PIPR9,PFPR9,PEPR9,R1074,R1083,R1777 | 7 | 610116R00-017-G | RES,14.3KOhm,+/-1%,1/16W,G,SMD0402 | KOA SPEER ELECTRONICS, INC. | RK73H1ETTP1432F | G | PWA BOM | In New BOM |
|  |  |  | 610116R00-012-G | RES,14.3KOhm,+/-1%,1/16W,G,SMD0402 | WALSIN TECHNOLOGY CORPORATION | WR04X1432FTL | G | PWA BOM | In New BOM |
|  |  |  | 610116R00-011-G | RES,14.3KOhm,+/-1%,1/16W,G,SMD0402 | YAGEO CORPORATION COMPONENT | RC0402FR-0714K3L | G | PWA BOM | In New BOM |
|  |  |  | 610116R00-044-G | RES,14.3KOhm,+/-1%,1/16W,G,SMD0402 | TA-I TECHNOLOGY CO., LTD | RM04FTN1432 | G | PWA BOM | In New BOM |
|  |  |  | 610116R00-029-G | RES,14.3KOhm,+/-1%,1/16W,G,SMD0402 | VISHAY ENTER TECHNO LOGY.INC | CRCW040214K3FKED | G | PWA BOM | In New BOM |
|  | PSPR9,PIPR9,PFPR9,PEPR9,R1074,R1083,R1777 | 7 | 610116R00-017-G | RES,14.3KOhm,+/-1%,1/16W,G,SMD0402 | KOA SPEER ELECTRONICS, INC. | RK73H1ETTP1432F | N | PWA BOM | In Old BOM |
|  |  |  | 610116R00-012-G | RES,14.3KOhm,+/-1%,1/16W,G,SMD0402 | WALSIN | WR04X1432FTL | G | PWA BOM | In Old BOM |
|  |  |  | 610116R00-011-G | RES,14.3KOhm,+/-1%,1/16W,G,SMD0402 | YAGEO | RC0402FR-0714K3L | G | PWA BOM | In Old BOM |
|  |  |  | 610116R00-044-G | RES,14.3KOhm,+/-1%,1/16W,G,SMD0402 | TA-I | RM04FTN1432 | G | PWA BOM | In Old BOM |
|  |  |  | 610116R00-029-G | RES,14.3KOhm,+/-1%,1/16W,G,SMD0402 | VISHAY ENTER TECHNO LOGY.INC | CRCW040214K3FKED | G | PWA BOM | In Old BOM |
| 122 | PSPR11,PIPR11,PFPR11,PEPR11,R680,R688,R689,R755,R756,R758,R759,R771,R1487,R1541 | 14 | 610112J00-017-G | RES,200 Ohm,+/-1%,1/16W,G,SMD0402 | KOA SPEER ELECTRONICS, INC. | RK73H1ETTP2000F | G | PWA BOM | In New BOM |
|  |  |  | 610112J00-012-G | RES,200 Ohm,+/-1%,1/16W,G,SMD0402 | WALSIN TECHNOLOGY CORPORATION | WR04X2000FTL | G | PWA BOM | In New BOM |
|  |  |  | 610112J00-011-G | RES,200 Ohm,+/-1%,1/16W,G,SMD0402 | YAGEO CORPORATION COMPONENT | RC0402FR-07200RL | G | PWA BOM | In New BOM |
|  |  |  | 610112J00-044-G | RES,200 Ohm,+/-1%,1/16W,G,SMD0402 | TA-I TECHNOLOGY CO., LTD | RM04FTN2000 | G | PWA BOM | In New BOM |
|  |  |  | 610112J00-029-G | RES,200 Ohm,+/-1%,1/16W,G,SMD0402 | VISHAY ENTER TECHNO LOGY.INC | CRCW0402200RFKED | G | PWA BOM | In New BOM |
|  |  |  | 610112J00-024-G | RES,200 Ohm,+/-1%,1/16W,G,SMD0402 | PANASONIC INDUSTRIAL CO.,LTD. | ERJ2RKF2000X | G | PWA BOM | In New BOM |
|  | PSPR11,PIPR11,PFPR11,PEPR11,R680,R688,R689,R755,R756,R758,R759,R771,R1487,R1541 | 14 | 610112J00-017-G | RES,200 Ohm,+/-1%,1/16W,G,SMD0402 | KOA SPEER ELECTRONICS, INC. | RK73H1ETTP2000F | N | PWA BOM | In Old BOM |
|  |  |  | 610112J00-012-G | RES,200 Ohm,+/-1%,1/16W,G,SMD0402 | WALSIN | WR04X2000FTL | G | PWA BOM | In Old BOM |
|  |  |  | 610112J00-011-G | RES,200 Ohm,+/-1%,1/16W,G,SMD0402 | YAGEO | RC0402FR-07200RL | G | PWA BOM | In Old BOM |
|  |  |  | 610112J00-044-G | RES,200 Ohm,+/-1%,1/16W,G,SMD0402 | TA-I | RM04FTN2000 | G | PWA BOM | In Old BOM |
|  |  |  | 610112J00-029-G | RES,200 Ohm,+/-1%,1/16W,G,SMD0402 | VISHAY ENTER TECHNO LOGY.INC | CRCW0402200RFKED | G | PWA BOM | In Old BOM |
|  |  |  | 610112J00-024-G | RES,200 Ohm,+/-1%,1/16W,G,SMD0402 | PANASONIC INDUSTRIAL CO.,LTD. | ERJ2RKF2000X | G | PWA BOM | In Old BOM |
| 123 | PSRR7,PSPR15,PIPR15,PFPR15,PEPR15 | 5 | 61011MU00-017-G | RES,48.7KOhm,+/-1%,1/16W,G,SMD0402 | KOA SPEER ELECTRONICS, INC. | RK73H1ETTP4872F | G | PWA BOM | In New BOM |
|  |  |  | 61011MU00-012-G | RES,48.7KOhm,+/-1%,1/16W,G,SMD0402 | WALSIN TECHNOLOGY CORPORATION | WR04X4872FTL | G | PWA BOM | In New BOM |
|  |  |  | 61011MU00-011-G | RES,48.7KOhm,+/-1%,1/16W,G,SMD0402 | YAGEO CORPORATION COMPONENT | RC0402FR-0748K7L | G | PWA BOM | In New BOM |
|  |  |  | 61011MU00-044-G | RES,48.7KOhm,+/-1%,1/16W,G,SMD0402 | TA-I TECHNOLOGY CO., LTD | RM04FTN4872 | G | PWA BOM | In New BOM |
|  |  |  | 61011MU00-029-G | RES,48.7KOhm,+/-1%,1/16W,G,SMD0402 | VISHAY ENTER TECHNO LOGY.INC | CRCW040248K7FKED | G | PWA BOM | In New BOM |
|  | PSRR7,PSPR15,PIPR15,PFPR15,PEPR15 | 5 | 61011MU00-017-G | RES,48.7KOhm,+/-1%,1/16W,G,SMD0402 | KOA SPEER ELECTRONICS, INC. | RK73H1ETTP4872F | N | PWA BOM | In Old BOM |
|  |  |  | 61011MU00-012-G | RES,48.7KOhm,+/-1%,1/16W,G,SMD0402 | WALSIN | WR04X4872FTL | G | PWA BOM | In Old BOM |
|  |  |  | 61011MU00-011-G | RES,48.7KOhm,+/-1%,1/16W,G,SMD0402 | YAGEO | RC0402FR-0748K7L | G | PWA BOM | In Old BOM |
|  |  |  | 61011MU00-044-G | RES,48.7KOhm,+/-1%,1/16W,G,SMD0402 | TA-I | RM04FTN4872 | G | PWA BOM | In Old BOM |
|  |  |  | 61011MU00-029-G | RES,48.7KOhm,+/-1%,1/16W,G,SMD0402 | VISHAY ENTER TECHNO LOGY.INC | CRCW040248K7FKED | G | PWA BOM | In Old BOM |
| 124 | PERC7 | 1 | 62013BN00-015-G | CAP,4.3nF,+/-10%,X7R,50V,G,SMD0402 | MURATA ELEC. NORTH AMERICA | GRM155R71H432KA01D | G | PWA BOM | In New BOM |
|  |  |  | 62010LJ00-023-G | CAP,4.7nF,+/-10%,X7R,50V,G,SMD0402 | TAIYO | UMK105B7472KV-F |  | PWA BOM | In New BOM |
|  | PERC7 | 1 | 62013BN00-015-G | CAP,4.3nF,+/-10%,X7R,50V,G,SMD0402 | MURATA ELEC. NORTH AMERICA | GRM155R71H432KA01D |  | PWA BOM | In Old BOM |
| 125 | PERR2,PHAR35 | 2 | 61011PE00-017-G | RES,8.87KOhm,+/-1%,1/16W,G,SMD0402 | KOA SPEER ELECTRONICS, INC. | RK73H1ETTP8871F | G | PWA BOM | In New BOM |
|  |  |  | 61011PE00-012-G | RES,8.87KOhm,+/-1%,1/16W,G,SMD0402 | WALSIN TECHNOLOGY CORPORATION | WR04X8871FTL | G | PWA BOM | In New BOM |
|  |  |  | 61011PE00-011-G | RES,8.87KOhm,+/-1%,1/16W,G,SMD0402 | YAGEO CORPORATION COMPONENT | RC0402FR-078K87L | G | PWA BOM | In New BOM |
|  |  |  | 61011PE00-044-G | RES,8.87KOhm,+/-1%,1/16W,G,SMD0402 | TA-I TECHNOLOGY CO., LTD | RM04FTN8871 | G | PWA BOM | In New BOM |
|  | PERR2,PHAR35 | 2 | 61011PE00-017-G | RES,8.87KOhm,+/-1%,1/16W,G,SMD0402 | KOA SPEER ELECTRONICS, INC. | RK73H1ETTP8871F | N | PWA BOM | In Old BOM |
|  |  |  | 61011PE00-012-G | RES,8.87KOhm,+/-1%,1/16W,G,SMD0402 | WALSIN | WR04X8871FTL | G | PWA BOM | In Old BOM |
|  |  |  | 61011PE00-011-G | RES,8.87KOhm,+/-1%,1/16W,G,SMD0402 | YAGEO | RC0402FR-078K87L | G | PWA BOM | In Old BOM |
|  |  |  | 61011PE00-044-G | RES,8.87KOhm,+/-1%,1/16W,G,SMD0402 | TA-I | RM04FTN8871 | G | PWA BOM | In Old BOM |
| 126 | PERR8,PERR11 | 2 | 61100JA00-017-G | RES,8.66KOhm,+/-0.1%,1/16W,G,SMD0402 | KOA SPEER ELECTRONICS, INC. | RN731ETTP8661B25 | G | PWA BOM | In New BOM |
|  |  |  | 61100JA00-012-G | RES,8.66KOhm,+/-0.1%,1/16W,G,SMD0402 | WALSIN TECHNOLOGY CORPORATION | WF04U8661BTL | G | PWA BOM | In New BOM |
|  |  |  | 61100JA00-011-G | RES,8.66KOhm,+/-0.1%,1/16W,G,SMD0402 | YAGEO CORPORATION COMPONENT | RT0402BRD078K66L | G | PWA BOM | In New BOM |
|  |  |  | 61100JA00-044-G | RES,8.66KOhm,+/-0.1%,1/16W,G,SMD0402 | TA-I TECHNOLOGY CO., LTD | RB04BTP8661 | G | PWA BOM | In New BOM |
|  |  |  | 61100JA00-024-G | RES,8.66KOhm,+/-0.1%,1/16W,G,SMD0402 | PANASONIC INDUSTRIAL CO.,LTD. | ERA2AEB8661X | G | PWA BOM | In New BOM |
|  |  |  | 61100JA00-029-G | RES,8.66KOhm,+/-0.1%,1/16W,G,SMD0402 | VISHAY ENTER TECHNO LOGY.INC | TNPW04028K66BEED | G | PWA BOM | In New BOM |
|  | PERR8,PERR11 | 2 | 61100JA00-017-G | RES,8.66KOhm,+/-0.1%,1/16W,G,SMD0402 | KOA SPEER ELECTRONICS, INC. | RN731ETTP8661B25 | Y | PWA BOM | In Old BOM |
|  |  |  | 61100JA00-012-G | RES,8.66KOhm,+/-0.1%,1/16W,G,SMD0402 | WALSIN | WF04U8661BTL | G | PWA BOM | In Old BOM |
|  |  |  | 61100JA00-011-G | RES,8.66KOhm,+/-0.1%,1/16W,G,SMD0402 | YAGEO | RT0402BRD078K66L | G | PWA BOM | In Old BOM |
|  |  |  | 61100JA00-044-G | RES,8.66KOhm,+/-0.1%,1/16W,G,SMD0402 | TA-I | RB04BTP8661 | G | PWA BOM | In Old BOM |
|  |  |  | 61100JA00-024-G | RES,8.66KOhm,+/-0.1%,1/16W,G,SMD0402 | PANASONIC INDUSTRIAL CO.,LTD. | ERA2AEB8661X | G | PWA BOM | In Old BOM |
|  |  |  | 61100JA00-029-G | RES,8.66KOhm,+/-0.1%,1/16W,G,SMD0402 | VISHAY ENTER TECHNO LOGY.INC | TNPW04028K66BEED | G | PWA BOM | In Old BOM |
| 127 | PETC7 | 1 | 62011AM00-015-G | CAP,6.8nF,+/-10%,X7R,50V,G,SMD0402 | MURATA ELEC. NORTH AMERICA | GRM155R71H682K | G | PWA BOM | In New BOM |
|  |  |  | 62011AM00-012-G | CAP,6.8nF,+/-10%,X7R,50V,G,SMD0402 | WALSIN TECHNOLOGY CORPORATION | 0402B682K500CT | G | PWA BOM | In New BOM |
|  |  |  | 62011AM00-026-G | CAP,6.8nF,+/-10%,X7R,50V,G,SMD0402 | SAMSUNG SEMICONDUCTOR | CL05B682KB5NNNC | G | PWA BOM | In New BOM |
|  | PETC7 | 1 | 62011AM00-015-G | CAP,6.8nF,+/-10%,X7R,50V,G,SMD0402 | MURATA ELEC. NORTH AMERICA | GRM155R71H682K | N | PWA BOM | In Old BOM |
|  |  |  | 62011AM00-012-G | CAP,6.8nF,+/-10%,X7R,50V,G,SMD0402 | WALSIN | 0402B682K500CT | G | PWA BOM | In Old BOM |
|  |  |  | 62011AM00-026-G | CAP,6.8nF,+/-10%,X7R,50V,G,SMD0402 | SAMSUNG SEMICONDUCTOR | CL05B682KB5NNNC | G | PWA BOM | In Old BOM |
| 128 | PETR2 | 1 | 61011KY00-017-G | RES,3.83KOhm,+/-1%,1/16W,G,SMD0402 | KOA SPEER ELECTRONICS, INC. | RK73H1ETTP3831F | G | PWA BOM | In New BOM |
|  |  |  | 61011KY00-012-G | RES,3.83KOhm,+/-1%,1/16W,G,SMD0402 | WALSIN TECHNOLOGY CORPORATION | WR04X3831FTL | G | PWA BOM | In New BOM |
|  |  |  | 61011KY00-011-G | RES,3.83KOhm,+/-1%,1/16W,G,SMD0402 | YAGEO CORPORATION COMPONENT | RC0402FR-073K83L | G | PWA BOM | In New BOM |
|  |  |  | 61011KY00-044-G | RES,3.83KOhm,+/-1%,1/16W,G,SMD0402 | TA-I TECHNOLOGY CO., LTD | RM04FTN3831 | G | PWA BOM | In New BOM |
|  |  |  | 61011KY00-029-G | RES,3.83KOhm,+/-1%,1/16W,G,SMD0402 | VISHAY ENTER TECHNO LOGY.INC | CRCW04023K83FKED | G | PWA BOM | In New BOM |
|  | PETR2 | 1 | 61011KY00-017-G | RES,3.83KOhm,+/-1%,1/16W,G,SMD0402 | KOA SPEER ELECTRONICS, INC. | RK73H1ETTP3831F | N | PWA BOM | In Old BOM |
|  |  |  | 61011KY00-012-G | RES,3.83KOhm,+/-1%,1/16W,G,SMD0402 | WALSIN | WR04X3831FTL | G | PWA BOM | In Old BOM |
|  |  |  | 61011KY00-011-G | RES,3.83KOhm,+/-1%,1/16W,G,SMD0402 | YAGEO | RC0402FR-073K83L | G | PWA BOM | In Old BOM |
|  |  |  | 61011KY00-044-G | RES,3.83KOhm,+/-1%,1/16W,G,SMD0402 | TA-I | RM04FTN3831 | G | PWA BOM | In Old BOM |
|  |  |  | 61011KY00-029-G | RES,3.83KOhm,+/-1%,1/16W,G,SMD0402 | VISHAY ENTER TECHNO LOGY.INC | CRCW04023K83FKED | G | PWA BOM | In Old BOM |
| 129 | PSIR8,PETR8,PSIR11,PETR11 | 4 | 611007000-017-G | RES,8.25KOhm,+/-0.1%,1/16W,G,SMD0402 | KOA SPEER ELECTRONICS, INC. | RN731ETTP8251B25 | G | PWA BOM | In New BOM |
|  |  |  | 611007000-012-G | RES,8.25KOhm,+/-0.1%,1/16W,G,SMD0402 | WALSIN TECHNOLOGY CORPORATION | WF04U8251BTL | G | PWA BOM | In New BOM |
|  |  |  | 611007000-011-G | RES,8.25KOhm,+/-0.1%,1/16W,G,SMD0402 | YAGEO CORPORATION COMPONENT | RT0402BRD078K25L | G | PWA BOM | In New BOM |
|  | PSIR8,PETR8,PSIR11,PETR11 | 4 | 611007000-017-G | RES,8.25KOhm,+/-0.1%,1/16W,G,SMD0402 | KOA SPEER ELECTRONICS, INC. | RN731ETTP8251B25 | Y | PWA BOM | In Old BOM |
|  |  |  | 611007000-012-G | RES,8.25KOhm,+/-0.1%,1/16W,G,SMD0402 | WALSIN | WF04U8251BTL | G | PWA BOM | In Old BOM |
|  |  |  | 611007000-011-G | RES,8.25KOhm,+/-0.1%,1/16W,G,SMD0402 | YAGEO | RT0402BRD078K25L | G | PWA BOM | In Old BOM |
| 130 | PSTC14,PQPC14,PFRC14 | 3 | 620105U00-015-G | CAP,220pF,+/-10%,X7R,50V,G,SMD0402 | MURATA ELEC. NORTH AMERICA | GRM155R71H221K | G | PWA BOM | In New BOM |
|  |  |  | 620105U00-012-G | CAP,220pF,+/-10%,X7R,50V,G,SMD0402 | WALSIN TECHNOLOGY CORPORATION | 0402B221K500CT | G | PWA BOM | In New BOM |
|  |  |  | 620105U00-026-G | CAP,220pF,+/-10%,X7R,50V,G,SMD0402 | SAMSUNG SEMICONDUCTOR | CL05B221KB5NNNC | G | PWA BOM | In New BOM |
|  | PSTC14,PQPC14,PFRC14 | 3 | 620105U00-015-G | CAP,220pF,+/-10%,X7R,50V,G,SMD0402 | MURATA ELEC. NORTH AMERICA | GRM155R71H221K | N | PWA BOM | In Old BOM |
|  |  |  | 620105U00-012-G | CAP,220pF,+/-10%,X7R,50V,G,SMD0402 | WALSIN | 0402B221K500CT | G | PWA BOM | In Old BOM |
|  |  |  | 620105U00-026-G | CAP,220pF,+/-10%,X7R,50V,G,SMD0402 | SAMSUNG SEMICONDUCTOR | CL05B221KB5NNNC | G | PWA BOM | In Old BOM |
| 131 | PFRR1 | 1 | 61011R400-017-G | RES,34.8KOhm,+/-1%,1/16W,G,SMD0402 | KOA SPEER ELECTRONICS, INC. | RK73H1ETTP3482F | G | PWA BOM | In New BOM |
|  |  |  | 61011R400-012-G | RES,34.8KOhm,+/-1%,1/16W,G,SMD0402 | WALSIN TECHNOLOGY CORPORATION | WR04X3482FTL | G | PWA BOM | In New BOM |
|  |  |  | 61011R400-011-G | RES,34.8KOhm,+/-1%,1/16W,G,SMD0402 | YAGEO CORPORATION COMPONENT | RC0402FR-0734K8L | G | PWA BOM | In New BOM |
|  |  |  | 61011R400-044-G | RES,34.8KOhm,+/-1%,1/16W,G,SMD0402 | TA-I TECHNOLOGY CO., LTD | RM04FTN3482 | G | PWA BOM | In New BOM |
|  | PFRR1 | 1 | 61011R400-017-G | RES,34.8KOhm,+/-1%,1/16W,G,SMD0402 | KOA SPEER ELECTRONICS, INC. | RK73H1ETTP3482F | N | PWA BOM | In Old BOM |
|  |  |  | 61011R400-012-G | RES,34.8KOhm,+/-1%,1/16W,G,SMD0402 | WALSIN | WR04X3482FTL | G | PWA BOM | In Old BOM |
|  |  |  | 61011R400-011-G | RES,34.8KOhm,+/-1%,1/16W,G,SMD0402 | YAGEO | RC0402FR-0734K8L | G | PWA BOM | In Old BOM |
|  |  |  | 61011R400-044-G | RES,34.8KOhm,+/-1%,1/16W,G,SMD0402 | TA-I | RM04FTN3482 | G | PWA BOM | In Old BOM |
| 132 | PHAC3 | 1 | 620133600-015-G | CAP,1nF,+/-5%,X7R,100V,G,SMD0805 | MURATA ELEC. NORTH AMERICA | GRM219R72A102JA01D | G | PWA BOM | In New BOM |
|  |  |  | 620133600-012-G | CAP,1nF,+/-5%,X7R,100V,G,SMD0805 | WALSIN TECHNOLOGY CORPORATION | 0805B102J101CT | G | PWA BOM | In New BOM |
|  | PHAC3 | 1 | 620133600-015-G | CAP,1nF,+/-5%,X7R,100V,G,SMD0805 | MURATA ELEC. NORTH AMERICA | GRM219R72A102JA01D |  | PWA BOM | In Old BOM |
|  |  |  | 620133600-012-G | CAP,1nF,+/-5%,X7R,100V,G,SMD0805 | WALSIN | 0805B102J101CT | G | PWA BOM | In Old BOM |
| 133 | PHAC18 | 1 | 620135500-015-G | CAP,39nF,+/-10%,X7R,100V,G,SMD0805 | MURATA ELEC. NORTH AMERICA | GRM21BR72A393KA01L | G | PWA BOM | In New BOM |
|  |  |  | 620135500-012-G | CAP,39nF,+/-10%,X7R,100V,G,SMD0805 | WALSIN TECHNOLOGY CORPORATION | 0805B393K101CT | G | PWA BOM | In New BOM |
|  | PHAC18 | 1 | 620135500-015-G | CAP,39nF,+/-10%,X7R,100V,G,SMD0805 | MURATA ELEC. NORTH AMERICA | GRM21BR72A393KA01L |  | PWA BOM | In Old BOM |
|  |  |  | 620135500-012-G | CAP,39nF,+/-10%,X7R,100V,G,SMD0805 | WALSIN | 0805B393K101CT | G | PWA BOM | In Old BOM |
| 134 | PHAD3 | 1 | 52040EC00-237-G | DIODE,Zener,MMSZ5246B-7-F,16V,7.8mA,G,SOD123-2,SMD | DIODES INEORPORATION | MMSZ5246B-7-F | G | PWA BOM | In New BOM |
|  |  |  | 52040B500-223-G | DIODE,Zener,MMSZ5246BT1G,16V,7.8mA,G,SOD123-2,SMD | ON | MMSZ5246BT1G | G | PWA BOM | In New BOM |
|  |  |  | 52040EY00-031-G | Diode,ZENER,BZT52H-C16,17.1V,5mA,G,SOD123F-2,SMD | NXP SEMICONDUCTORS | BZT52H-C16 | G | PWA BOM | In New BOM |
|  | PHAD3 | 1 | 52040EC00-237-G | DIODE,Zener,MMSZ5246B-7-F,16V,7.8mA,G,SOD123-2,SMD | DIODES INEORPORATION | MMSZ5246B-7-F | N | PWA BOM | In Old BOM |
|  |  |  | 52040B500-223-G | DIODE,Zener,MMSZ5246BT1G,16V,7.8mA,G,SOD123-2,SMD | ON | MMSZ5246BT1G | G | PWA BOM | In Old BOM |
|  |  |  | 52040EY00-031-G | Diode,ZENER,BZT52H-C16,17.1V,5mA,G,SOD123F-2,SMD | NXP | BZT52H-C16 | G | PWA BOM | In Old BOM |
| 135 | PHAQ1,PHAQ2,PHAQ3 | 3 | 51031VY00-031-G | MOS N,PSMN4R8-100BSE,100V,120A,4.8m@10V,G,SOT404-3,SMD | NXP SEMICONDUCTORS | PSMN4R8-100BSE | G | PWA BOM | In New BOM |
|  |  |  | SUM70040E-GE3 | MOS N,SUM70040E-GE3 | VISHAY ENTER TECHNO LOGY.INC | SUM70040E-GE3 | G | PWA BOM | In New BOM |
|  |  |  | FDB047N10 | MOS N,FDB047N10 | FAIRCHILD SEMICONDUCTOR CORP | FDB047N10 | G | PWA BOM | In New BOM |
|  | PHAQ1,PHAQ2,PHAQ3 | 3 | 51031VY00-031-G | MOS N,PSMN4R8-100BSE,100V,120A,4.8m@10V,G,SOT404-3,SMD | NXP SEMICONDUCTORS | PSMN4R8-100BSE |  | PWA BOM | In Old BOM |
|  |  |  | SUM70040E-GE3 | MOS N,SUM70040E-GE3 | Vishay | SUM70040E-GE3 | G | PWA BOM | In Old BOM |
|  |  |  | FDB047N10 | MOS N,FDB047N10 | Fairchild | FDB047N10 | G | PWA BOM | In Old BOM |
| 136 | PHAQ4 | 1 | 51020A000-031-G | TRANS P,PBHV9115T,150V,1A,G,SOT23-3,SMD | NXP SEMICONDUCTORS | PBHV9115T | G | PWA BOM | In New BOM |
|  |  |  | MMBT5401 | TRANS P,150V,1A,G,SOT23-3,SMD | FAIRCHILD SEMICONDUCTOR CORP | MMBT5401 | G | PWA BOM | In New BOM |
|  |  |  | MMBT5401_1 | TRANS P,150V,1A,G,SOT23-3,SMD | DIODES INCORPORATION | MMBT5401_1 | G | PWA BOM | In New BOM |
|  | PHAQ4 | 1 | 51020A000-031-G | TRANS P,PBHV9115T,150V,1A,G,SOT23-3,SMD | NXP SEMICONDUCTORS | PBHV9115T |  | PWA BOM | In Old BOM |
|  |  |  | 51020AF00-280-G | Trans PNP,MMBT5401,-150V,-500mA,SOT-23,3P,G | Fairchild | MMBT5401 | G | PWA BOM | In Old BOM |
|  |  |  | MMBT5401 | TRANS,150V,1A,G,SOT23-3,SMD | DIODES | MMBT5401 |  | PWA BOM | In Old BOM |
| 137 | PHAQ5,PHAQ6 | 2 | 51032D100-237-G | MOS N,DMN10H220L-7,100V,1.6A,220m@10V,G,SOT-23-3,SMD | DIODES INCORPORATION | DMN10H220L-7 | G | PWA BOM | In New BOM |
|  |  |  | FQT7N10LTF | MOS N,FQT7N10LTF,100V,1.7A,220m@10V,G,SOT-23-3,SMD | FAIRCHILD SEMICONDUCTOR CORP | FQT7N10LTF | G | PWA BOM | In New BOM |
|  | PHAQ5,PHAQ6 | 2 | 51032D100-237-G | MOS N,DMN10H220L-7,100V,1.6A,220m@10V,G,SOT-23-3,SMD | DIODES INCORPORATION | DMN10H220L-7 |  | PWA BOM | In Old BOM |
|  |  |  | FQT7N10LTF | MOS N,FQT7N10LTF | Fairchild | FQT7N10LTF | G | PWA BOM | In Old BOM |
| 138 | PHAR2 | 1 | 61100DA00-017-G | RES,33KOhm,+/-0.1%,1/16W,G,SMD0402 | KOA SPEER ELECTRONICS, INC. | RN731ETTP3302B25 | G | PWA BOM | In New BOM |
|  |  |  | 61100DA00-012-G | RES,33KOhm,+/-0.1%,1/16W,G,SMD0402 | WALSIN TECHNOLOGY CORPORATION | WF04U3302BTL | G | PWA BOM | In New BOM |
|  |  |  | 61100DA00-011-G | RES,33KOhm,+/-0.1%,1/16W,G,SMD0402 | YAGEO CORPORATION COMPONENT | RT0402BRD0733KL | G | PWA BOM | In New BOM |
|  | PHAR2 | 1 | 61100DA00-017-G | RES,33KOhm,+/-0.1%,1/16W,G,SMD0402 | KOA SPEER ELECTRONICS, INC. | RN731ETTP3302B25 |  | PWA BOM | In Old BOM |
|  |  |  | 61100DA00-012-G | RES,33KOhm,+/-0.1%,1/16W,G,SMD0402 | WALSIN | WF04U3302BTL | G | PWA BOM | In Old BOM |
|  |  |  | 61100DA00-011-G | RES,33KOhm,+/-0.1%,1/16W,G,SMD0402 | YAGEO | RT0402BRD0733KL | G | PWA BOM | In Old BOM |
| 139 | PHAR5 | 1 | 61100QM00-017-G | RES,100KOhm,+/-0.1%,1/10W,G,SMD0603 | KOA SPEER ELECTRONICS, INC. | RN73H1JTTD1003B25 | G | PWA BOM | In New BOM |
|  |  |  | 61100QM00-012-G | RES,100KOhm,+/-0.1%,1/10W,G,SMD0603 | WALSIN TECHNOLOGY CORPORATION | WF06Q1003BTL | G | PWA BOM | In New BOM |
|  |  |  | 61100QM00-011-G | RES,100KOhm,+/-0.1%,1/10W,G,SMD0603 | YAGEO CORPORATION COMPONENT | RT0603BRD07100KL | G | PWA BOM | In New BOM |
|  | PHAR5 | 1 | 61100QM00-017-G | RES,100KOhm,+/-0.1%,1/10W,G,SMD0603 | KOA SPEER ELECTRONICS, INC. | RN73H1JTTD1003B25 |  | PWA BOM | In Old BOM |
|  |  |  | 61100QM00-012-G | RES,100KOhm,+/-0.1%,1/10W,G,SMD0603 | WALSIN | WF06Q1003BTL | G | PWA BOM | In Old BOM |
|  |  |  | 61100QM00-011-G | RES,100KOhm,+/-0.1%,1/10W,G,SMD0603 | YAGEO | RT0603BRD07100KL | G | PWA BOM | In Old BOM |
| 140 | PHAR6 | 1 | 610100R00-017-G | RES,3.74KOhm,+/-1%,1/10W,G,SMD0603 | KOA SPEER ELECTRONICS, INC. | RK73H1JTTD3741F | G | PWA BOM | In New BOM |
|  |  |  | 610100R00-012-G | RES,3.74KOhm,+/-1%,1/10W,G,SMD0603 | WALSIN TECHNOLOGY CORPORATION | WR06X3741FTL | G | PWA BOM | In New BOM |
|  |  |  | 610100R00-011-G | RES,3.74KOhm,+/-1%,1/10W,G,SMD0603 | YAGEO CORPORATION COMPONENT | RC0603FR-073K74L | G | PWA BOM | In New BOM |
|  |  |  | 610100R00-044-G | RES,3.74KOhm,+/-1%,1/10W,G,SMD0603 | TA-I TECHNOLOGY CO., LTD | RM06FTN3741 | G | PWA BOM | In New BOM |
|  | PHAR6 | 1 | 610100R00-017-G | RES,3.74KOhm,+/-1%,1/10W,G,SMD0603 | KOA SPEER ELECTRONICS, INC. | RK73H1JTTD3741F | N | PWA BOM | In Old BOM |
|  |  |  | 610100R00-012-G | RES,3.74KOhm,+/-1%,1/10W,G,SMD0603 | WALSIN | WR06X3741FTL | G | PWA BOM | In Old BOM |
|  |  |  | 610100R00-011-G | RES,3.74KOhm,+/-1%,1/10W,G,SMD0603 | YAGEO | RC0603FR-073K74L | G | PWA BOM | In Old BOM |
|  |  |  | 610100R00-044-G | RES,3.74KOhm,+/-1%,1/10W,G,SMD0603 | TA-I | RM06FTN3741 | G | PWA BOM | In Old BOM |
| 141 | PHAR7 | 1 | 610107P00-017-G | RES,4.12KOhm,+/-1%,1/10W,G,SMD0603 | KOA SPEER ELECTRONICS, INC. | RK73H1JTTD4121F | G | PWA BOM | In New BOM |
|  |  |  | 610107P00-012-G | RES,4.12KOhm,+/-1%,1/10W,G,SMD0603 | WALSIN TECHNOLOGY CORPORATION | WR06X4121FTL | G | PWA BOM | In New BOM |
|  |  |  | 610107P00-011-G | RES,4.12KOhm,+/-1%,1/10W,G,SMD0603 | YAGEO CORPORATION COMPONENT | RC0603FR-074K12L | G | PWA BOM | In New BOM |
|  |  |  | 610107P00-044-G | RES,4.12KOhm,+/-1%,1/10W,G,SMD0603 | TA-I TECHNOLOGY CO., LTD | RM06FTN4121 | G | PWA BOM | In New BOM |
|  | PHAR7 | 1 | 610107P00-017-G | RES,4.12KOhm,+/-1%,1/10W,G,SMD0603 | KOA SPEER ELECTRONICS, INC. | RK73H1JTTD4121F | N | PWA BOM | In Old BOM |
|  |  |  | 610107P00-012-G | RES,4.12KOhm,+/-1%,1/10W,G,SMD0603 | WALSIN | WR06X4121FTL | G | PWA BOM | In Old BOM |
|  |  |  | 610107P00-011-G | RES,4.12KOhm,+/-1%,1/10W,G,SMD0603 | YAGEO | RC0603FR-074K12L | G | PWA BOM | In Old BOM |
|  |  |  | 610107P00-044-G | RES,4.12KOhm,+/-1%,1/10W,G,SMD0603 | TA-I | RM06FTN4121 | G | PWA BOM | In Old BOM |
| 142 | PHAR13 | 1 | 61013GW00-017-G | RES,150KOhm,+/-1%,1/8W,G,SMD0805 | KOA SPEER ELECTRONICS, INC. | RK73H2ATTD1503F | G | PWA BOM | In New BOM |
|  |  |  | 61013GW00-012-G | RES,150KOhm,+/-1%,1/8W,G,SMD0805 | WALSIN TECHNOLOGY CORPORATION | WR08X1503FTL | G | PWA BOM | In New BOM |
|  |  |  | 61013GW00-011-G | RES,150KOhm,+/-1%,1/8W,G,SMD0805 | YAGEO CORPORATION COMPONENT | RC0805FR-07150KL | G | PWA BOM | In New BOM |
|  |  |  | 61013GW00-044-G | RES,150KOhm,+/-1%,1/8W,G,SMD0805 | TA-I TECHNOLOGY CO., LTD | RM10FTN1503 | G | PWA BOM | In New BOM |
|  | PHAR13 | 1 | 61013GW00-017-G | RES,150KOhm,+/-1%,1/8W,G,SMD0805 | KOA SPEER ELECTRONICS, INC. | RK73H2ATTD1503F | N | PWA BOM | In Old BOM |
|  |  |  | 61013GW00-012-G | RES,150KOhm,+/-1%,1/8W,G,SMD0805 | WALSIN | WR08X1503FTL | G | PWA BOM | In Old BOM |
|  |  |  | 61013GW00-011-G | RES,150KOhm,+/-1%,1/8W,G,SMD0805 | YAGEO | RC0805FR-07150KL | G | PWA BOM | In Old BOM |
|  |  |  | 61013GW00-044-G | RES,150KOhm,+/-1%,1/8W,G,SMD0805 | TA-I | RM10FTN1503 | G | PWA BOM | In Old BOM |
| 143 | PHAR20 | 1 | 610119P00-017-G | RES,5.11KOhm,+/-1%,1/16W,G,SMD0402 | KOA SPEER ELECTRONICS, INC. | RK73H1ETTP5111F | G | PWA BOM | In New BOM |
|  |  |  | 610119P00-012-G | RES,5.11KOhm,+/-1%,1/16W,G,SMD0402 | WALSIN TECHNOLOGY CORPORATION | WR04X5111FTL | G | PWA BOM | In New BOM |
|  |  |  | 610119P00-011-G | RES,5.11KOhm,+/-1%,1/16W,G,SMD0402 | YAGEO CORPORATION COMPONENT | RC0402FR-075K11L | G | PWA BOM | In New BOM |
|  |  |  | 610119P00-024-G | RES,5.11KOhm,+/-1%,1/16W,G,SMD0402 | PANASONIC | ERJ2RKF5111X | G | PWA BOM | In New BOM |
|  |  |  | 610119P00-029-G | RES,5.11KOhm,+/-1%,1/16W,G,SMD0402 | VISHAY ENTER TECHNO LOGY.INC | CRCW04025K11FKED | G | PWA BOM | In New BOM |
|  | PHAR20 | 1 | 610119P00-017-G | RES,5.11KOhm,+/-1%,1/16W,G,SMD0402 | KOA SPEER ELECTRONICS, INC. | RK73H1ETTP5111F | N | PWA BOM | In Old BOM |
|  |  |  | 610119P00-012-G | RES,5.11KOhm,+/-1%,1/16W,G,SMD0402 | WALSIN | WR04X5111FTL | G | PWA BOM | In Old BOM |
|  |  |  | 610119P00-011-G | RES,5.11KOhm,+/-1%,1/16W,G,SMD0402 | YAGEO | RC0402FR-075K11L | G | PWA BOM | In Old BOM |
|  |  |  | 610119P00-024-G | RES,5.11KOhm,+/-1%,1/16W,G,SMD0402 | PANASONIC | ERJ2RKF5111X | G | PWA BOM | In Old BOM |
|  |  |  | 610119P00-029-G | RES,5.11KOhm,+/-1%,1/16W,G,SMD0402 | VISHAY ENTER TECHNO LOGY.INC | CRCW04025K11FKED | G | PWA BOM | In Old BOM |
| 144 | PHAR78 | 1 | 61012Y700-017-G | RES,49.9KOhm,+/-1%,1/8W,G,SMD0805 | KOA SPEER ELECTRONICS, INC. | RK73H2ATTD4992F | G | PWA BOM | In New BOM |
|  |  |  | 61012Y700-012-G | RES,49.9KOhm,+/-1%,1/8W,G,SMD0805 | WALSIN TECHNOLOGY CORPORATION | WR08X4992FTL | G | PWA BOM | In New BOM |
|  |  |  | 61012Y700-011-G | RES,49.9KOhm,+/-1%,1/8W,G,SMD0805 | YAGEO CORPORATION COMPONENT | RC0805FR-0749K9L | G | PWA BOM | In New BOM |
|  |  |  | 61012Y700-044-G | RES,49.9KOhm,+/-1%,1/8W,G,SMD0805 | TA-I TECHNOLOGY CO., LTD | RM10FTN4992 | G | PWA BOM | In New BOM |
|  | PHAR78 | 1 | 61012Y700-017-G | RES,49.9KOhm,+/-1%,1/8W,G,SMD0805 | KOA SPEER ELECTRONICS, INC. | RK73H2ATTD4992F | N | PWA BOM | In Old BOM |
|  |  |  | 61012Y700-012-G | RES,49.9KOhm,+/-1%,1/8W,G,SMD0805 | WALSIN | WR08X4992FTL | G | PWA BOM | In Old BOM |
|  |  |  | 61012Y700-011-G | RES,49.9KOhm,+/-1%,1/8W,G,SMD0805 | YAGEO | RC0805FR-0749K9L | G | PWA BOM | In Old BOM |
|  |  |  | 61012Y700-044-G | RES,49.9KOhm,+/-1%,1/8W,G,SMD0805 | TA-I | RM10FTN4992 | G | PWA BOM | In Old BOM |
| 145 | PSDR19 | 1 | 61100KM01-017-G | RES,15KOhm,+/-0.1%,1/16W,G,SMD0402 | KOA SPEER ELECTRONICS, INC. | RN73H1ETTP1502B25 | G | PWA BOM | In New BOM |
|  |  |  | ERA2AEB153X | RES,15KOhm,+/-0.1%,1/16W,G,SMD0402 | PANASONIC INDUSTRIAL CO.,LTD. | ERA2AEB153X | G | PWA BOM | In New BOM |
|  | PSDR19 | 1 | 61100KM01-017-G | RES,15KOhm,+/-0.1%,1/16W,G,SMD0402 | KOA SPEER ELECTRONICS, INC. | RN73H1ETTP1502B25 |  | PWA BOM | In Old BOM |
|  |  |  | 61100KM00-024-G | RES,15KOhm,+/-0.1%,1/16W,G,SMD0402 | PANASONIC INDUSTRIAL CO.,LTD. | ERA2AEB1502X | G | PWA BOM | In Old BOM |
| 146 | PSIR2 | 1 | 61011MA00-017-G | RES,3.32KOhm,+/-1%,1/16W,G,SMD0402 | KOA SPEER ELECTRONICS, INC. | RK73H1ETTP3321F | G | PWA BOM | In New BOM |
|  |  |  | 61011MA00-012-G | RES,3.32KOhm,+/-1%,1/16W,G,SMD0402 | WALSIN TECHNOLOGY CORPORATION | WR04X3321FTL | G | PWA BOM | In New BOM |
|  |  |  | 61011MA00-011-G | RES,3.32KOhm,+/-1%,1/16W,G,SMD0402 | YAGEO CORPORATION COMPONENT | RC0402FR-073K32L | G | PWA BOM | In New BOM |
|  |  |  | 61011MA00-044-G | RES,3.32KOhm,+/-1%,1/16W,G,SMD0402 | TA-I TECHNOLOGY CO., LTD | RM04FTN3321 | G | PWA BOM | In New BOM |
|  | PSIR2 | 1 | 61011MA00-017-G | RES,3.32KOhm,+/-1%,1/16W,G,SMD0402 | KOA SPEER ELECTRONICS, INC. | RK73H1ETTP3321F | N | PWA BOM | In Old BOM |
|  |  |  | 61011MA00-012-G | RES,3.32KOhm,+/-1%,1/16W,G,SMD0402 | WALSIN | WR04X3321FTL | G | PWA BOM | In Old BOM |
|  |  |  | 61011MA00-011-G | RES,3.32KOhm,+/-1%,1/16W,G,SMD0402 | YAGEO | RC0402FR-073K32L | G | PWA BOM | In Old BOM |
|  |  |  | 61011MA00-044-G | RES,3.32KOhm,+/-1%,1/16W,G,SMD0402 | TA-I | RM04FTN3321 | G | PWA BOM | In Old BOM |
| 147 | PSLR19 | 1 | 61100DF00-017-G | RES,6.34KOhm,+/-0.1%,1/16W,G,SMD0402 | KOA SPEER ELECTRONICS, INC. | RN731ETTP6341B25 | G | PWA BOM | In New BOM |
|  |  |  | 61100DF00-011-G | RES,6.34KOhm,+/-0.1%,1/16W,G,SMD0402 | YAGEO CORPORATION COMPONENT | RT0402BRD076K34L | G | PWA BOM | In New BOM |
|  |  |  | 61100DF00-012-G | RES,6.34KOhm,+/-0.1%,1/16W,G,SMD0402 | WALSIN TECHNOLOGY CORPORATION | WF04U6341BTL | G | PWA BOM | In New BOM |
|  |  |  | 61100DF00-044-G | RES,6.34KOhm,+/-0.1%,1/16W,G,SMD0402 | TA-I TECHNOLOGY CO., LTD | RB04BTP6341 | G | PWA BOM | In New BOM |
|  |  |  | 61100DF00-024-G | RES,6.34KOhm,+/-0.1%,1/16W,G,SMD0402 | PANASONIC INDUSTRIAL CO.,LTD. | ERA2AEB6341X | G | PWA BOM | In New BOM |
|  |  |  | 61100DF00-029-G | RES,6.34KOhm,+/-0.1%,1/16W,G,SMD0402 | VISHAY ENTER TECHNO LOGY.INC | TNPW04026K34BEED | G | PWA BOM | In New BOM |
|  | PSLR19 | 1 | 61100DF00-017-G | RES,6.34KOhm,+/-0.1%,1/16W,G,SMD0402 | KOA SPEER ELECTRONICS, INC. | RN731ETTP6341B25 |  | PWA BOM | In Old BOM |
|  |  |  | 61100DF00-011-G | RES,6.34KOhm,+/-0.1%,1/16W,G,SMD0402 | YAGEO | RT0402BRD076K34L | G | PWA BOM | In Old BOM |
|  |  |  | 61100DF00-012-G | RES,6.34KOhm,+/-0.1%,1/16W,G,SMD0402 | WALSIN | WF04U6341BTL | G | PWA BOM | In Old BOM |
|  |  |  | 61100DF00-044-G | RES,6.34KOhm,+/-0.1%,1/16W,G,SMD0402 | TA-I | RB04BTP6341 | G | PWA BOM | In Old BOM |
|  |  |  | 61100DF00-024-G | RES,6.34KOhm,+/-0.1%,1/16W,G,SMD0402 | PANASONIC INDUSTRIAL CO.,LTD. | ERA2AEB6341X | G | PWA BOM | In Old BOM |
|  |  |  | 61100DF00-029-G | RES,6.34KOhm,+/-0.1%,1/16W,G,SMD0402 | VISHAY ENTER TECHNO LOGY.INC | TNPW04026K34BEED | G | PWA BOM | In Old BOM |
| 148 | PSRL1 | 1 | 63033PG00-15A-G | IND,22nH@100KHz,+/-15%,22A,249.55uOhm,SHLD,G,SMD | The Inter-Technical Group, Inc. | SLC1615A-R022LHF | G | PWA BOM | In New BOM |
|  |  |  | 63035Y500-129-G | IND,22nH@100KHz,+/-15%,22A,249.55uOhm,SHLD,G,SMD | MAG.LAYERS, SCIENTIFIC-TECHNICS (KUNSHAN) CO., LTD. | MSI-400404-22NL-I | G | PWA BOM | In New BOM |
|  |  |  | 630352U00-034-G | IND,22nH@100KHz,+/-15%,22A,249.55uOhm,SHLD,G,SMD | CYNTEC CO. LTD | HCB0439-220 | G | PWA BOM | In New BOM |
|  | PSRL1 | 1 | 63033PG00-15A-G | IND,22nH@100KHz,+/-15%,22A,249.55uOhm,SHLD,G,SMD | The Inter-Technical Group, Inc. | SLC1615A-R022LHF |  | PWA BOM | In Old BOM |
|  |  |  | MSI-400404-22NL-I | IND,MSI-400404-22NL-I | MAG.LAYERS, SCIENTIFIC-TECHNICS (KUNSHAN) CO., LTD. | MSI-400404-22NL-I | G | PWA BOM | In Old BOM |
|  |  |  | 630352U00-034-G | IND,22nH@100KHz,+/-15%,22A,249.55uOhm,SHLD,G,SMD | CYNTEC | HCB0439-220 | G | PWA BOM | In Old BOM |
| 149 | PSRL2 | 1 | 63034GW00-088-G | IND,680nH@100KHz,+/-20%,34A,1.33mOhm,SHLD,G,SMD | COOPER BUSSMANN, INC. | HCM1305-R68-R | G | PWA BOM | In New BOM |
|  |  |  | CMLB135T-R68MS | IND,680nH@100KHz,+/-20%,34A,1.33mOhm,SHLD,G,SMD | CYNTEC CO. LTD | CMLB135T-R68MS | G | PWA BOM | In New BOM |
|  | PSRL2 | 1 | 63034GW00-088-G | IND,680nH@100KHz,+/-20%,34A,1.33mOhm,SHLD,G,SMD | COOPER BUSSMANN, INC. | HCM1305-R68-R |  | PWA BOM | In Old BOM |
|  |  |  | CMLB135T-R68MS | IND,680nH@100KHz,+/-20%,34A,1.33mOhm,SHLD,G,SMD | CYNTEC | CMLB135T-R68MS |  | PWA BOM | In Old BOM |
| 150 | PSRR11 | 1 | 61011MN00-017-G | RES,976 Ohm,+/-1%,1/16W,G,SMD0402 | KOA SPEER ELECTRONICS, INC. | RK73H1ETTP9760F | G | PWA BOM | In New BOM |
|  |  |  | 61011MN00-012-G | RES,976 Ohm,+/-1%,1/16W,G,SMD0402 | WALSIN TECHNOLOGY CORPORATION | WR04X9760FTL | G | PWA BOM | In New BOM |
|  |  |  | 61011MN00-011-G | RES,976 Ohm,+/-1%,1/16W,G,SMD0402 | YAGEO CORPORATION COMPONENT | RC0402FR-07976RL | G | PWA BOM | In New BOM |
|  | PSRR11 | 1 | 61011MN00-017-G | RES,976 Ohm,+/-1%,1/16W,G,SMD0402 | KOA SPEER ELECTRONICS, INC. | RK73H1ETTP9760F | N | PWA BOM | In Old BOM |
|  |  |  | 61011MN00-012-G | RES,976 Ohm,+/-1%,1/16W,G,SMD0402 | WALSIN | WR04X9760FTL | G | PWA BOM | In Old BOM |
|  |  |  | 61011MN00-011-G | RES,976 Ohm,+/-1%,1/16W,G,SMD0402 | YAGEO | RC0402FR-07976RL | G | PWA BOM | In Old BOM |
| 151 | PSRR13 | 1 | 610114A00-017-G | RES,24.9KOhm,+/-1%,1/16W,G,SMD0402 | KOA SPEER ELECTRONICS, INC. | RK73H1ETTP2492F | G | PWA BOM | In New BOM |
|  |  |  | 610114A00-012-G | RES,24.9KOhm,+/-1%,1/16W,G,SMD0402 | WALSIN TECHNOLOGY CORPORATION | WR04X2492FTL | G | PWA BOM | In New BOM |
|  |  |  | 610114A00-011-G | RES,24.9KOhm,+/-1%,1/16W,G,SMD0402 | YAGEO CORPORATION COMPONENT | RC0402FR-0724K9L | G | PWA BOM | In New BOM |
|  |  |  | 610114A00-024-G | RES,24.9KOhm,+/-1%,1/16W,G,SMD0402 | PANASONIC | ERJ2RKF2492X | G | PWA BOM | In New BOM |
|  |  |  | 610114A00-029-G | RES,24.9KOhm,+/-1%,1/16W,G,SMD0402 | VISHAY ENTER TECHNO LOGY.INC | CRCW040224K9FKED | G | PWA BOM | In New BOM |
|  | PSRR13 | 1 | 610114A00-017-G | RES,24.9KOhm,+/-1%,1/16W,G,SMD0402 | KOA SPEER ELECTRONICS, INC. | RK73H1ETTP2492F | N | PWA BOM | In Old BOM |
|  |  |  | 610114A00-012-G | RES,24.9KOhm,+/-1%,1/16W,G,SMD0402 | WALSIN | WR04X2492FTL | G | PWA BOM | In Old BOM |
|  |  |  | 610114A00-011-G | RES,24.9KOhm,+/-1%,1/16W,G,SMD0402 | YAGEO | RC0402FR-0724K9L | G | PWA BOM | In Old BOM |
|  |  |  | 610114A00-024-G | RES,24.9KOhm,+/-1%,1/16W,G,SMD0402 | PANASONIC | ERJ2RKF2492X | G | PWA BOM | In Old BOM |
|  |  |  | 610114A00-029-G | RES,24.9KOhm,+/-1%,1/16W,G,SMD0402 | VISHAY ENTER TECHNO LOGY.INC | CRCW040224K9FKED | G | PWA BOM | In Old BOM |
| 152 | PSRR17 | 1 | 61100PM00-017-G | RES,453 Ohm,+/-0.1%,1/16W,G,SMD0402 | KOA SPEER ELECTRONICS, INC. | RN731ETTP4530B25 | G | PWA BOM | In New BOM |
|  |  |  | 61100PM00-012-G | RES,453 Ohm,+/-0.1%,1/16W,G,SMD0402 | WALSIN TECHNOLOGY CORPORATION | WF04U4530BTL | G | PWA BOM | In New BOM |
|  |  |  | 61100PM00-011-G | RES,453 Ohm,+/-0.1%,1/16W,G,SMD0402 | YAGEO CORPORATION COMPONENT | RT0402BRD07453RL | G | PWA BOM | In New BOM |
|  |  |  | 61100PM00-044-G | RES,453 Ohm,+/-0.1%,1/16W,G,SMD0402 | TA-I TECHNOLOGY CO., LTD | RB04BTP4530 | G | PWA BOM | In New BOM |
|  | PSRR17 | 1 | 61100PM00-017-G | RES,453 Ohm,+/-0.1%,1/16W,G,SMD0402 | KOA SPEER ELECTRONICS, INC. | RN731ETTP4530B25 |  | PWA BOM | In Old BOM |
|  |  |  | 61100PM00-012-G | RES,453 Ohm,+/-0.1%,1/16W,G,SMD0402 | WALSIN | WF04U4530BTL | G | PWA BOM | In Old BOM |
|  |  |  | 61100PM00-011-G | RES,453 Ohm,+/-0.1%,1/16W,G,SMD0402 | YAGEO | RT0402BRD07453RL | G | PWA BOM | In Old BOM |
|  |  |  | 61100PM00-044-G | RES,453 Ohm,+/-0.1%,1/16W,G,SMD0402 | TA-I | RB04BTP4530 | G | PWA BOM | In Old BOM |
| 153 | PSRR3006 | 1 | 61011C300-017-G | RES,2.2 Ohm,+/-1%,1/16W,G,SMD0402 | KOA SPEER ELECTRONICS, INC. | RK73H1ETTP2R20F | G | PWA BOM | In New BOM |
|  |  |  | 61011C300-012-G | RES,2.2 Ohm,+/-1%,1/16W,G,SMD0402 | WALSIN TECHNOLOGY CORPORATION | WR04W2R20FTL | G | PWA BOM | In New BOM |
|  |  |  | 61011C300-011-G | RES,2.2 Ohm,+/-1%,1/16W,G,SMD0402 | YAGEO CORPORATION COMPONENT | RC0402FR-072R2L | G | PWA BOM | In New BOM |
|  |  |  | 61011C300-044-G | RES,2.2 Ohm,+/-1%,1/16W,G,SMD0402 | TA-I TECHNOLOGY CO., LTD | RM04FTN2R20 | G | PWA BOM | In New BOM |
|  | PSRR3006 | 1 | 61011C300-017-G | RES,2.2 Ohm,+/-1%,1/16W,G,SMD0402 | KOA SPEER ELECTRONICS, INC. | RK73H1ETTP2R20F | N | PWA BOM | In Old BOM |
|  |  |  | 61011C300-012-G | RES,2.2 Ohm,+/-1%,1/16W,G,SMD0402 | WALSIN | WR04W2R20FTL | G | PWA BOM | In Old BOM |
|  |  |  | 61011C300-011-G | RES,2.2 Ohm,+/-1%,1/16W,G,SMD0402 | YAGEO | RC0402FR-072R2L | G | PWA BOM | In Old BOM |
|  |  |  | 61011C300-044-G | RES,2.2 Ohm,+/-1%,1/16W,G,SMD0402 | TA-I | RM04FTN2R20 | G | PWA BOM | In Old BOM |
| 154 | PSTR17 | 1 | 61100QA00-017-G | RES,16KOhm,+/-0.1%,1/16W,G,SMD0402 | KOA SPEER ELECTRONICS, INC. | RN731ETTP1602B25 | G | PWA BOM | In New BOM |
|  |  |  | ERA2AEB163X | RES,16KOhm,+/-0.1%,1/16W,G,SMD0402 | PANASONIC INDUSTRIAL CO.,LTD. | ERA2AEB163X | G | PWA BOM | In New BOM |
|  |  |  | 61100QA00-029-G | RES,16KOhm,+/-0.1%,1/16W,G,SMD0402 | VISHAY ENTER TECHNO LOGY.INC | TNPW040216K0BEED | G | PWA BOM | In New BOM |
|  | PSTR17 | 1 | 61100QA00-017-G | RES,16KOhm,+/-0.1%,1/16W,G,SMD0402 | KOA SPEER ELECTRONICS, INC. | RN731ETTP1602B25 | Y | PWA BOM | In Old BOM |
|  |  |  | 61100QA00-024-G | RES,16KOhm,+/-0.1%,1/16W,G,SMD0402 | PANASONIC INDUSTRIAL CO.,LTD. | ERA2AEB1602X | G | PWA BOM | In Old BOM |
|  |  |  | 61100QA00-029-G | RES,16KOhm,+/-0.1%,1/16W,G,SMD0402 | VISHAY ENTER TECHNO LOGY.INC | TNPW040216K0BEED | G | PWA BOM | In Old BOM |
| 155 | PSUU1 | 1 | 880302300-065-G | Converter,input 40V~60V,600W,G,Q54SJ12050NNDH,OVAL | DELTA ELECTRONICS INDUSTRIAL CO.,LTD | Q54SJ12050NNDH | G | PWA BOM | In New BOM |
|  |  |  | 880302100-065-G | Converter,input 40V~60V,600W,G,Q54SH12050NNDH | DELTA ELECTRONICS INDUSTRIAL CO.,LTD | Q54SH12050NNDH | G | PWA BOM | In New BOM |
|  | PSUU1 | 1 | 880302300-065-G | Converter,input 40V~60V,600W,G,Q54SJ12050NNDH,OVAL | DELTA ELECTRONICS INDUSTRIAL CO.,LTD | Q54SH12050NNDH |  | PWA BOM | In Old BOM |
|  |  |  | 880302100-065-G | Converter,input 40V~60V,600W,G,Q54SH12050NNDH | DELTA ELECTRONICS INDUSTRIAL CO.,LTD | Q54SH12050NNDH |  | PWA BOM | In Old BOM |
| 156 | QN1 | 1 | 510507500-185-G | MOS N/P,FDC6327C,20V,2.7/1.9A,80m/170m@4.5V,G,SuperSOT-6,SMD | FAIRCHILD SEMICONDUCTOR CORP | FDC6327C | G | PWA BOM | In New BOM |
|  |  |  | 51050BG00-223-G | MOS N/P,NTGD4167CT1G,30V,2.9/2.2A,90m/170m@4.5V,G,TSOP-6,SMD | ON SEMICONDUCTOR CORP | NTGD4167CT1G | G | PWA BOM | In New BOM |
|  |  |  | DMC2038LVT | MOS N/P,NTGD4167CT1G,30V,2.9/2.2A,90m/170m@4.5V,G,TSOP-6,SMD | DIODES INCORPORATION | DMC2038LVT | G | PWA BOM | In New BOM |
|  | QN1 | 1 | 510507500-185-G | MOS N/P,FDC6327C,20V,2.7/1.9A,80m/170m@4.5V,G,SuperSOT-6,SMD | FAIRCHILD SEMICONDUCTOR CORP | FDC6327C |  | PWA BOM | In Old BOM |
| 157 | QN2,QN3 | 2 | 510503B00-223-G | MOS N/N,NTZD3154NT1G,20V,0.54A,550m24.5V,G,SOT563-6,SMD | ON SEMICONDUCTOR CORP | NTZD3154NT1G | G | PWA BOM | In New BOM |
|  |  |  | Si1034CX-T1-GE3 | MOS N/N,Si1034CX-T1-GE3 | VISHAY ENTER TECHNO LOGY.INC | Si1034CX-T1-GE3 | G | PWA BOM | In New BOM |
|  |  |  | SSM6N36FE | MOS N/N,SSM6N36FE | TOSHIBA ELECTRONICS ASIA LTD | SSM6N36FE | G | PWA BOM | In New BOM |
|  | QN2,QN3 | 2 | 510503B00-223-G | MOS N/N,NTZD3154NT1G,20V,0.54A,550m24.5V,G,SOT563-6,SMD | ON SEMICONDUCTOR CORP | NTZD3154NT1G | N | PWA BOM | In Old BOM |
|  |  |  | Si1034CX-T1-GE3 | MOS N/N,Si1034CX-T1-GE3 | Vishay | Si1034CX-T1-GE3 | G | PWA BOM | In Old BOM |
|  |  |  | SSM6N36FE | MOS N/N,SSM6N36FE | Toshiba | SSM6N36FE | G | PWA BOM | In Old BOM |
| 158 | Q2,Q3,Q4,Q6,Q15,PSUQ1 | 6 | 510301N00-223-G | MOS N,2N7002LT1G,60V,0.115A,7.5ohm@5V,G,SOT23-3,SMD | ON SEMICONDUCTOR CORP | 2N7002LT1G | G | PWA BOM | In New BOM |
|  |  |  | 51030CQ00-185-G | MOS N,2N7002,60V,115mA,7.5ohm@5V,G,SOT23-3,SMD | FAIRCHILD SEMICONDUCTOR CORP | 2N7002 |  | PWA BOM | In New BOM |
|  | Q2,Q3,Q4,Q6 | 4 | 510301N00-223-G | MOS N,2N7002LT1G,60V,0.115A,7.5ohm@5V,G,SOT23-3,SMD | ON SEMICONDUCTOR CORP | 2N7002LT1G | N | PWA BOM | In Old BOM |
| 159 | Q5,Q7 | 2 | 510406000-185-G | MOS P,FDD6685,30V,11A,30m@4.5V,G,TO252-3,SMD | FAIRCHILD SEMICONDUCTOR CORP | FDD6685 | G | PWA BOM | In New BOM |
|  |  |  | IPD042P03L3 | MOS P,30V,11A,30m@4.5V,G,TO252-3,SMD | INFINEON TECHNOLOGIES CORP. | IPD042P03L3 |  | PWA BOM | In New BOM |
|  |  |  | 51040WQ00-131-G | MOSFET-P,TJ40S04M3L,-40V,-40A,9.1mOhm@Vgs=-10V,13mOhm@Vgs=-6V,SMD,3P,G | TOSHIBA ELECTRONICS ASIA LTD | TJ40S04M3L | G | PWA BOM | In New BOM |
|  | Q5,Q7 | 2 | 510406000-185-G | MOS P,FDD6685,30V,11A,30m@4.5V,G,TO252-3,SMD | FAIRCHILD SEMICONDUCTOR CORP | FDD6685 | N | PWA BOM | In Old BOM |
|  |  |  | 51040WQ00-131-G | MOSFET-P,TJ40S04M3L,-40V,-40A,9.1mOhm@Vgs=-10V,13mOhm@Vgs=-6V,SMD,3P,G | TOSHIBA ELECTRONICS ASIA LTD | TJ40S04M3L | G | PWA BOM | In Old BOM |
| 160 | Q12 | 1 | 510501900-237-G | MOS N/N,2N7002DW-7-F,60V,0.115A,7.5ohm@5V,G,SOT363-6,SMD | DIODES INEORPORATION | 2N7002DW-7-F | G | PWA BOM | In New BOM |
|  |  |  | 51050HV00-031-G | FET Dual channel,NX7002BKS,60V,240mA,2.8Ohm@Vgs=10V,3.2Ohm@Vgs=5V,SOT-363,6P,G | NXP SEMICONDUCTORS | NX7002BKS | G | PWA BOM | In New BOM |
|  |  |  | 510507800-131-G | MOS N/N,SSM6N7002BFU,60V,200mA,3.3Ohm@4.5V,G,SC88-6,SMD | TOSHIBA ELECTRONICS ASIA LTD | SSM6N7002BFU | G | PWA BOM | In New BOM |
|  | Q12 | 1 | 510501900-237-G | MOS N/N,2N7002DW-7-F,60V,0.115A,7.5ohm@5V,G,SOT363-6,SMD | DIODES INEORPORATION | 2N7002DW-7-F | N | PWA BOM | In Old BOM |
|  |  |  | 51050HS00-237-G | MOS N/N,60V,0.115A,7.5ohm@5V,G,SOT363-6,SMD | DIODES | DMN65D8LDW-7 |  | PWA BOM | In Old BOM |
|  |  |  | SSM6N7002KFU | MOS N/N,SSM6N7002KFU,60V,200mA,3.3Ohm@4.5V,G,SC88-6,SMD | TOSHIBA ELECTRONICS ASIA LTD | SSM6N7002KFU |  | PWA BOM | In Old BOM |
|  |  |  | 510507800-131-G | MOS N/N,SSM6N7002BFU,60V,200mA,3.3Ohm@4.5V,G,SC88-6,SMD | TOSHIBA ELECTRONICS ASIA LTD | SSM6N7002BFU | G | PWA BOM | In Old BOM |
| 161 | R3,R8,R365,R370 | 4 | 61100QE00-017-G | RES,240 Ohm,+/-0.1%,1/16W,G,SMD0402 | KOA SPEER ELECTRONICS, INC. | RN731ETTP2400B25 | G | PWA BOM | In New BOM |
|  |  |  | 61100QE00-012-G | RES,240 Ohm,+/-0.1%,1/16W,G,SMD0402 | WALSIN TECHNOLOGY CORPORATION | WF04U2400BTL | G | PWA BOM | In New BOM |
|  |  |  | 61100QE00-011-G | RES,240 Ohm,+/-0.1%,1/16W,G,SMD0402 | YAGEO CORPORATION COMPONENT | RT0402BRD07240RL | G | PWA BOM | In New BOM |
|  |  |  | 61100QE00-044-G | RES,240 Ohm,+/-0.1%,1/16W,G,SMD0402 | TA-I TECHNOLOGY CO., LTD | RB04BTP2400 | G | PWA BOM | In New BOM |
|  | R3,R8,R365,R370 | 4 | 61100QE00-017-G | RES,240 Ohm,+/-0.1%,1/16W,G,SMD0402 | KOA SPEER ELECTRONICS, INC. | RN731ETTP2400B25 | Y | PWA BOM | In Old BOM |
|  |  |  | 61100QE00-012-G | RES,240 Ohm,+/-0.1%,1/16W,G,SMD0402 | WALSIN | WF04U2400BTL | G | PWA BOM | In Old BOM |
|  |  |  | 61100QE00-011-G | RES,240 Ohm,+/-0.1%,1/16W,G,SMD0402 | YAGEO | RT0402BRD07240RL | G | PWA BOM | In Old BOM |
|  |  |  | 61100QE00-044-G | RES,240 Ohm,+/-0.1%,1/16W,G,SMD0402 | TA-I | RB04BTP2400 | G | PWA BOM | In Old BOM |
| 162 | R4,R5,R9,R10,R103,R129,R130,R131,R150,R151,R154,R171,R172,R175,R192,R193,R195,R213,R214,R215,R234,R235,R236,R255,R256,R259,R276,R277,R279,R318,R319,R366,R367,R371,R372,R455,R458,R484,R485,R486,R505,R506,R509,R526,R527,R530,R547,R548,R550,R568,R569,R570,R589,R590,R591,R611,R612,R615,R631,R632,R634,R704,R705,R706,R711,R715,R735,R736,R1072,R1080,R1232,R1340,R1341,R1350,R1351,R1352,R1353,R1354,R1355,R1356,R1357,R1358,R1359,R1361,R1363,R1364,R1365,R1366,R1367,R1377,R1378,R1379,R1380,R1381,R1382,R1383,R1384,R1385,R1386,R1387,R1388,R1389,R1390,R1391,R1392,R1746,R1775 | 107 | 610100T00-017-G | RES,1KOhm,+/-5%,1/16W,G,SMD0402 | KOA SPEER ELECTRONICS, INC. | RK73B1ETTP102J | G | PWA BOM | In New BOM |
|  |  |  | 610100T00-012-G | RES,1KOhm,+/-5%,1/16W,G,SMD0402 | WALSIN TECHNOLOGY CORPORATION | WR04X102JTL | G | PWA BOM | In New BOM |
|  |  |  | 610100T00-011-G | RES,1KOhm,+/-5%,1/16W,G,SMD0402 | YAGEO CORPORATION COMPONENT | RC0402JR-071KL | G | PWA BOM | In New BOM |
|  |  |  | 610100T00-044-G | RES,1KOhm,+/-5%,1/16W,G,SMD0402 | TA-I TECHNOLOGY CO., LTD | RM04JTN102 | G | PWA BOM | In New BOM |
|  |  |  | 610100T00-024-G | RES,1KOhm,+/-5%,1/16W,G,SMD0402 | PANASONIC INDUSTRIAL CO.,LTD. | ERJ2GEJ102X | G | PWA BOM | In New BOM |
|  | R4,R5,R9,R10,R103,R129,R130,R131,R150,R151,R154,R171,R172,R175,R192,R193,R195,R213,R214,R215,R234,R235,R236,R255,R256,R259,R276,R277,R279,R318,R319,R366,R367,R371,R372,R455,R458,R484,R485,R486,R505,R506,R509,R526,R527,R530,R547,R548,R550,R568,R569,R570,R589,R590,R591,R611,R612,R615,R631,R632,R634,R704,R705,R706,R711,R715,R735,R736,R1072,R1080,R1232,R1340,R1341,R1350,R1351,R1352,R1353,R1354,R1355,R1356,R1357,R1358,R1359,R1361,R1363,R1364,R1365,R1366,R1367,R1377,R1378,R1379,R1380,R1381,R1382,R1383,R1384,R1385,R1386,R1387,R1388,R1389,R1390,R1391,R1392,R1746,R1775 | 107 | 610100T00-017-G | RES,1KOhm,+/-5%,1/16W,G,SMD0402 | KOA SPEER ELECTRONICS, INC. | RK73B1ETTP102J | N | PWA BOM | In Old BOM |
|  |  |  | 610100T00-012-G | RES,1KOhm,+/-5%,1/16W,G,SMD0402 | WALSIN | WR04X102JTL | G | PWA BOM | In Old BOM |
|  |  |  | 610100T00-011-G | RES,1KOhm,+/-5%,1/16W,G,SMD0402 | YAGEO | RC0402JR-071KL | G | PWA BOM | In Old BOM |
|  |  |  | 610100T00-044-G | RES,1KOhm,+/-5%,1/16W,G,SMD0402 | TA-I | RM04JTN102 | G | PWA BOM | In Old BOM |
|  |  |  | 610100T00-024-G | RES,1KOhm,+/-5%,1/16W,G,SMD0402 | PANASONIC INDUSTRIAL CO.,LTD. | ERJ2GEJ102X | G | PWA BOM | In Old BOM |
| 163 | R16,R17,R18,R19,R20,R21,R24,R25,R33,R34,R35,R36,R37,R46,R47,R48,R49,R50,R51,R65,R66,R69,R76,R94,R95,R99,R100,R101,R104,R105,R106,R107,R110,R111,R112,R113,R114,R115,R117,R121,R122,R138,R139,R140,R146,R147,R148,R155,R160,R161,R164,R166,R169,R177,R180,R182,R186,R187,R189,R197,R198,R203,R206,R207,R208,R222,R223,R224,R230,R231,R232,R240,R244,R245,R248,R250,R253,R261,R264,R266,R270,R271,R273,R281,R282,R287,R291,R292,R293,R376,R379,R380,R381,R382,R383,R386,R387,R391,R392,R395,R396,R397,R398,R400,R405,R406,R407,R408,R409,R410,R421,R422,R423,R424,R425,R426,R427,R432,R435,R436,R445,R446,R449,R453,R456,R457,R459,R460,R461,R493,R494,R495,R501,R502,R503,R510,R515,R516,R519,R521,R524,R533,R535,R537,R541,R542,R544,R552,R553,R558,R561,R562,R563,R577,R578,R579,R585,R586,R587,R594,R599,R600,R603,R605,R608,R610,R617,R621,R625,R626,R628,R636,R637,R642,R645,R646,R647,R740,R748,R933,R935,R1346,R1348,R1349,R1368,R1371,R1374,R1396,R1397,R1401,R1402,R1408,R1409,R1410,R1411,R1419,R1420,R1421,R1429,R1430,R1431,R1591,R1822,R1827,R1828,R1829,R1830,R1831 | 208 | 610102700-017-G | RES,49.9 Ohm,+/-1%,1/16W,G,SMD0402 | KOA SPEER ELECTRONICS, INC. | RK73H1ETTP49R9F | G | PWA BOM | In New BOM |
|  |  |  | 610102700-012-G | RES,49.9 Ohm,+/-1%,1/16W,G,SMD0402 | WALSIN TECHNOLOGY CORPORATION | WR04X49R9FTL | G | PWA BOM | In New BOM |
|  |  |  | 610102700-011-G | RES,49.9 Ohm,+/-1%,1/16W,G,SMD0402 | YAGEO CORPORATION COMPONENT | RC0402FR-0749R9L | G | PWA BOM | In New BOM |
|  |  |  | 610102700-044-G | RES,49.9 Ohm,+/-1%,1/16W,G,SMD0402 | TA-I TECHNOLOGY CO., LTD | RM04FTN49R9 | G | PWA BOM | In New BOM |
|  |  |  | 610102700-029-G | RES,49.9 Ohm,+/-1%,1/16W,G,SMD0402 | VISHAY ENTER TECHNO LOGY.INC | CRCW040249R9FKED | G | PWA BOM | In New BOM |
|  |  |  | 610102700-024-G | RES,49.9 Ohm,+/-1%,1/16W,G,SMD0402 | PANASONIC INDUSTRIAL CO.,LTD. | ERJ2RKF49R9X | G | PWA BOM | In New BOM |
|  | R16,R17,R18,R19,R20,R21,R24,R25,R33,R34,R35,R36,R37,R46,R47,R48,R49,R50,R51,R65,R66,R69,R76,R94,R95,R99,R100,R101,R104,R105,R106,R107,R110,R111,R112,R113,R114,R115,R117,R121,R122,R138,R139,R140,R146,R147,R148,R155,R160,R161,R164,R166,R169,R177,R180,R182,R186,R187,R189,R197,R198,R203,R206,R207,R208,R222,R223,R224,R230,R231,R232,R240,R244,R245,R248,R250,R253,R261,R264,R266,R270,R271,R273,R281,R282,R287,R291,R292,R293,R376,R379,R380,R381,R382,R383,R386,R387,R391,R392,R395,R396,R397,R398,R400,R405,R406,R407,R408,R409,R410,R421,R422,R423,R424,R425,R426,R427,R432,R435,R436,R445,R446,R449,R453,R456,R457,R459,R460,R461,R493,R494,R495,R501,R502,R503,R510,R515,R516,R519,R521,R524,R533,R535,R537,R541,R542,R544,R552,R553,R558,R561,R562,R563,R577,R578,R579,R585,R586,R587,R594,R599,R600,R603,R605,R608,R610,R617,R621,R625,R626,R628,R636,R637,R642,R645,R646,R647,R740,R748,R933,R935,R1346,R1348,R1349,R1368,R1371,R1374,R1396,R1397,R1401,R1402,R1408,R1409,R1410,R1411,R1419,R1420,R1421,R1429,R1430,R1431,R1591,R1811,R1822,R1827,R1828,R1829,R1830,R1831 | 209 | 610102700-017-G | RES,49.9 Ohm,+/-1%,1/16W,G,SMD0402 | KOA SPEER ELECTRONICS, INC. | RK73H1ETTP49R9F | N | PWA BOM | In Old BOM |
|  |  |  | 610102700-012-G | RES,49.9 Ohm,+/-1%,1/16W,G,SMD0402 | WALSIN | WR04X49R9FTL | G | PWA BOM | In Old BOM |
|  |  |  | 610102700-011-G | RES,49.9 Ohm,+/-1%,1/16W,G,SMD0402 | YAGEO | RC0402FR-0749R9L | G | PWA BOM | In Old BOM |
|  |  |  | 610102700-044-G | RES,49.9 Ohm,+/-1%,1/16W,G,SMD0402 | TA-I | RM04FTN49R9 | G | PWA BOM | In Old BOM |
|  |  |  | 610102700-029-G | RES,49.9 Ohm,+/-1%,1/16W,G,SMD0402 | VISHAY ENTER TECHNO LOGY.INC | CRCW040249R9FKED | G | PWA BOM | In Old BOM |
|  |  |  | 610102700-024-G | RES,49.9 Ohm,+/-1%,1/16W,G,SMD0402 | PANASONIC INDUSTRIAL CO.,LTD. | ERJ2RKF49R9X | G | PWA BOM | In Old BOM |
| 164 | R22,R23,R26,R32,R38,R39,R41,R42,R43,R44,R45,R52,R68,R88,R89,R299,R300,R301,R302,R342,R384,R385,R388,R389,R390,R394,R399,R401,R403,R404,R411,R412,R413,R441,R442,R465,R466,R468,R469,R470,R472,R475,R476,R954,R1029,R1031,R1032,R1033,R1034,R1035,R1041,R1042,R1043,R1044,R1047,R1048,R1050,R1051,R1054,R1055,R1059,R1060,R1063,R1064,R1067,R1068,R1127,R1128,R1139,R1141,R1225,R1227,R1229,R1234,R1239,R1336,R1337,R1466,R1468,R1524,R1525,R1553,R1823 | 83 | 61010KJ00-017-G | RES,3.3KOhm,+/-5%,1/16W,G,SMD0402 | KOA SPEER ELECTRONICS, INC. | RK73B1ETTP332J | G | PWA BOM | In New BOM |
|  |  |  | 61010KJ00-012-G | RES,3.3KOhm,+/-5%,1/16W,G,SMD0402 | WALSIN TECHNOLOGY CORPORATION | WR04X332JTL | G | PWA BOM | In New BOM |
|  |  |  | 61010KJ00-011-G | RES,3.3KOhm,+/-5%,1/16W,G,SMD0402 | YAGEO CORPORATION COMPONENT | RC0402JR-073K3L | G | PWA BOM | In New BOM |
|  |  |  | 61010KJ00-044-G | RES,3.3KOhm,+/-5%,1/16W,G,SMD0402 | TA-I TECHNOLOGY CO., LTD | RM04JTN332 | G | PWA BOM | In New BOM |
|  |  |  | 61010KJ00-024-G | RES,3.3KOhm,+/-5%,1/16W,G,SMD0402 | PANASONIC INDUSTRIAL CO.,LTD. | ERJ2GEJ332X | G | PWA BOM | In New BOM |
|  | R22,R23,R26,R32,R38,R39,R41,R42,R43,R44,R45,R52,R68,R88,R89,R299,R300,R301,R302,R342,R384,R385,R388,R389,R390,R394,R399,R401,R403,R404,R411,R412,R413,R441,R442,R465,R466,R468,R469,R470,R472,R475,R476,R954,R1029,R1031,R1032,R1033,R1034,R1035,R1041,R1042,R1043,R1044,R1047,R1048,R1050,R1051,R1054,R1055,R1059,R1060,R1063,R1064,R1067,R1068,R1127,R1128,R1139,R1141,R1225,R1227,R1229,R1234,R1239,R1336,R1337,R1466,R1468,R1524,R1525,R1553,R1823 | 83 | 61010KJ00-017-G | RES,3.3KOhm,+/-5%,1/16W,G,SMD0402 | KOA SPEER ELECTRONICS, INC. | RK73B1ETTP332J | N | PWA BOM | In Old BOM |
|  |  |  | 61010KJ00-012-G | RES,3.3KOhm,+/-5%,1/16W,G,SMD0402 | WALSIN | WR04X332JTL | G | PWA BOM | In Old BOM |
|  |  |  | 61010KJ00-011-G | RES,3.3KOhm,+/-5%,1/16W,G,SMD0402 | YAGEO | RC0402JR-073K3L | G | PWA BOM | In Old BOM |
|  |  |  | 61010KJ00-044-G | RES,3.3KOhm,+/-5%,1/16W,G,SMD0402 | TA-I | RM04JTN332 | G | PWA BOM | In Old BOM |
|  |  |  | 61010KJ00-024-G | RES,3.3KOhm,+/-5%,1/16W,G,SMD0402 | PANASONIC INDUSTRIAL CO.,LTD. | ERJ2GEJ332X | G | PWA BOM | In Old BOM |
| 165 | R27,R28,R54,R55,R56,R57,R58,R59,R417,R418,R419,R420 | 12 | 610115E00-017-G | RES,1.2KOhm,+/-5%,1/16W,G,SMD0402 | KOA SPEER ELECTRONICS, INC. | RK73B1ETTP122J | G | PWA BOM | In New BOM |
|  |  |  | 610115E00-012-G | RES,1.2KOhm,+/-5%,1/16W,G,SMD0402 | WALSIN TECHNOLOGY CORPORATION | WR04X122JTL | G | PWA BOM | In New BOM |
|  |  |  | 610115E00-011-G | RES,1.2KOhm,+/-5%,1/16W,G,SMD0402 | YAGEO CORPORATION COMPONENT | RC0402JR-071K2L | G | PWA BOM | In New BOM |
|  |  |  | 610115E00-044-G | RES,1.2KOhm,+/-5%,1/16W,G,SMD0402 | TA-I TECHNOLOGY CO., LTD | RM04JTN122 | G | PWA BOM | In New BOM |
|  |  |  | 610115E00-024-G | RES,1.2KOhm,+/-5%,1/16W,G,SMD0402 | PANASONIC INDUSTRIAL CO.,LTD. | ERJ2GEJ122X | G | PWA BOM | In New BOM |
|  | R27,R28,R54,R55,R56,R57,R58,R59,R417,R418,R419,R420 | 12 | 610115E00-017-G | RES,1.2KOhm,+/-5%,1/16W,G,SMD0402 | KOA SPEER ELECTRONICS, INC. | RK73B1ETTP122J | N | PWA BOM | In Old BOM |
|  |  |  | 610115E00-012-G | RES,1.2KOhm,+/-5%,1/16W,G,SMD0402 | WALSIN | WR04X122JTL | G | PWA BOM | In Old BOM |
|  |  |  | 610115E00-011-G | RES,1.2KOhm,+/-5%,1/16W,G,SMD0402 | YAGEO | RC0402JR-071K2L | G | PWA BOM | In Old BOM |
|  |  |  | 610115E00-044-G | RES,1.2KOhm,+/-5%,1/16W,G,SMD0402 | TA-I | RM04JTN122 | G | PWA BOM | In Old BOM |
|  |  |  | 610115E00-024-G | RES,1.2KOhm,+/-5%,1/16W,G,SMD0402 | PANASONIC INDUSTRIAL CO.,LTD. | ERJ2GEJ122X | G | PWA BOM | In Old BOM |
| 166 | R31,R40,R53,R393,R402,R416 | 6 | 61100V600-017-G | RES,200 Ohm,+/-0.1%,1/16W,G,SMD0402 | KOA SPEER ELECTRONICS, INC. | RN731ETTP2000B25 | G | PWA BOM | In New BOM |
|  |  |  | 61100V600-012-G | RES,200 Ohm,+/-0.1%,1/16W,G,SMD0402 | WALSIN TECHNOLOGY CORPORATION | WF04U2000BTL | G | PWA BOM | In New BOM |
|  |  |  | 61100V600-011-G | RES,200 Ohm,+/-0.1%,1/16W,G,SMD0402 | YAGEO CORPORATION COMPONENT | RT0402BRD07200RL | G | PWA BOM | In New BOM |
|  | R31,R40,R53,R393,R402,R416 | 6 | 61100V600-017-G | RES,200 Ohm,+/-0.1%,1/16W,G,SMD0402 | KOA SPEER ELECTRONICS, INC. | RN731ETTP2000B25 |  | PWA BOM | In Old BOM |
|  |  |  | 61100V600-012-G | RES,200 Ohm,+/-0.1%,1/16W,G,SMD0402 | WALSIN | WF04U2000BTL | G | PWA BOM | In Old BOM |
|  |  |  | 61100V600-011-G | RES,200 Ohm,+/-0.1%,1/16W,G,SMD0402 | YAGEO | RT0402BRD07200RL | G | PWA BOM | In Old BOM |
| 167 | R78 | 1 | 610115T00-017-G | RES,40.2KOhm,+/-1%,1/16W,G,SMD0402 | KOA SPEER ELECTRONICS, INC. | RK73H1ETTP4022F | G | PWA BOM | In New BOM |
|  |  |  | 610115T00-012-G | RES,40.2KOhm,+/-1%,1/16W,G,SMD0402 | WALSIN TECHNOLOGY CORPORATION | WR04X4022FTL | G | PWA BOM | In New BOM |
|  |  |  | 610115T00-011-G | RES,40.2KOhm,+/-1%,1/16W,G,SMD0402 | YAGEO CORPORATION COMPONENT | RC0402FR-0740K2L | G | PWA BOM | In New BOM |
|  |  |  | 610115T00-044-G | RES,40.2KOhm,+/-1%,1/16W,G,SMD0402 | TA-I TECHNOLOGY CO., LTD | RM04FTN4022 | G | PWA BOM | In New BOM |
|  |  |  | 610115T00-029-G | RES,40.2KOhm,+/-1%,1/16W,G,SMD0402 | VISHAY ENTER TECHNO LOGY.INC | CRCW040240K2FKEDC | G | PWA BOM | In New BOM |
|  | R78 | 1 | 610115T00-017-G | RES,40.2KOhm,+/-1%,1/16W,G,SMD0402 | KOA SPEER ELECTRONICS, INC. | RK73H1ETTP4022F | N | PWA BOM | In Old BOM |
|  |  |  | 610115T00-012-G | RES,40.2KOhm,+/-1%,1/16W,G,SMD0402 | WALSIN | WR04X4022FTL | G | PWA BOM | In Old BOM |
|  |  |  | 610115T00-011-G | RES,40.2KOhm,+/-1%,1/16W,G,SMD0402 | YAGEO | RC0402FR-0740K2L | G | PWA BOM | In Old BOM |
|  |  |  | 610115T00-044-G | RES,40.2KOhm,+/-1%,1/16W,G,SMD0402 | TA-I | RM04FTN4022 | G | PWA BOM | In Old BOM |
|  |  |  | 610115T00-029-G | RES,40.2KOhm,+/-1%,1/16W,G,SMD0402 | VISHAY ENTER TECHNO LOGY.INC | CRCW040240K2FKEDC | G | PWA BOM | In Old BOM |
| 168 | R97,R98,R447,R452,R454 | 5 | 610112W00-017-G | RES,2KOhm,+/-5%,1/16W,G,SMD0402 | KOA SPEER ELECTRONICS, INC. | RK73B1ETTP202J | G | PWA BOM | In New BOM |
|  |  |  | 610112W00-012-G | RES,2KOhm,+/-5%,1/16W,G,SMD0402 | WALSIN TECHNOLOGY CORPORATION | WR04X202JTL | G | PWA BOM | In New BOM |
|  |  |  | 610112W00-011-G | RES,2KOhm,+/-5%,1/16W,G,SMD0402 | YAGEO CORPORATION COMPONENT | RC0402JR-072KL | G | PWA BOM | In New BOM |
|  |  |  | 610112W00-044-G | RES,2KOhm,+/-5%,1/16W,G,SMD0402 | TA-I TECHNOLOGY CO., LTD | RM04JTN202 | G | PWA BOM | In New BOM |
|  |  |  | 610112W00-024-G | RES,2KOhm,+/-5%,1/16W,G,SMD0402 | PANASONIC INDUSTRIAL CO.,LTD. | ERJ2GEJ202X | G | PWA BOM | In New BOM |
|  | R97,R98,R447,R452,R454 | 5 | 610112W00-017-G | RES,2KOhm,+/-5%,1/16W,G,SMD0402 | KOA SPEER ELECTRONICS, INC. | RK73B1ETTP202J | N | PWA BOM | In Old BOM |
|  |  |  | 610112W00-012-G | RES,2KOhm,+/-5%,1/16W,G,SMD0402 | WALSIN | WR04X202JTL | G | PWA BOM | In Old BOM |
|  |  |  | 610112W00-011-G | RES,2KOhm,+/-5%,1/16W,G,SMD0402 | YAGEO | RC0402JR-072KL | G | PWA BOM | In Old BOM |
|  |  |  | 610112W00-044-G | RES,2KOhm,+/-5%,1/16W,G,SMD0402 | TA-I | RM04JTN202 | G | PWA BOM | In Old BOM |
|  |  |  | 610112W00-024-G | RES,2KOhm,+/-5%,1/16W,G,SMD0402 | PANASONIC INDUSTRIAL CO.,LTD. | ERJ2GEJ202X | G | PWA BOM | In Old BOM |
| 169 | R108,R109,R463,R464,R700,R701 | 6 | 61010DL01-017-G | RES,0 Ohm,+/-5%,1/8W,G,SMD0805 | KOA SPEER ELECTRONICS, INC. | RK73Z2ATTD | G | PWA BOM | In New BOM |
|  |  |  | 61010DL00-012-G | RES,0 Ohm,+/-5%,1/8W,G,SMD0805 | WALSIN TECHNOLOGY CORPORATION | WR08X000PTL | G | PWA BOM | In New BOM |
|  |  |  | 61010DL00-011-G | RES,0 Ohm,+/-5%,1/8W,G,SMD0805 | YAGEO CORPORATION COMPONENT | RC0805JR-070RL | G | PWA BOM | In New BOM |
|  |  |  | 61010DL00-044-G | RES,0 Ohm,+/-5%,1/8W,G,SMD0805 | TA-I TECHNOLOGY CO., LTD | RM10JTN0 | G | PWA BOM | In New BOM |
|  |  |  | 61010DL00-024-G | RES,0 Ohm,+/-5%,1/8W,G,SMD0805 | PANASONIC INDUSTRIAL CO.,LTD. | ERJ6GEY0R00V | G | PWA BOM | In New BOM |
|  | R108,R109,R463,R464,R700,R701 | 6 | 61010DL01-017-G | RES,0 Ohm,+/-5%,1/8W,G,SMD0805 | KOA SPEER ELECTRONICS, INC. | RK73Z2ATTD | N | PWA BOM | In Old BOM |
|  |  |  | 61010DL00-012-G | RES,0 Ohm,+/-5%,1/8W,G,SMD0805 | WALSIN | WR08X000PTL | G | PWA BOM | In Old BOM |
|  |  |  | 61010DL00-011-G | RES,0 Ohm,+/-5%,1/8W,G,SMD0805 | YAGEO | RC0805JR-070RL | G | PWA BOM | In Old BOM |
|  |  |  | 61010DL00-044-G | RES,0 Ohm,+/-5%,1/8W,G,SMD0805 | TA-I | RM10JTN0 | G | PWA BOM | In Old BOM |
|  |  |  | 61010DL00-024-G | RES,0 Ohm,+/-5%,1/8W,G,SMD0805 | PANASONIC INDUSTRIAL CO.,LTD. | ERJ6GEY0R00V | G | PWA BOM | In Old BOM |
| 170 | R123,R124,R125,R126,R127,R128,R327,R829,R835,R836,R1125,R1513,R1542,R1543,R1544,R1545,R1546,R1547 | 18 | 610102C00-017-G | RES,15KOhm,+/-5%,1/16W,G,SMD0402 | KOA SPEER ELECTRONICS, INC. | RK73B1ETTP153J | G | PWA BOM | In New BOM |
|  |  |  | 610102C00-011-G | RES,15KOhm,+/-5%,1/16W,G,SMD0402 | YAGEO CORPORATION COMPONENT | RC0402JR-0715KL | G | PWA BOM | In New BOM |
|  |  |  | 610102C00-012-G | RES,15KOhm,+/-5%,1/16W,G,SMD0402 | WALSIN TECHNOLOGY CORPORATION | WR04X153JTL | G | PWA BOM | In New BOM |
|  |  |  | 610102C00-024-G | RES,15KOhm,+/-5%,1/16W,G,SMD0402 | PANASONIC | ERJ2GEJ153X | G | PWA BOM | In New BOM |
|  |  |  | 610102C00-029-G | RES,15KOhm,+/-5%,1/16W,G,SMD0402 | VISHAY ENTER TECHNO LOGY.INC | CRCW040215K0JNED | G | PWA BOM | In New BOM |
|  |  |  | 610102C00-044-G | RES,15KOhm,+/-5%,1/16W,G,SMD0402 | TA-I TECHNOLOGY CO., LTD | RM04JTN153 | G | PWA BOM | In New BOM |
|  | R123,R124,R125,R126,R127,R128,R327,R829,R835,R836,R1125,R1513,R1542,R1543,R1544,R1545,R1546,R1547 | 18 | 610102C00-017-G | RES,15KOhm,+/-5%,1/16W,G,SMD0402 | KOA SPEER ELECTRONICS, INC. | RK73B1ETTP153J | N | PWA BOM | In Old BOM |
|  |  |  | 610102C00-011-G | RES,15KOhm,+/-5%,1/16W,G,SMD0402 | YAGEO | RC0402JR-0715KL | G | PWA BOM | In Old BOM |
|  |  |  | 610102C00-012-G | RES,15KOhm,+/-5%,1/16W,G,SMD0402 | WALSIN | WR04X153JTL | G | PWA BOM | In Old BOM |
|  |  |  | 610102C00-024-G | RES,15KOhm,+/-5%,1/16W,G,SMD0402 | PANASONIC | ERJ2GEJ153X | G | PWA BOM | In Old BOM |
|  |  |  | 610102C00-029-G | RES,15KOhm,+/-5%,1/16W,G,SMD0402 | VISHAY ENTER TECHNO LOGY.INC | CRCW040215K0JNED | G | PWA BOM | In Old BOM |
|  |  |  | 610102C00-044-G | RES,15KOhm,+/-5%,1/16W,G,SMD0402 | TA-I | RM04JTN153 | G | PWA BOM | In Old BOM |
| 171 | R132,R137,R141,R143,R152,R158,R162,R167,R173,R179,R183,R188,R194,R200,R204,R209,R216,R221,R225,R227,R237,R239,R246,R251,R257,R263,R267,R272,R278,R284,R288,R290,R487,R492,R496,R498,R507,R513,R517,R522,R528,R531,R538,R543,R549,R555,R559,R564,R571,R576,R580,R582,R592,R597,R601,R606,R613,R620,R622,R627,R633,R639,R643,R648,R934 | 65 | 610102E00-017-G | RES,100 Ohm,+/-5%,1/16W,G,SMD0402 | KOA SPEER ELECTRONICS, INC. | RK73B1ETTP101J | G | PWA BOM | In New BOM |
|  |  |  | 610102E00-012-G | RES,100 Ohm,+/-5%,1/16W,G,SMD0402 | WALSIN TECHNOLOGY CORPORATION | WR04X101JTL | G | PWA BOM | In New BOM |
|  |  |  | 610102E00-011-G | RES,100 Ohm,+/-5%,1/16W,G,SMD0402 | YAGEO CORPORATION COMPONENT | RC0402JR-07100RL | G | PWA BOM | In New BOM |
|  |  |  | 610102E00-044-G | RES,100 Ohm,+/-5%,1/16W,G,SMD0402 | TA-I TECHNOLOGY CO., LTD | RM04JTN101 | G | PWA BOM | In New BOM |
|  |  |  | 610102E00-029-G | RES,100 Ohm,+/-5%,1/16W,G,SMD0402 | VISHAY ENTER TECHNO LOGY.INC | CRCW0402100RJNED | G | PWA BOM | In New BOM |
|  | R132,R137,R141,R143,R152,R158,R162,R167,R173,R179,R183,R188,R194,R200,R204,R209,R216,R221,R225,R227,R237,R239,R246,R251,R257,R263,R267,R272,R278,R284,R288,R290,R487,R492,R496,R498,R507,R513,R517,R522,R528,R531,R538,R543,R549,R555,R559,R564,R571,R576,R580,R582,R592,R597,R601,R606,R613,R620,R622,R627,R633,R639,R643,R648,R934 | 65 | 610102E00-017-G | RES,100 Ohm,+/-5%,1/16W,G,SMD0402 | KOA SPEER ELECTRONICS, INC. | RK73B1ETTP101J | N | PWA BOM | In Old BOM |
|  |  |  | 610102E00-012-G | RES,100 Ohm,+/-5%,1/16W,G,SMD0402 | WALSIN | WR04X101JTL | G | PWA BOM | In Old BOM |
|  |  |  | 610102E00-011-G | RES,100 Ohm,+/-5%,1/16W,G,SMD0402 | YAGEO | RC0402JR-07100RL | G | PWA BOM | In Old BOM |
|  |  |  | 610102E00-044-G | RES,100 Ohm,+/-5%,1/16W,G,SMD0402 | TA-I | RM04JTN101 | G | PWA BOM | In Old BOM |
|  |  |  | 610102E00-029-G | RES,100 Ohm,+/-5%,1/16W,G,SMD0402 | VISHAY ENTER TECHNO LOGY.INC | CRCW0402100RJNED | G | PWA BOM | In Old BOM |
| 172 | R297,R298,R304,R1069,R1070,R1342,R1343 | 7 | 610107B00-017-G | RES,4.7KOhm,+/-5%,1/16W,G,SMD0402 | KOA SPEER ELECTRONICS, INC. | RK73B1ETTP472J | G | PWA BOM | In New BOM |
|  |  |  | 610107B00-012-G | RES,4.7KOhm,+/-5%,1/16W,G,SMD0402 | WALSIN TECHNOLOGY CORPORATION | WR04X472JTL | G | PWA BOM | In New BOM |
|  |  |  | 610107B00-011-G | RES,4.7KOhm,+/-5%,1/16W,G,SMD0402 | YAGEO CORPORATION COMPONENT | RC0402JR-074K7L | G | PWA BOM | In New BOM |
|  |  |  | 610107B00-044-G | RES,4.7KOhm,+/-5%,1/16W,G,SMD0402 | TA-I TECHNOLOGY CO., LTD | RM04JTN472 | G | PWA BOM | In New BOM |
|  |  |  | 610107B00-024-G | RES,4.7KOhm,+/-5%,1/16W,G,SMD0402 | PANASONIC INDUSTRIAL CO.,LTD. | ERJ2GEJ472X | G | PWA BOM | In New BOM |
|  |  |  | 610107B00-029-G | RES,4.7KOhm,+/-5%,1/16W,G,SMD0402 | VISHAY ENTER TECHNO LOGY.INC | CRCW04024K70JNED | G | PWA BOM | In New BOM |
|  | R297,R298,R304,R1069,R1070,R1342,R1343 | 7 | 610107B00-017-G | RES,4.7KOhm,+/-5%,1/16W,G,SMD0402 | KOA SPEER ELECTRONICS, INC. | RK73B1ETTP472J | N | PWA BOM | In Old BOM |
|  |  |  | 610107B00-012-G | RES,4.7KOhm,+/-5%,1/16W,G,SMD0402 | WALSIN | WR04X472JTL | G | PWA BOM | In Old BOM |
|  |  |  | 610107B00-011-G | RES,4.7KOhm,+/-5%,1/16W,G,SMD0402 | YAGEO | RC0402JR-074K7L | G | PWA BOM | In Old BOM |
|  |  |  | 610107B00-044-G | RES,4.7KOhm,+/-5%,1/16W,G,SMD0402 | TA-I | RM04JTN472 | G | PWA BOM | In Old BOM |
|  |  |  | 610107B00-024-G | RES,4.7KOhm,+/-5%,1/16W,G,SMD0402 | PANASONIC INDUSTRIAL CO.,LTD. | ERJ2GEJ472X | G | PWA BOM | In Old BOM |
|  |  |  | 610107B00-029-G | RES,4.7KOhm,+/-5%,1/16W,G,SMD0402 | VISHAY ENTER TECHNO LOGY.INC | CRCW04024K70JNED | G | PWA BOM | In Old BOM |
| 173 | R307 | 1 | 610112U00-017-G | RES,499 Ohm,+/-1%,1/16W,G,SMD0402 | KOA SPEER ELECTRONICS, INC. | RK73H1ETTP4990F | G | PWA BOM | In New BOM |
|  |  |  | 610112U00-012-G | RES,499 Ohm,+/-1%,1/16W,G,SMD0402 | WALSIN TECHNOLOGY CORPORATION | WR04X4990FTL | G | PWA BOM | In New BOM |
|  |  |  | 610112U00-011-G | RES,499 Ohm,+/-1%,1/16W,G,SMD0402 | YAGEO CORPORATION COMPONENT | RC0402FR-07499RL | G | PWA BOM | In New BOM |
|  |  |  | 610112U00-044-G | RES,499 Ohm,+/-1%,1/16W,G,SMD0402 | TA-I TECHNOLOGY CO., LTD | RM04FTN4990 | G | PWA BOM | In New BOM |
|  |  |  | 610112U00-024-G | RES,499 Ohm,+/-1%,1/16W,G,SMD0402 | PANASONIC INDUSTRIAL CO.,LTD. | ERJ2RKF4990X | G | PWA BOM | In New BOM |
|  | R307 | 1 | 610112U00-017-G | RES,499 Ohm,+/-1%,1/16W,G,SMD0402 | KOA SPEER ELECTRONICS, INC. | RK73H1ETTP4990F | N | PWA BOM | In Old BOM |
|  |  |  | 610112U00-012-G | RES,499 Ohm,+/-1%,1/16W,G,SMD0402 | WALSIN | WR04X4990FTL | G | PWA BOM | In Old BOM |
|  |  |  | 610112U00-011-G | RES,499 Ohm,+/-1%,1/16W,G,SMD0402 | YAGEO | RC0402FR-07499RL | G | PWA BOM | In Old BOM |
|  |  |  | 610112U00-044-G | RES,499 Ohm,+/-1%,1/16W,G,SMD0402 | TA-I | RM04FTN4990 | G | PWA BOM | In Old BOM |
|  |  |  | 610112U00-024-G | RES,499 Ohm,+/-1%,1/16W,G,SMD0402 | PANASONIC INDUSTRIAL CO.,LTD. | ERJ2RKF4990X | G | PWA BOM | In Old BOM |
| 174 | R310,R990 | 2 | 610107C00-017-G | RES,10KOhm,+/-5%,1/16W,G,SMD0402 | KOA SPEER ELECTRONICS, INC. | RK73B1ETTP103J | G | PWA BOM | In New BOM |
|  |  |  | 610107C00-012-G | RES,10KOhm,+/-5%,1/16W,G,SMD0402 | WALSIN TECHNOLOGY CORPORATION | WR04X103JTL | G | PWA BOM | In New BOM |
|  |  |  | 610107C00-011-G | RES,10KOhm,+/-5%,1/16W,G,SMD0402 | YAGEO CORPORATION COMPONENT | RC0402JR-0710KL | G | PWA BOM | In New BOM |
|  |  |  | 610107C00-044-G | RES,10KOhm,+/-5%,1/16W,G,SMD0402 | TA-I TECHNOLOGY CO., LTD | RM04JTN103 | G | PWA BOM | In New BOM |
|  |  |  | 610107C00-024-G | RES,10KOhm,+/-5%,1/16W,G,SMD0402 | PANASONIC INDUSTRIAL CO.,LTD. | ERJ2GEJ103X | G | PWA BOM | In New BOM |
|  |  |  | 610107C00-029-G | RES,10KOhm,+/-5%,1/16W,G,SMD0402 | VISHAY ENTER TECHNO LOGY.INC | CRCW040210K0JNED | G | PWA BOM | In New BOM |
|  | R310,R990 | 2 | 610107C00-017-G | RES,10KOhm,+/-5%,1/16W,G,SMD0402 | KOA SPEER ELECTRONICS, INC. | RK73B1ETTP103J | N | PWA BOM | In Old BOM |
|  |  |  | 610107C00-012-G | RES,10KOhm,+/-5%,1/16W,G,SMD0402 | WALSIN | WR04X103JTL | G | PWA BOM | In Old BOM |
|  |  |  | 610107C00-011-G | RES,10KOhm,+/-5%,1/16W,G,SMD0402 | YAGEO | RC0402JR-0710KL | G | PWA BOM | In Old BOM |
|  |  |  | 610107C00-044-G | RES,10KOhm,+/-5%,1/16W,G,SMD0402 | TA-I | RM04JTN103 | G | PWA BOM | In Old BOM |
|  |  |  | 610107C00-024-G | RES,10KOhm,+/-5%,1/16W,G,SMD0402 | PANASONIC INDUSTRIAL CO.,LTD. | ERJ2GEJ103X | G | PWA BOM | In Old BOM |
|  |  |  | 610107C00-029-G | RES,10KOhm,+/-5%,1/16W,G,SMD0402 | VISHAY ENTER TECHNO LOGY.INC | CRCW040210K0JNED | G | PWA BOM | In Old BOM |
| 175 | R328 | 1 | 61011MW00-017-G | RES,31.6KOhm,+/-1%,1/16W,G,SMD0402 | KOA SPEER ELECTRONICS, INC. | RK73H1ETTP3162F | G | PWA BOM | In New BOM |
|  |  |  | 61011MW00-012-G | RES,31.6KOhm,+/-1%,1/16W,G,SMD0402 | WALSIN TECHNOLOGY CORPORATION | WR04X3162FTL | G | PWA BOM | In New BOM |
|  |  |  | 61011MW00-011-G | RES,31.6KOhm,+/-1%,1/16W,G,SMD0402 | YAGEO CORPORATION COMPONENT | RC0402FR-0731K6L | G | PWA BOM | In New BOM |
|  |  |  | 61011MW00-044-G | RES,31.6KOhm,+/-1%,1/16W,G,SMD0402 | TA-I TECHNOLOGY CO., LTD | RM04FTN3162 | G | PWA BOM | In New BOM |
|  | R328 | 1 | 61011MW00-017-G | RES,31.6KOhm,+/-1%,1/16W,G,SMD0402 | KOA SPEER ELECTRONICS, INC. | RK73H1ETTP3162F | N | PWA BOM | In Old BOM |
|  |  |  | 61011MW00-012-G | RES,31.6KOhm,+/-1%,1/16W,G,SMD0402 | WALSIN | WR04X3162FTL | G | PWA BOM | In Old BOM |
|  |  |  | 61011MW00-011-G | RES,31.6KOhm,+/-1%,1/16W,G,SMD0402 | YAGEO | RC0402FR-0731K6L | G | PWA BOM | In Old BOM |
|  |  |  | 61011MW00-044-G | RES,31.6KOhm,+/-1%,1/16W,G,SMD0402 | TA-I | RM04FTN3162 | G | PWA BOM | In Old BOM |
| 176 | R329 | 1 | 610118G00-017-G | RES,90.9KOhm,+/-1%,1/16W,G,SMD0402 | KOA SPEER ELECTRONICS, INC. | RK73H1ETTP9092F | G | PWA BOM | In New BOM |
|  |  |  | 610118G00-012-G | RES,90.9KOhm,+/-1%,1/16W,G,SMD0402 | WALSIN TECHNOLOGY CORPORATION | WR04X9092FTL | G | PWA BOM | In New BOM |
|  |  |  | 610118G00-011-G | RES,90.9KOhm,+/-1%,1/16W,G,SMD0402 | YAGEO CORPORATION COMPONENT | RC0402FR-0790K9L | G | PWA BOM | In New BOM |
|  |  |  | 610118G00-044-G | RES,90.9KOhm,+/-1%,1/16W,G,SMD0402 | TA-I TECHNOLOGY CO., LTD | RM04FTN9092 | G | PWA BOM | In New BOM |
|  |  |  | 610118G00-024-G | RES,90.9KOhm,+/-1%,1/16W,G,SMD0402 | PANASONIC INDUSTRIAL CO.,LTD. | ERJ2RKF9092X | G | PWA BOM | In New BOM |
|  | R329 | 1 | 610118G00-017-G | RES,90.9KOhm,+/-1%,1/16W,G,SMD0402 | KOA SPEER ELECTRONICS, INC. | RK73H1ETTP9092F | N | PWA BOM | In Old BOM |
|  |  |  | 610118G00-012-G | RES,90.9KOhm,+/-1%,1/16W,G,SMD0402 | WALSIN | WR04X9092FTL | G | PWA BOM | In Old BOM |
|  |  |  | 610118G00-011-G | RES,90.9KOhm,+/-1%,1/16W,G,SMD0402 | YAGEO | RC0402FR-0790K9L | G | PWA BOM | In Old BOM |
|  |  |  | 610118G00-044-G | RES,90.9KOhm,+/-1%,1/16W,G,SMD0402 | TA-I | RM04FTN9092 | G | PWA BOM | In Old BOM |
|  |  |  | 610118G00-024-G | RES,90.9KOhm,+/-1%,1/16W,G,SMD0402 | PANASONIC INDUSTRIAL CO.,LTD. | ERJ2RKF9092X | G | PWA BOM | In Old BOM |
| 177 | R332,R333,R334,R335,R336,R337,R338,R339,R340,R341,R343,R344,R345 | 13 | 610116J00-017-G | RES,1.21KOhm,+/-1%,1/16W,G,SMD0402 | KOA SPEER ELECTRONICS, INC. | RK73H1ETTP1211F | G | PWA BOM | In New BOM |
|  |  |  | 610116J00-012-G | RES,1.21KOhm,+/-1%,1/16W,G,SMD0402 | WALSIN TECHNOLOGY CORPORATION | WR04X1211FTL | G | PWA BOM | In New BOM |
|  |  |  | 610116J00-011-G | RES,1.21KOhm,+/-1%,1/16W,G,SMD0402 | YAGEO CORPORATION COMPONENT | RC0402FR-071K21L | G | PWA BOM | In New BOM |
|  |  |  | 610116J00-044-G | RES,1.21KOhm,+/-1%,1/16W,G,SMD0402 | TA-I TECHNOLOGY CO., LTD | RM04FTN1211 | G | PWA BOM | In New BOM |
|  |  |  | 610116J00-024-G | RES,1.21KOhm,+/-1%,1/16W,G,SMD0402 | PANASONIC INDUSTRIAL CO.,LTD. | ERJ2RKF1211X | G | PWA BOM | In New BOM |
|  |  |  | 610116J00-029-G | RES,1.21KOhm,+/-1%,1/16W,G,SMD0402 | VISHAY ENTER TECHNO LOGY.INC | CRCW04021K21FKED | G | PWA BOM | In New BOM |
|  | R332,R333,R334,R335,R336,R337,R338,R339,R340,R341,R343,R344,R345 | 13 | 610116J00-017-G | RES,1.21KOhm,+/-1%,1/16W,G,SMD0402 | KOA SPEER ELECTRONICS, INC. | RK73H1ETTP1211F | N | PWA BOM | In Old BOM |
|  |  |  | 610116J00-012-G | RES,1.21KOhm,+/-1%,1/16W,G,SMD0402 | WALSIN | WR04X1211FTL | G | PWA BOM | In Old BOM |
|  |  |  | 610116J00-011-G | RES,1.21KOhm,+/-1%,1/16W,G,SMD0402 | YAGEO | RC0402FR-071K21L | G | PWA BOM | In Old BOM |
|  |  |  | 610116J00-044-G | RES,1.21KOhm,+/-1%,1/16W,G,SMD0402 | TA-I | RM04FTN1211 | G | PWA BOM | In Old BOM |
|  |  |  | 610116J00-024-G | RES,1.21KOhm,+/-1%,1/16W,G,SMD0402 | PANASONIC INDUSTRIAL CO.,LTD. | ERJ2RKF1211X | G | PWA BOM | In Old BOM |
|  |  |  | 610116J00-029-G | RES,1.21KOhm,+/-1%,1/16W,G,SMD0402 | VISHAY ENTER TECHNO LOGY.INC | CRCW04021K21FKED | G | PWA BOM | In Old BOM |
| 178 | R346 | 1 | 610114W00-017-G | RES,3.01KOhm,+/-1%,1/16W,G,SMD0402 | KOA SPEER ELECTRONICS, INC. | RK73H1ETTP3011F | G | PWA BOM | In New BOM |
|  |  |  | 610114W00-012-G | RES,3.01KOhm,+/-1%,1/16W,G,SMD0402 | WALSIN TECHNOLOGY CORPORATION | WR04X3011FTL | G | PWA BOM | In New BOM |
|  |  |  | 610114W00-011-G | RES,3.01KOhm,+/-1%,1/16W,G,SMD0402 | YAGEO CORPORATION COMPONENT | RC0402FR-073K01L | G | PWA BOM | In New BOM |
|  |  |  | 610114W00-044-G | RES,3.01KOhm,+/-1%,1/16W,G,SMD0402 | TA-I TECHNOLOGY CO., LTD | RM04FTN3011 | G | PWA BOM | In New BOM |
|  |  |  | 610114W00-029-G | RES,3.01KOhm,+/-1%,1/16W,G,SMD0402 | VISHAY ENTER TECHNO LOGY.INC | CRCW04023K01FKED | G | PWA BOM | In New BOM |
|  | R346 | 1 | 610114W00-017-G | RES,3.01KOhm,+/-1%,1/16W,G,SMD0402 | KOA SPEER ELECTRONICS, INC. | RK73H1ETTP3011F | N | PWA BOM | In Old BOM |
|  |  |  | 610114W00-012-G | RES,3.01KOhm,+/-1%,1/16W,G,SMD0402 | WALSIN | WR04X3011FTL | G | PWA BOM | In Old BOM |
|  |  |  | 610114W00-011-G | RES,3.01KOhm,+/-1%,1/16W,G,SMD0402 | YAGEO | RC0402FR-073K01L | G | PWA BOM | In Old BOM |
|  |  |  | 610114W00-044-G | RES,3.01KOhm,+/-1%,1/16W,G,SMD0402 | TA-I | RM04FTN3011 | G | PWA BOM | In Old BOM |
|  |  |  | 610114W00-029-G | RES,3.01KOhm,+/-1%,1/16W,G,SMD0402 | VISHAY ENTER TECHNO LOGY.INC | CRCW04023K01FKED | G | PWA BOM | In Old BOM |
| 179 | R349 | 1 | 61010L600-017-G | RES,11KOhm,+/-1%,1/16W,G,SMD0402 | KOA SPEER ELECTRONICS, INC. | RK73H1ETTP1102F | G | PWA BOM | In New BOM |
|  |  |  | 61010L600-012-G | RES,11KOhm,+/-1%,1/16W,G,SMD0402 | WALSIN TECHNOLOGY CORPORATION | WR04X1102FTL | G | PWA BOM | In New BOM |
|  |  |  | 61010L600-011-G | RES,11KOhm,+/-1%,1/16W,G,SMD0402 | YAGEO CORPORATION COMPONENT | RC0402FR-0711KL | G | PWA BOM | In New BOM |
|  |  |  | 61010L600-044-G | RES,11KOhm,+/-1%,1/16W,G,SMD0402 | TA-I TECHNOLOGY CO., LTD | RM04FTN1102 | G | PWA BOM | In New BOM |
|  |  |  | 61010L600-024-G | RES,11KOhm,+/-1%,1/16W,G,SMD0402 | PANASONIC INDUSTRIAL CO.,LTD. | ERJ2RKF1102X | G | PWA BOM | In New BOM |
|  |  |  | 61010L600-029-G | RES,11KOhm,+/-1%,1/16W,G,SMD0402 | VISHAY ENTER TECHNO LOGY.INC | CRCW040211K0FKEDC | G | PWA BOM | In New BOM |
|  | R349 | 1 | 61010L600-017-G | RES,11KOhm,+/-1%,1/16W,G,SMD0402 | KOA SPEER ELECTRONICS, INC. | RK73H1ETTP1102F | N | PWA BOM | In Old BOM |
|  |  |  | 61010L600-012-G | RES,11KOhm,+/-1%,1/16W,G,SMD0402 | WALSIN | WR04X1102FTL | G | PWA BOM | In Old BOM |
|  |  |  | 61010L600-011-G | RES,11KOhm,+/-1%,1/16W,G,SMD0402 | YAGEO | RC0402FR-0711KL | G | PWA BOM | In Old BOM |
|  |  |  | 61010L600-044-G | RES,11KOhm,+/-1%,1/16W,G,SMD0402 | TA-I | RM04FTN1102 | G | PWA BOM | In Old BOM |
|  |  |  | 61010L600-024-G | RES,11KOhm,+/-1%,1/16W,G,SMD0402 | PANASONIC INDUSTRIAL CO.,LTD. | ERJ2RKF1102X | G | PWA BOM | In Old BOM |
|  |  |  | 61010L600-029-G | RES,11KOhm,+/-1%,1/16W,G,SMD0402 | VISHAY ENTER TECHNO LOGY.INC | CRCW040211K0FKEDC | G | PWA BOM | In Old BOM |
| 180 | R652,R658 | 2 | 61011KS00-017-G | RES,47KOhm,+/-1%,1/16W,G,SMD0402 | KOA SPEER ELECTRONICS, INC. | RK73H1ETTP4702F | G | PWA BOM | In New BOM |
|  |  |  | 61011KS00-012-G | RES,47KOhm,+/-1%,1/16W,G,SMD0402 | WALSIN TECHNOLOGY CORPORATION | WR04X4702FTL | G | PWA BOM | In New BOM |
|  |  |  | 61011KS00-011-G | RES,47KOhm,+/-1%,1/16W,G,SMD0402 | YAGEO CORPORATION COMPONENT | RC0402FR-0747KL | G | PWA BOM | In New BOM |
|  |  |  | 61011KS00-044-G | RES,47KOhm,+/-1%,1/16W,G,SMD0402 | TA-I TECHNOLOGY CO., LTD | RM04FTN4702 | G | PWA BOM | In New BOM |
|  |  |  | 61011KS00-029-G | RES,47KOhm,+/-1%,1/16W,G,SMD0402 | VISHAY ENTER TECHNO LOGY.INC | CRCW040247K0FKED | G | PWA BOM | In New BOM |
|  | R652,R658 | 2 | 61011KS00-017-G | RES,47KOhm,+/-1%,1/16W,G,SMD0402 | KOA SPEER ELECTRONICS, INC. | RK73H1ETTP4702F | N | PWA BOM | In Old BOM |
|  |  |  | 61011KS00-012-G | RES,47KOhm,+/-1%,1/16W,G,SMD0402 | WALSIN | WR04X4702FTL | G | PWA BOM | In Old BOM |
|  |  |  | 61011KS00-011-G | RES,47KOhm,+/-1%,1/16W,G,SMD0402 | YAGEO | RC0402FR-0747KL | G | PWA BOM | In Old BOM |
|  |  |  | 61011KS00-044-G | RES,47KOhm,+/-1%,1/16W,G,SMD0402 | TA-I | RM04FTN4702 | G | PWA BOM | In Old BOM |
|  |  |  | 61011KS00-029-G | RES,47KOhm,+/-1%,1/16W,G,SMD0402 | VISHAY ENTER TECHNO LOGY.INC | CRCW040247K0FKED | G | PWA BOM | In Old BOM |
| 181 | R664,R665,R666,R673,R1020,R1021 | 6 | 61010FL00-017-G | RES,2.2KOhm,+/-5%,1/16W,G,SMD0402 | KOA SPEER ELECTRONICS, INC. | RK73B1ETTP222J | G | PWA BOM | In New BOM |
|  |  |  | 61010FL01-012-G | RES,2.2KOhm,+/-5%,1/16W,G,SMD0402 | WALSIN TECHNOLOGY CORPORATION | WR04X222JTL | G | PWA BOM | In New BOM |
|  |  |  | 61010FL00-011-G | RES,2.2KOhm,+/-5%,1/16W,G,SMD0402 | YAGEO CORPORATION COMPONENT | RC0402JR-072K2L | G | PWA BOM | In New BOM |
|  |  |  | 61010FL00-044-G | RES,2.2KOhm,+/-5%,1/16W,G,SMD0402 | TA-I TECHNOLOGY CO., LTD | RM04JTN222 | G | PWA BOM | In New BOM |
|  |  |  | 61010FL00-029-G | RES,2.2KOhm,+/-5%,1/16W,G,SMD0402 | VISHAY ENTER TECHNO LOGY.INC | CRCW04022K20JNED | G | PWA BOM | In New BOM |
|  |  |  | 61010FL00-024-G | RES,2.2KOhm,+/-5%,1/16W,G,SMD0402 | PANASONIC INDUSTRIAL CO.,LTD. | ERJ2GEJ222X | G | PWA BOM | In New BOM |
|  | R664,R665,R666,R673,R1020,R1021 | 6 | 61010FL00-017-G | RES,2.2KOhm,+/-5%,1/16W,G,SMD0402 | KOA SPEER ELECTRONICS, INC. | RK73B1ETTP222J | N | PWA BOM | In Old BOM |
|  |  |  | 61010FL01-012-G | RES,2.2KOhm,+/-5%,1/16W,G,SMD0402 | WALSIN | WR04X222JTL | G | PWA BOM | In Old BOM |
|  |  |  | 61010FL00-011-G | RES,2.2KOhm,+/-5%,1/16W,G,SMD0402 | YAGEO | RC0402JR-072K2L | G | PWA BOM | In Old BOM |
|  |  |  | 61010FL00-044-G | RES,2.2KOhm,+/-5%,1/16W,G,SMD0402 | TA-I | RM04JTN222 | G | PWA BOM | In Old BOM |
|  |  |  | 61010FL00-029-G | RES,2.2KOhm,+/-5%,1/16W,G,SMD0402 | VISHAY ENTER TECHNO LOGY.INC | CRCW04022K20JNED | G | PWA BOM | In Old BOM |
|  |  |  | 61010FL00-024-G | RES,2.2KOhm,+/-5%,1/16W,G,SMD0402 | PANASONIC INDUSTRIAL CO.,LTD. | ERJ2GEJ222X | G | PWA BOM | In Old BOM |
| 182 | R690,R753 | 2 | 610112L00-017-G | RES,1.24KOhm,+/-1%,1/16W,G,SMD0402 | KOA SPEER ELECTRONICS, INC. | RK73H1ETTP1241F | G | PWA BOM | In New BOM |
|  |  |  | 610112L00-012-G | RES,1.24KOhm,+/-1%,1/16W,G,SMD0402 | WALSIN TECHNOLOGY CORPORATION | WR04X1241FTL | G | PWA BOM | In New BOM |
|  |  |  | 610112L00-011-G | RES,1.24KOhm,+/-1%,1/16W,G,SMD0402 | YAGEO CORPORATION COMPONENT | RC0402FR-071K24L | G | PWA BOM | In New BOM |
|  |  |  | 610112L00-044-G | RES,1.24KOhm,+/-1%,1/16W,G,SMD0402 | TA-I TECHNOLOGY CO., LTD | RM04FTN1241 | G | PWA BOM | In New BOM |
|  |  |  | 610112L00-029-G | RES,1.24KOhm,+/-1%,1/16W,G,SMD0402 | VISHAY ENTER TECHNO LOGY.INC | CRCW04021K24FKED | G | PWA BOM | In New BOM |
|  |  |  | 610112L00-024-G | RES,1.24KOhm,+/-1%,1/16W,G,SMD0402 | PANASONIC INDUSTRIAL CO.,LTD. | ERJ2RKF1241X | G | PWA BOM | In New BOM |
|  | R690,R753 | 2 | 610112L00-017-G | RES,1.24KOhm,+/-1%,1/16W,G,SMD0402 | KOA SPEER ELECTRONICS, INC. | RK73H1ETTP1241F | N | PWA BOM | In Old BOM |
|  |  |  | 610112L00-012-G | RES,1.24KOhm,+/-1%,1/16W,G,SMD0402 | WALSIN | WR04X1241FTL | G | PWA BOM | In Old BOM |
|  |  |  | 610112L00-011-G | RES,1.24KOhm,+/-1%,1/16W,G,SMD0402 | YAGEO | RC0402FR-071K24L | G | PWA BOM | In Old BOM |
|  |  |  | 610112L00-044-G | RES,1.24KOhm,+/-1%,1/16W,G,SMD0402 | TA-I | RM04FTN1241 | G | PWA BOM | In Old BOM |
|  |  |  | 610112L00-029-G | RES,1.24KOhm,+/-1%,1/16W,G,SMD0402 | VISHAY ENTER TECHNO LOGY.INC | CRCW04021K24FKED | G | PWA BOM | In Old BOM |
|  |  |  | 610112L00-024-G | RES,1.24KOhm,+/-1%,1/16W,G,SMD0402 | PANASONIC INDUSTRIAL CO.,LTD. | ERJ2RKF1241X | G | PWA BOM | In Old BOM |
| 183 | R699 | 1 | 610104E00-017-G | RES,470 Ohm,+/-1%,1/10W,G,SMD0603 | KOA SPEER ELECTRONICS, INC. | RK73H1JTTD4700F | G | PWA BOM | In New BOM |
|  |  |  | 610104E00-012-G | RES,470 Ohm,+/-1%,1/10W,G,SMD0603 | WALSIN TECHNOLOGY CORPORATION | WR06X4700FTL | G | PWA BOM | In New BOM |
|  |  |  | 610104E00-011-G | RES,470 Ohm,+/-1%,1/10W,G,SMD0603 | YAGEO CORPORATION COMPONENT | RC0603FR-07470RL | G | PWA BOM | In New BOM |
|  |  |  | 610104E00-044-G | RES,470 Ohm,+/-1%,1/10W,G,SMD0603 | TA-I TECHNOLOGY CO., LTD | RM06FTN4700 | G | PWA BOM | In New BOM |
|  |  |  | 610104E00-024-G | RES,470 Ohm,+/-1%,1/10W,G,SMD0603 | PANASONIC INDUSTRIAL CO.,LTD. | ERJ3EKF4700V | G | PWA BOM | In New BOM |
|  | R699 | 1 | 610104E00-017-G | RES,470 Ohm,+/-1%,1/10W,G,SMD0603 | KOA SPEER ELECTRONICS, INC. | RK73H1JTTD4700F | N | PWA BOM | In Old BOM |
|  |  |  | 610104E00-012-G | RES,470 Ohm,+/-1%,1/10W,G,SMD0603 | WALSIN | WR06X4700FTL | G | PWA BOM | In Old BOM |
|  |  |  | 610104E00-011-G | RES,470 Ohm,+/-1%,1/10W,G,SMD0603 | YAGEO | RC0603FR-07470RL | G | PWA BOM | In Old BOM |
|  |  |  | 610104E00-044-G | RES,470 Ohm,+/-1%,1/10W,G,SMD0603 | TA-I | RM06FTN4700 | G | PWA BOM | In Old BOM |
|  |  |  | 610104E00-024-G | RES,470 Ohm,+/-1%,1/10W,G,SMD0603 | PANASONIC INDUSTRIAL CO.,LTD. | ERJ3EKF4700V | G | PWA BOM | In Old BOM |
| 184 | R702 | 1 | 61013W100-017-G | RES,20mOhm,+/-1%,1/5W,G,SMD0603 | KOA SPEER ELECTRONICS, INC. | UR73D1JTTD20L0F | G | PWA BOM | In New BOM |
|  |  |  | 610602500-011-G | RES,20mOhm,+/-1%,1/5W,G,SMD0603 | YAGEO CORPORATION COMPONENT | PF0603FRM7W0R02Z | G | PWA BOM | In New BOM |
|  |  |  | 610602500-029-G | RES,20mOhm,+/-1%,1/5W,G,SMD0603 | VISHAY ENTER TECHNO LOGY.INC | WSL0603R0200FEA18 | G | PWA BOM | In New BOM |
|  | R702 | 1 | 61013W100-017-G | RES,20mOhm,+/-1%,1/5W,G,SMD0603 | KOA SPEER ELECTRONICS, INC. | UR73D1JTTD20L0F |  | PWA BOM | In Old BOM |
|  |  |  | 610602500-011-G | RES,20mOhm,+/-1%,1/5W,G,SMD0603 | YAGEO | PF0603FRM7W0R02Z | G | PWA BOM | In Old BOM |
|  |  |  | 610602500-029-G | RES,20mOhm,+/-1%,1/5W,G,SMD0603 | VISHAY ENTER TECHNO LOGY.INC | WSL0603R0200FEA18 | G | PWA BOM | In Old BOM |
| 185 | R725,R727,R729,R730,R815,R816,R818,R1012,R1015,R1161,R1163,R1171,R1173,R1183,R1189,R1196,R1202,R1206,R1209,R1307,R1314,R1315,R1316,R1317,R1318,R1319,R1320 | 27 | 61011H500-017-G | RES,22 Ohm,+/-1%,1/16W,G,SMD0402 | KOA SPEER ELECTRONICS, INC. | RK73H1ETTP22R0F | G | PWA BOM | In New BOM |
|  |  |  | 61011H500-012-G | RES,22 Ohm,+/-1%,1/16W,G,SMD0402 | WALSIN TECHNOLOGY CORPORATION | WR04X22R0FTL | G | PWA BOM | In New BOM |
|  |  |  | 61011H500-011-G | RES,22 Ohm,+/-1%,1/16W,G,SMD0402 | YAGEO CORPORATION COMPONENT | RC0402FR-0722RL | G | PWA BOM | In New BOM |
|  |  |  | 61011H500-044-G | RES,22 Ohm,+/-1%,1/16W,G,SMD0402 | TA-I TECHNOLOGY CO., LTD | RM04FTN22R0 | G | PWA BOM | In New BOM |
|  |  |  | 61011H500-024-G | RES,22 Ohm,+/-1%,1/16W,G,SMD0402 | PANASONIC INDUSTRIAL CO.,LTD. | ERJ2RKF22R0X | G | PWA BOM | In New BOM |
|  | R725,R727,R729,R730,R815,R816,R818,R1012,R1015,R1161,R1163,R1171,R1173,R1183,R1189,R1196,R1202,R1206,R1209,R1307,R1314,R1315,R1316,R1317,R1318,R1319,R1320 | 27 | 61011H500-017-G | RES,22 Ohm,+/-1%,1/16W,G,SMD0402 | KOA SPEER ELECTRONICS, INC. | RK73H1ETTP22R0F | N | PWA BOM | In Old BOM |
|  |  |  | 61011H500-012-G | RES,22 Ohm,+/-1%,1/16W,G,SMD0402 | WALSIN | WR04X22R0FTL | G | PWA BOM | In Old BOM |
|  |  |  | 61011H500-011-G | RES,22 Ohm,+/-1%,1/16W,G,SMD0402 | YAGEO | RC0402FR-0722RL | G | PWA BOM | In Old BOM |
|  |  |  | 61011H500-044-G | RES,22 Ohm,+/-1%,1/16W,G,SMD0402 | TA-I | RM04FTN22R0 | G | PWA BOM | In Old BOM |
|  |  |  | 61011H500-024-G | RES,22 Ohm,+/-1%,1/16W,G,SMD0402 | PANASONIC INDUSTRIAL CO.,LTD. | ERJ2RKF22R0X | G | PWA BOM | In Old BOM |
| 186 | R733,R734 | 2 | 610112B00-017-G | RES,3.4KOhm,+/-1%,1/16W,G,SMD0402 | KOA SPEER ELECTRONICS, INC. | RK73H1ETTP3401F | G | PWA BOM | In New BOM |
|  |  |  | 610112B00-012-G | RES,3.4KOhm,+/-1%,1/16W,G,SMD0402 | WALSIN TECHNOLOGY CORPORATION | WR04X3401FTL | G | PWA BOM | In New BOM |
|  |  |  | 610112B00-011-G | RES,3.4KOhm,+/-1%,1/16W,G,SMD0402 | YAGEO CORPORATION COMPONENT | RC0402FR-073K4L | G | PWA BOM | In New BOM |
|  |  |  | 610112B00-044-G | RES,3.4KOhm,+/-1%,1/16W,G,SMD0402 | TA-I TECHNOLOGY CO., LTD | RM04FTN3401 | G | PWA BOM | In New BOM |
|  | R733,R734 | 2 | 610112B00-017-G | RES,3.4KOhm,+/-1%,1/16W,G,SMD0402 | KOA SPEER ELECTRONICS, INC. | RK73H1ETTP3401F | N | PWA BOM | In Old BOM |
|  |  |  | 610112B00-012-G | RES,3.4KOhm,+/-1%,1/16W,G,SMD0402 | WALSIN | WR04X3401FTL | G | PWA BOM | In Old BOM |
|  |  |  | 610112B00-011-G | RES,3.4KOhm,+/-1%,1/16W,G,SMD0402 | YAGEO | RC0402FR-073K4L | G | PWA BOM | In Old BOM |
|  |  |  | 610112B00-044-G | RES,3.4KOhm,+/-1%,1/16W,G,SMD0402 | TA-I | RM04FTN3401 | G | PWA BOM | In Old BOM |
| 187 | R738,R1111 | 2 | 61011B000-017-G | RES,1.5KOhm,+/-1%,1/16W,G,SMD0402 | KOA SPEER ELECTRONICS, INC. | RK73H1ETTP1501F | G | PWA BOM | In New BOM |
|  |  |  | 61011B000-012-G | RES,1.5KOhm,+/-1%,1/16W,G,SMD0402 | WALSIN TECHNOLOGY CORPORATION | WR04X1501FTL | G | PWA BOM | In New BOM |
|  |  |  | 61011B000-011-G | RES,1.5KOhm,+/-1%,1/16W,G,SMD0402 | YAGEO CORPORATION COMPONENT | RC0402FR-071K5L | G | PWA BOM | In New BOM |
|  |  |  | 61011B000-044-G | RES,1.5KOhm,+/-1%,1/16W,G,SMD0402 | TA-I TECHNOLOGY CO., LTD | RM04FTN1501 | G | PWA BOM | In New BOM |
|  |  |  | 61011B000-024-G | RES,1.5KOhm,+/-1%,1/16W,G,SMD0402 | PANASONIC INDUSTRIAL CO.,LTD. | ERJ2RKF1501X | G | PWA BOM | In New BOM |
|  | R738,R1111 | 2 | 61011B000-017-G | RES,1.5KOhm,+/-1%,1/16W,G,SMD0402 | KOA SPEER ELECTRONICS, INC. | RK73H1ETTP1501F | N | PWA BOM | In Old BOM |
|  |  |  | 61011B000-012-G | RES,1.5KOhm,+/-1%,1/16W,G,SMD0402 | WALSIN | WR04X1501FTL | G | PWA BOM | In Old BOM |
|  |  |  | 61011B000-011-G | RES,1.5KOhm,+/-1%,1/16W,G,SMD0402 | YAGEO | RC0402FR-071K5L | G | PWA BOM | In Old BOM |
|  |  |  | 61011B000-044-G | RES,1.5KOhm,+/-1%,1/16W,G,SMD0402 | TA-I | RM04FTN1501 | G | PWA BOM | In Old BOM |
|  |  |  | 61011B000-024-G | RES,1.5KOhm,+/-1%,1/16W,G,SMD0402 | PANASONIC INDUSTRIAL CO.,LTD. | ERJ2RKF1501X | G | PWA BOM | In Old BOM |
| 188 | R739,R741,R742,R743,R749,R936,R937,R993,R994,R995,R996,R997 | 12 | 610101V00-017-G | RES,22 Ohm,+/-5%,1/16W,G,SMD0402 | KOA SPEER ELECTRONICS, INC. | RK73B1ETTP220J | G | PWA BOM | In New BOM |
|  |  |  | 610101V00-012-G | RES,22 Ohm,+/-5%,1/16W,G,SMD0402 | WALSIN TECHNOLOGY CORPORATION | WR04X220JTL | G | PWA BOM | In New BOM |
|  |  |  | 610101V00-011-G | RES,22 Ohm,+/-5%,1/16W,G,SMD0402 | YAGEO CORPORATION COMPONENT | RC0402JR-0722RL | G | PWA BOM | In New BOM |
|  |  |  | 610101V00-044-G | RES,22 Ohm,+/-5%,1/16W,G,SMD0402 | TA-I TECHNOLOGY CO., LTD | RM04JTN220 | G | PWA BOM | In New BOM |
|  |  |  | 610101V00-024-G | RES,22 Ohm,+/-5%,1/16W,G,SMD0402 | PANASONIC INDUSTRIAL CO.,LTD. | ERJ2GEJ220X | G | PWA BOM | In New BOM |
|  | R739,R741,R742,R743,R749,R936,R937,R993,R994,R995,R996,R997 | 12 | 610101V00-017-G | RES,22 Ohm,+/-5%,1/16W,G,SMD0402 | KOA SPEER ELECTRONICS, INC. | RK73B1ETTP220J | N | PWA BOM | In Old BOM |
|  |  |  | 610101V00-012-G | RES,22 Ohm,+/-5%,1/16W,G,SMD0402 | WALSIN | WR04X220JTL | G | PWA BOM | In Old BOM |
|  |  |  | 610101V00-011-G | RES,22 Ohm,+/-5%,1/16W,G,SMD0402 | YAGEO | RC0402JR-0722RL | G | PWA BOM | In Old BOM |
|  |  |  | 610101V00-044-G | RES,22 Ohm,+/-5%,1/16W,G,SMD0402 | TA-I | RM04JTN220 | G | PWA BOM | In Old BOM |
|  |  |  | 610101V00-024-G | RES,22 Ohm,+/-5%,1/16W,G,SMD0402 | PANASONIC INDUSTRIAL CO.,LTD. | ERJ2GEJ220X | G | PWA BOM | In Old BOM |
| 189 | R789 | 1 | 61011T800-017-G | RES,240 Ohm,+/-1%,1/16W,G,SMD0402 | KOA SPEER ELECTRONICS, INC. | RK73H1ETTP2400F | G | PWA BOM | In New BOM |
|  |  |  | 61011T800-012-G | RES,240 Ohm,+/-1%,1/16W,G,SMD0402 | WALSIN TECHNOLOGY CORPORATION | WR04X2400FTL | G | PWA BOM | In New BOM |
|  |  |  | 61011T800-011-G | RES,240 Ohm,+/-1%,1/16W,G,SMD0402 | YAGEO CORPORATION COMPONENT | RC0402FR-07240RL | G | PWA BOM | In New BOM |
|  |  |  | 61011T800-044-G | RES,240 Ohm,+/-1%,1/16W,G,SMD0402 | TA-I TECHNOLOGY CO., LTD | RM04FTN2400 | G | PWA BOM | In New BOM |
|  | R789 | 1 | 61011T800-017-G | RES,240 Ohm,+/-1%,1/16W,G,SMD0402 | KOA SPEER ELECTRONICS, INC. | RK73H1ETTP2400F | N | PWA BOM | In Old BOM |
|  |  |  | 61011T800-012-G | RES,240 Ohm,+/-1%,1/16W,G,SMD0402 | WALSIN | WR04X2400FTL | G | PWA BOM | In Old BOM |
|  |  |  | 61011T800-011-G | RES,240 Ohm,+/-1%,1/16W,G,SMD0402 | YAGEO | RC0402FR-07240RL | G | PWA BOM | In Old BOM |
|  |  |  | 61011T800-044-G | RES,240 Ohm,+/-1%,1/16W,G,SMD0402 | TA-I | RM04FTN2400 | G | PWA BOM | In Old BOM |
| 190 | R790,R1154,R1157,R1237 | 4 | 61100BN00-017-G | RES,100KOhm,+/-1%,1/16W,G,SMD0402 | KOA SPEER ELECTRONICS, INC. | RN731ETTP1003F25 | G | PWA BOM | In New BOM |
|  |  |  | 61100BN00-012-G | RES,100KOhm,+/-1%,1/16W,G,SMD0402 | WALSIN TECHNOLOGY CORPORATION | WF04U1003FTL | G | PWA BOM | In New BOM |
|  |  |  | 61100BN00-011-G | RES,100KOhm,+/-1%,1/16W,G,SMD0402 | YAGEO CORPORATION COMPONENT | RT0402FRD07100KL | G | PWA BOM | In New BOM |
|  | R790,R1154,R1157,R1237 | 4 | 61100BN00-017-G | RES,100KOhm,+/-1%,1/16W,G,SMD0402 | KOA SPEER ELECTRONICS, INC. | RN731ETTP1003F25 |  | PWA BOM | In Old BOM |
|  |  |  | 61100BN00-012-G | RES,100KOhm,+/-1%,1/16W,G,SMD0402 | WALSIN | WF04U1003FTL | G | PWA BOM | In Old BOM |
|  |  |  | 61100BN00-011-G | RES,100KOhm,+/-1%,1/16W,G,SMD0402 | YAGEO | RT0402FRD07100KL | G | PWA BOM | In Old BOM |
| 191 | R792,R793,R794,R796,R797,R799,R1019,R1025 | 8 | 610115J00-017-G | RES,33 Ohm,+/-1%,1/16W,G,SMD0402 | KOA SPEER ELECTRONICS, INC. | RK73H1ETTP33R0F | G | PWA BOM | In New BOM |
|  |  |  | 610115J00-012-G | RES,33 Ohm,+/-1%,1/16W,G,SMD0402 | WALSIN TECHNOLOGY CORPORATION | WR04X33R0FTL | G | PWA BOM | In New BOM |
|  |  |  | 610115J00-011-G | RES,33 Ohm,+/-1%,1/16W,G,SMD0402 | YAGEO CORPORATION COMPONENT | RC0402FR-0733RL | G | PWA BOM | In New BOM |
|  |  |  | 610115J00-044-G | RES,33 Ohm,+/-1%,1/16W,G,SMD0402 | TA-I TECHNOLOGY CO., LTD | RM04FTN33R0 | G | PWA BOM | In New BOM |
|  |  |  | 610115J00-024-G | RES,33 Ohm,+/-1%,1/16W,G,SMD0402 | PANASONIC INDUSTRIAL CO.,LTD. | ERJ2RKF33R0X | G | PWA BOM | In New BOM |
|  | R792,R793,R794,R796,R797,R799,R1019,R1025 | 8 | 610115J00-017-G | RES,33 Ohm,+/-1%,1/16W,G,SMD0402 | KOA SPEER ELECTRONICS, INC. | RK73H1ETTP33R0F | N | PWA BOM | In Old BOM |
|  |  |  | 610115J00-012-G | RES,33 Ohm,+/-1%,1/16W,G,SMD0402 | WALSIN | WR04X33R0FTL | G | PWA BOM | In Old BOM |
|  |  |  | 610115J00-011-G | RES,33 Ohm,+/-1%,1/16W,G,SMD0402 | YAGEO | RC0402FR-0733RL | G | PWA BOM | In Old BOM |
|  |  |  | 610115J00-044-G | RES,33 Ohm,+/-1%,1/16W,G,SMD0402 | TA-I | RM04FTN33R0 | G | PWA BOM | In Old BOM |
|  |  |  | 610115J00-024-G | RES,33 Ohm,+/-1%,1/16W,G,SMD0402 | PANASONIC INDUSTRIAL CO.,LTD. | ERJ2RKF33R0X | G | PWA BOM | In Old BOM |
| 192 | R831,R832,R833,R834,R1345,R1347,R1494 | 7 | 61011H100-017-G | RES,220 Ohm,+/-1%,1/16W,G,SMD0402 | KOA SPEER ELECTRONICS, INC. | RK73H1ETTP2200F | G | PWA BOM | In New BOM |
|  |  |  | 61011H100-012-G | RES,220 Ohm,+/-1%,1/16W,G,SMD0402 | WALSIN TECHNOLOGY CORPORATION | WR04X2200FTL | G | PWA BOM | In New BOM |
|  |  |  | 61011H100-011-G | RES,220 Ohm,+/-1%,1/16W,G,SMD0402 | YAGEO CORPORATION COMPONENT | RC0402FR-07220RL | G | PWA BOM | In New BOM |
|  |  |  | 61011H100-044-G | RES,220 Ohm,+/-1%,1/16W,G,SMD0402 | TA-I TECHNOLOGY CO., LTD | RM04FTN2200 | G | PWA BOM | In New BOM |
|  |  |  | 61011H100-024-G | RES,220 Ohm,+/-1%,1/16W,G,SMD0402 | PANASONIC INDUSTRIAL CO.,LTD. | ERJ2RKF2200X | G | PWA BOM | In New BOM |
|  |  |  | 61011H100-029-G | RES,220 Ohm,+/-1%,1/16W,G,SMD0402 | VISHAY ENTER TECHNO LOGY.INC | CRCW0402220RFKEDC | G | PWA BOM | In New BOM |
|  | R831,R832,R833,R834,R1345,R1347,R1494 | 7 | 61011H100-017-G | RES,220 Ohm,+/-1%,1/16W,G,SMD0402 | KOA SPEER ELECTRONICS, INC. | RK73H1ETTP2200F | N | PWA BOM | In Old BOM |
|  |  |  | 61011H100-012-G | RES,220 Ohm,+/-1%,1/16W,G,SMD0402 | WALSIN | WR04X2200FTL | G | PWA BOM | In Old BOM |
|  |  |  | 61011H100-011-G | RES,220 Ohm,+/-1%,1/16W,G,SMD0402 | YAGEO | RC0402FR-07220RL | G | PWA BOM | In Old BOM |
|  |  |  | 61011H100-044-G | RES,220 Ohm,+/-1%,1/16W,G,SMD0402 | TA-I | RM04FTN2200 | G | PWA BOM | In Old BOM |
|  |  |  | 61011H100-024-G | RES,220 Ohm,+/-1%,1/16W,G,SMD0402 | PANASONIC INDUSTRIAL CO.,LTD. | ERJ2RKF2200X | G | PWA BOM | In Old BOM |
|  |  |  | 61011H100-029-G | RES,220 Ohm,+/-1%,1/16W,G,SMD0402 | VISHAY ENTER TECHNO LOGY.INC | CRCW0402220RFKEDC | G | PWA BOM | In Old BOM |
| 193 | R886 | 1 | 61011KH00-017-G | RES,240 Ohm,+/-5%,1/16W,G,SMD0402 | KOA SPEER ELECTRONICS, INC. | RK73B1ETTP241J | G | PWA BOM | In New BOM |
|  |  |  | 61011KH00-012-G | RES,240 Ohm,+/-5%,1/16W,G,SMD0402 | WALSIN TECHNOLOGY CORPORATION | WR04X241JTL | G | PWA BOM | In New BOM |
|  |  |  | 61011KH00-011-G | RES,240 Ohm,+/-5%,1/16W,G,SMD0402 | YAGEO CORPORATION COMPONENT | RC0402JR-07240RL | G | PWA BOM | In New BOM |
|  |  |  | 61011KH00-044-G | RES,240 Ohm,+/-5%,1/16W,G,SMD0402 | TA-I TECHNOLOGY CO., LTD | RM04JTN241 | G | PWA BOM | In New BOM |
|  |  |  | 61011KH00-024-G | RES,240 Ohm,+/-5%,1/16W,G,SMD0402 | PANASONIC INDUSTRIAL CO.,LTD. | ERJ2GEJ241X | G | PWA BOM | In New BOM |
|  | R886 | 1 | 61011KH00-017-G | RES,240 Ohm,+/-5%,1/16W,G,SMD0402 | KOA SPEER ELECTRONICS, INC. | RK73B1ETTP241J | N | PWA BOM | In Old BOM |
|  |  |  | 61011KH00-012-G | RES,240 Ohm,+/-5%,1/16W,G,SMD0402 | WALSIN | WR04X241JTL | G | PWA BOM | In Old BOM |
|  |  |  | 61011KH00-011-G | RES,240 Ohm,+/-5%,1/16W,G,SMD0402 | YAGEO | RC0402JR-07240RL | G | PWA BOM | In Old BOM |
|  |  |  | 61011KH00-044-G | RES,240 Ohm,+/-5%,1/16W,G,SMD0402 | TA-I | RM04JTN241 | G | PWA BOM | In Old BOM |
|  |  |  | 61011KH00-024-G | RES,240 Ohm,+/-5%,1/16W,G,SMD0402 | PANASONIC INDUSTRIAL CO.,LTD. | ERJ2GEJ241X | G | PWA BOM | In Old BOM |
| 194 | R925,R927,R929 | 3 | 610102600-017-G | RES,56 Ohm,+/-1%,1/16W,G,SMD0402 | KOA SPEER ELECTRONICS, INC. | RK73H1ETTP56R0F | G | PWA BOM | In New BOM |
|  |  |  | 610102600-012-G | RES,56 Ohm,+/-1%,1/16W,G,SMD0402 | WALSIN TECHNOLOGY CORPORATION | WR04X56R0FTL | G | PWA BOM | In New BOM |
|  |  |  | 610102600-011-G | RES,56 Ohm,+/-1%,1/16W,G,SMD0402 | YAGEO CORPORATION COMPONENT | RC0402FR-0756RL | G | PWA BOM | In New BOM |
|  |  |  | 610102600-044-G | RES,56 Ohm,+/-1%,1/16W,G,SMD0402 | TA-I TECHNOLOGY CO., LTD | RM04FTN56R0 | G | PWA BOM | In New BOM |
|  |  |  | 610102600-024-G | RES,56 Ohm,+/-1%,1/16W,G,SMD0402 | PANASONIC INDUSTRIAL CO.,LTD. | ERJ2RKF56R0X | G | PWA BOM | In New BOM |
|  | R925,R927,R929 | 3 | 610102600-017-G | RES,56 Ohm,+/-1%,1/16W,G,SMD0402 | KOA SPEER ELECTRONICS, INC. | RK73H1ETTP56R0F | N | PWA BOM | In Old BOM |
|  |  |  | 610102600-012-G | RES,56 Ohm,+/-1%,1/16W,G,SMD0402 | WALSIN | WR04X56R0FTL | G | PWA BOM | In Old BOM |
|  |  |  | 610102600-011-G | RES,56 Ohm,+/-1%,1/16W,G,SMD0402 | YAGEO | RC0402FR-0756RL | G | PWA BOM | In Old BOM |
|  |  |  | 610102600-044-G | RES,56 Ohm,+/-1%,1/16W,G,SMD0402 | TA-I | RM04FTN56R0 | G | PWA BOM | In Old BOM |
|  |  |  | 610102600-024-G | RES,56 Ohm,+/-1%,1/16W,G,SMD0402 | PANASONIC INDUSTRIAL CO.,LTD. | ERJ2RKF56R0X | G | PWA BOM | In Old BOM |
| 195 | R940,R966,R998,R999,R1084,R1085,R1088,R1261,R1751 | 9 | 61100LV00-017-G | RES,10KOhm,+/-1%,1/16W,G,SMD0402 | KOA SPEER ELECTRONICS, INC. | RN731ETTP1002F50 | G | PWA BOM | In New BOM |
|  |  |  | 61100LV00-012-G | RES,10KOhm,+/-1%,1/16W,G,SMD0402 | WALSIN TECHNOLOGY CORPORATION | WF04T1002FTL | G | PWA BOM | In New BOM |
|  |  |  | 61100LV00-011-G | RES,10KOhm,+/-1%,1/16W,G,SMD0402 | YAGEO CORPORATION COMPONENT | RT0402FRE0710KL | G | PWA BOM | In New BOM |
|  |  |  | 61100LV00-044-G | RES,10KOhm,+/-1%,1/16W,G,SMD0402 | TA-I TECHNOLOGY CO., LTD | RB04FTS1002 | G | PWA BOM | In New BOM |
|  | R940,R966,R998,R999,R1084,R1085,R1088,R1261,R1751 | 9 | 61100LV00-017-G | RES,10KOhm,+/-1%,1/16W,G,SMD0402 | KOA SPEER ELECTRONICS, INC. | RN731ETTP1002F50 |  | PWA BOM | In Old BOM |
|  |  |  | 61100LV00-012-G | RES,10KOhm,+/-1%,1/16W,G,SMD0402 | WALSIN | WF04T1002FTL | G | PWA BOM | In Old BOM |
|  |  |  | 61100LV00-011-G | RES,10KOhm,+/-1%,1/16W,G,SMD0402 | YAGEO | RT0402FRE0710KL | G | PWA BOM | In Old BOM |
|  |  |  | 61100LV00-044-G | RES,10KOhm,+/-1%,1/16W,G,SMD0402 | TA-I | RB04FTS1002 | G | PWA BOM | In Old BOM |
| 196 | R960,R1323,R1325,R1327,R1328,R1412,R1413,R1414,R1416,R1417,R1418,R1422,R1423,R1424,R1425,R1426,R1427,R1428,R1505,R1506,R1516,R1517,R1518,R1523,R1783 | 25 | 610114U00-017-G | RES,3.3KOhm,+/-1%,1/16W,G,SMD0402 | KOA SPEER ELECTRONICS, INC. | RK73H1ETTP3301F | G | PWA BOM | In New BOM |
|  |  |  | 610114U00-012-G | RES,3.3KOhm,+/-1%,1/16W,G,SMD0402 | WALSIN TECHNOLOGY CORPORATION | WR04X3301FTL | G | PWA BOM | In New BOM |
|  |  |  | 610114U00-011-G | RES,3.3KOhm,+/-1%,1/16W,G,SMD0402 | YAGEO CORPORATION COMPONENT | RC0402FR-073K3L | G | PWA BOM | In New BOM |
|  |  |  | 610114U00-044-G | RES,3.3KOhm,+/-1%,1/16W,G,SMD0402 | TA-I TECHNOLOGY CO., LTD | RM04FTN3301 | G | PWA BOM | In New BOM |
|  |  |  | 610114U00-024-G | RES,3.3KOhm,+/-1%,1/16W,G,SMD0402 | PANASONIC INDUSTRIAL CO.,LTD. | ERJ2RKF3301X | G | PWA BOM | In New BOM |
|  | R960,R1323,R1325,R1327,R1328,R1412,R1413,R1414,R1416,R1417,R1418,R1422,R1423,R1424,R1425,R1426,R1427,R1428,R1505,R1506,R1516,R1517,R1518,R1523,R1783 | 25 | 610114U00-017-G | RES,3.3KOhm,+/-1%,1/16W,G,SMD0402 | KOA SPEER ELECTRONICS, INC. | RK73H1ETTP3301F | N | PWA BOM | In Old BOM |
|  |  |  | 610114U00-012-G | RES,3.3KOhm,+/-1%,1/16W,G,SMD0402 | WALSIN | WR04X3301FTL | G | PWA BOM | In Old BOM |
|  |  |  | 610114U00-011-G | RES,3.3KOhm,+/-1%,1/16W,G,SMD0402 | YAGEO | RC0402FR-073K3L | G | PWA BOM | In Old BOM |
|  |  |  | 610114U00-044-G | RES,3.3KOhm,+/-1%,1/16W,G,SMD0402 | TA-I | RM04FTN3301 | G | PWA BOM | In Old BOM |
|  |  |  | 610114U00-024-G | RES,3.3KOhm,+/-1%,1/16W,G,SMD0402 | PANASONIC INDUSTRIAL CO.,LTD. | ERJ2RKF3301X | G | PWA BOM | In Old BOM |
| 197 | R961,R962,R963,R964,R965,R967,R968,R969,R970,R975,R976,R977,R978,R985,R986,R988,R989,R992,R1003 | 19 | 61100C600-017-G | RES,1KOhm,+/-0.5%,1/16W,G,SMD0402 | KOA SPEER ELECTRONICS, INC. | RN731ETTP1001D25 | G | PWA BOM | In New BOM |
|  |  |  | ERA2AED102X | RES,1KOhm,+/-0.5%,1/16W,G,SMD0402 | PANASONIC INDUSTRIAL CO.,LTD. | ERA2AED102X | G | PWA BOM | In New BOM |
|  |  |  | 61100C600-029-G | RES,1KOhm,+/-0.5%,1/16W,G,SMD0402 | VISHAY ENTER TECHNO LOGY.INC | MCS04020D1001DE000 | G | PWA BOM | In New BOM |
|  | R961,R962,R963,R964,R965,R967,R968,R969,R970,R975,R976,R977,R978,R985,R986,R988,R989,R992,R1003 | 19 | 61100C600-017-G | RES,1KOhm,+/-0.5%,1/16W,G,SMD0402 | KOA SPEER ELECTRONICS, INC. | RN731ETTP1001D25 |  | PWA BOM | In Old BOM |
|  |  |  | 61100C600-024-G | RES,1KOhm,+/-0.5%,1/16W,G,SMD0402 | PANASONIC INDUSTRIAL CO.,LTD. | ERA2AED1001X | G | PWA BOM | In Old BOM |
|  |  |  | 61100C600-029-G | RES,1KOhm,+/-0.5%,1/16W,G,SMD0402 | VISHAY ENTER TECHNO LOGY.INC | MCS04020D1001DE000 | G | PWA BOM | In Old BOM |
| 198 | R971 | 1 | 61010A000-017-G | RES,8.2KOhm,+/-5%,1/16W,G,SMD0402 | KOA SPEER ELECTRONICS, INC. | RK73B1ETTP822J | G | PWA BOM | In New BOM |
|  |  |  | 61010A000-012-G | RES,8.2KOhm,+/-5%,1/16W,G,SMD0402 | WALSIN TECHNOLOGY CORPORATION | WR04X822JTL | G | PWA BOM | In New BOM |
|  |  |  | 61010A000-011-G | RES,8.2KOhm,+/-5%,1/16W,G,SMD0402 | YAGEO CORPORATION COMPONENT | RC0402JR-078K2L | G | PWA BOM | In New BOM |
|  |  |  | 61010A000-044-G | RES,8.2KOhm,+/-5%,1/16W,G,SMD0402 | TA-I TECHNOLOGY CO., LTD | RM04JTN822 | G | PWA BOM | In New BOM |
|  |  |  | 61010A000-024-G | RES,8.2KOhm,+/-5%,1/16W,G,SMD0402 | PANASONIC INDUSTRIAL CO.,LTD. | ERJ2GEJ822X | G | PWA BOM | In New BOM |
|  | R971 | 1 | 61010A000-017-G | RES,8.2KOhm,+/-5%,1/16W,G,SMD0402 | KOA SPEER ELECTRONICS, INC. | RK73B1ETTP822J | N | PWA BOM | In Old BOM |
|  |  |  | 61010A000-012-G | RES,8.2KOhm,+/-5%,1/16W,G,SMD0402 | WALSIN | WR04X822JTL | G | PWA BOM | In Old BOM |
|  |  |  | 61010A000-011-G | RES,8.2KOhm,+/-5%,1/16W,G,SMD0402 | YAGEO | RC0402JR-078K2L | G | PWA BOM | In Old BOM |
|  |  |  | 61010A000-044-G | RES,8.2KOhm,+/-5%,1/16W,G,SMD0402 | TA-I | RM04JTN822 | G | PWA BOM | In Old BOM |
|  |  |  | 61010A000-024-G | RES,8.2KOhm,+/-5%,1/16W,G,SMD0402 | PANASONIC INDUSTRIAL CO.,LTD. | ERJ2GEJ822X | G | PWA BOM | In Old BOM |
| 199 | R991,R1440,R1446,R1447,R1448,R1449,R1450,R1451,R1594,R1595,R1596,R1597,R1598,R1601,R1602,R1607,R1608,R1609,R1610,R1611,R1612,R1613,R1614,R1615,R1616,R1617,R1618,R1619,R1620,R1621,R1622,R1623,R1624,R1625,R1626,R1627,R1628,R1629,R1630,R1631,R1632,R1633,R1634,R1635,R1636,R1637,R1638,R1723 | 48 | 610115V00-017-G | RES,300 Ohm,+/-1%,1/16W,G,SMD0402 | KOA SPEER ELECTRONICS, INC. | RK73H1ETTP3000F | G | PWA BOM | In New BOM |
|  |  |  | 610115V00-012-G | RES,300 Ohm,+/-1%,1/16W,G,SMD0402 | WALSIN TECHNOLOGY CORPORATION | WR04X3000FTL | G | PWA BOM | In New BOM |
|  |  |  | 610115V00-011-G | RES,300 Ohm,+/-1%,1/16W,G,SMD0402 | YAGEO CORPORATION COMPONENT | RC0402FR-07300RL | G | PWA BOM | In New BOM |
|  |  |  | 610115V00-044-G | RES,300 Ohm,+/-1%,1/16W,G,SMD0402 | TA-I TECHNOLOGY CO., LTD | RM04FTN3000 | G | PWA BOM | In New BOM |
|  | R991,R1440,R1446,R1447,R1448,R1449,R1450,R1451,R1594,R1595,R1596,R1597,R1598,R1601,R1602,R1607,R1608,R1609,R1610,R1611,R1612,R1613,R1614,R1615,R1616,R1617,R1618,R1619,R1620,R1621,R1622,R1623,R1624,R1625,R1626,R1627,R1628,R1629,R1630,R1631,R1632,R1633,R1634,R1635,R1636,R1637,R1638,R1723 | 48 | 610115V00-017-G | RES,300 Ohm,+/-1%,1/16W,G,SMD0402 | KOA SPEER ELECTRONICS, INC. | RK73H1ETTP3000F | N | PWA BOM | In Old BOM |
|  |  |  | 610115V00-012-G | RES,300 Ohm,+/-1%,1/16W,G,SMD0402 | WALSIN | WR04X3000FTL | G | PWA BOM | In Old BOM |
|  |  |  | 610115V00-011-G | RES,300 Ohm,+/-1%,1/16W,G,SMD0402 | YAGEO | RC0402FR-07300RL | G | PWA BOM | In Old BOM |
|  |  |  | 610115V00-044-G | RES,300 Ohm,+/-1%,1/16W,G,SMD0402 | TA-I | RM04FTN3000 | G | PWA BOM | In Old BOM |
| 200 | R1000,R1002 | 2 | 610118100-017-G | RES,1.4KOhm,+/-1%,1/16W,G,SMD0402 | KOA SPEER ELECTRONICS, INC. | RK73H1ETTP1401F | G | PWA BOM | In New BOM |
|  |  |  | 610118100-012-G | RES,1.4KOhm,+/-1%,1/16W,G,SMD0402 | WALSIN TECHNOLOGY CORPORATION | WR04X1401FTL | G | PWA BOM | In New BOM |
|  |  |  | 610118100-011-G | RES,1.4KOhm,+/-1%,1/16W,G,SMD0402 | YAGEO CORPORATION COMPONENT | RC0402FR-071K4L | G | PWA BOM | In New BOM |
|  |  |  | 610118100-044-G | RES,1.4KOhm,+/-1%,1/16W,G,SMD0402 | TA-I TECHNOLOGY CO., LTD | RM04FTN1401 | G | PWA BOM | In New BOM |
|  |  |  | 610118100-024-G | RES,1.4KOhm,+/-1%,1/16W,G,SMD0402 | PANASONIC INDUSTRIAL CO.,LTD. | ERJ2RKF1401X | G | PWA BOM | In New BOM |
|  | R1000,R1002 | 2 | 610118100-017-G | RES,1.4KOhm,+/-1%,1/16W,G,SMD0402 | KOA SPEER ELECTRONICS, INC. | RK73H1ETTP1401F | N | PWA BOM | In Old BOM |
|  |  |  | 610118100-012-G | RES,1.4KOhm,+/-1%,1/16W,G,SMD0402 | WALSIN | WR04X1401FTL | G | PWA BOM | In Old BOM |
|  |  |  | 610118100-011-G | RES,1.4KOhm,+/-1%,1/16W,G,SMD0402 | YAGEO | RC0402FR-071K4L | G | PWA BOM | In Old BOM |
|  |  |  | 610118100-044-G | RES,1.4KOhm,+/-1%,1/16W,G,SMD0402 | TA-I | RM04FTN1401 | G | PWA BOM | In Old BOM |
|  |  |  | 610118100-024-G | RES,1.4KOhm,+/-1%,1/16W,G,SMD0402 | PANASONIC INDUSTRIAL CO.,LTD. | ERJ2RKF1401X | G | PWA BOM | In Old BOM |
| 201 | R1006,R1007,R1008,R1009,R1010,R1011 | 6 | 61010FF00-017-G | RES,150 Ohm,+/-1%,1/16W,G,SMD0402 | KOA SPEER ELECTRONICS, INC. | RK73H1ETTP1500F | G | PWA BOM | In New BOM |
|  |  |  | 61010FF00-012-G | RES,150 Ohm,+/-1%,1/16W,G,SMD0402 | WALSIN TECHNOLOGY CORPORATION | WR04X1500FTL | G | PWA BOM | In New BOM |
|  |  |  | 61010FF00-011-G | RES,150 Ohm,+/-1%,1/16W,G,SMD0402 | YAGEO CORPORATION COMPONENT | RC0402FR-07150RL | G | PWA BOM | In New BOM |
|  |  |  | 61010FF00-044-G | RES,150 Ohm,+/-1%,1/16W,G,SMD0402 | TA-I TECHNOLOGY CO., LTD | RM04FTN1500 | G | PWA BOM | In New BOM |
|  |  |  | 61010FF00-024-G | RES,150 Ohm,+/-1%,1/16W,G,SMD0402 | PANASONIC INDUSTRIAL CO.,LTD. | ERJ2RKF1500X | G | PWA BOM | In New BOM |
|  | R1006,R1007,R1008,R1009,R1010,R1011 | 6 | 61010FF00-017-G | RES,150 Ohm,+/-1%,1/16W,G,SMD0402 | KOA SPEER ELECTRONICS, INC. | RK73H1ETTP1500F | N | PWA BOM | In Old BOM |
|  |  |  | 61010FF00-012-G | RES,150 Ohm,+/-1%,1/16W,G,SMD0402 | WALSIN | WR04X1500FTL | G | PWA BOM | In Old BOM |
|  |  |  | 61010FF00-011-G | RES,150 Ohm,+/-1%,1/16W,G,SMD0402 | YAGEO | RC0402FR-07150RL | G | PWA BOM | In Old BOM |
|  |  |  | 61010FF00-044-G | RES,150 Ohm,+/-1%,1/16W,G,SMD0402 | TA-I | RM04FTN1500 | G | PWA BOM | In Old BOM |
|  |  |  | 61010FF00-024-G | RES,150 Ohm,+/-1%,1/16W,G,SMD0402 | PANASONIC INDUSTRIAL CO.,LTD. | ERJ2RKF1500X | G | PWA BOM | In Old BOM |
| 202 | R1026 | 1 | 610114R00-017-G | RES,49.9KOhm,+/-1%,1/16W,G,SMD0402 | KOA SPEER ELECTRONICS, INC. | RK73H1ETTP4992F | G | PWA BOM | In New BOM |
|  |  |  | 610114R00-012-G | RES,49.9KOhm,+/-1%,1/16W,G,SMD0402 | WALSIN TECHNOLOGY CORPORATION | WR04X4992FTL | G | PWA BOM | In New BOM |
|  |  |  | 610114R00-011-G | RES,49.9KOhm,+/-1%,1/16W,G,SMD0402 | YAGEO CORPORATION COMPONENT | RC0402FR-0749K9L | G | PWA BOM | In New BOM |
|  |  |  | 610114R00-044-G | RES,49.9KOhm,+/-1%,1/16W,G,SMD0402 | TA-I TECHNOLOGY CO., LTD | RM04FTN4992 | G | PWA BOM | In New BOM |
|  |  |  | 610114R00-029-G | RES,49.9KOhm,+/-1%,1/16W,G,SMD0402 | VISHAY ENTER TECHNO LOGY.INC | CRCW040249K9FKED | G | PWA BOM | In New BOM |
|  | R1026 | 1 | 610114R00-017-G | RES,49.9KOhm,+/-1%,1/16W,G,SMD0402 | KOA SPEER ELECTRONICS, INC. | RK73H1ETTP4992F | N | PWA BOM | In Old BOM |
|  |  |  | 610114R00-012-G | RES,49.9KOhm,+/-1%,1/16W,G,SMD0402 | WALSIN | WR04X4992FTL | G | PWA BOM | In Old BOM |
|  |  |  | 610114R00-011-G | RES,49.9KOhm,+/-1%,1/16W,G,SMD0402 | YAGEO | RC0402FR-0749K9L | G | PWA BOM | In Old BOM |
|  |  |  | 610114R00-044-G | RES,49.9KOhm,+/-1%,1/16W,G,SMD0402 | TA-I | RM04FTN4992 | G | PWA BOM | In Old BOM |
|  |  |  | 610114R00-029-G | RES,49.9KOhm,+/-1%,1/16W,G,SMD0402 | VISHAY ENTER TECHNO LOGY.INC | CRCW040249K9FKED | G | PWA BOM | In Old BOM |
| 203 | R1027 | 1 | 610115W00-017-G | RES,18KOhm,+/-1%,1/16W,G,SMD0402 | KOA SPEER ELECTRONICS, INC. | RK73H1ETTP1802F | G | PWA BOM | In New BOM |
|  |  |  | 610115W00-012-G | RES,18KOhm,+/-1%,1/16W,G,SMD0402 | WALSIN TECHNOLOGY CORPORATION | WR04X1802FTL | G | PWA BOM | In New BOM |
|  |  |  | 610115W00-011-G | RES,18KOhm,+/-1%,1/16W,G,SMD0402 | YAGEO CORPORATION COMPONENT | RC0402FR-0718KL | G | PWA BOM | In New BOM |
|  |  |  | 610115W00-044-G | RES,18KOhm,+/-1%,1/16W,G,SMD0402 | TA-I TECHNOLOGY CO., LTD | RM04FTN1802 | G | PWA BOM | In New BOM |
|  |  |  | 610115W00-024-G | RES,18KOhm,+/-1%,1/16W,G,SMD0402 | PANASONIC INDUSTRIAL CO.,LTD. | ERJ2RKF1802X | G | PWA BOM | In New BOM |
|  | R1027 | 1 | 610115W00-017-G | RES,18KOhm,+/-1%,1/16W,G,SMD0402 | KOA SPEER ELECTRONICS, INC. | RK73H1ETTP1802F | N | PWA BOM | In Old BOM |
|  |  |  | 610115W00-012-G | RES,18KOhm,+/-1%,1/16W,G,SMD0402 | WALSIN | WR04X1802FTL | G | PWA BOM | In Old BOM |
|  |  |  | 610115W00-011-G | RES,18KOhm,+/-1%,1/16W,G,SMD0402 | YAGEO | RC0402FR-0718KL | G | PWA BOM | In Old BOM |
|  |  |  | 610115W00-044-G | RES,18KOhm,+/-1%,1/16W,G,SMD0402 | TA-I | RM04FTN1802 | G | PWA BOM | In Old BOM |
|  |  |  | 610115W00-024-G | RES,18KOhm,+/-1%,1/16W,G,SMD0402 | PANASONIC INDUSTRIAL CO.,LTD. | ERJ2RKF1802X | G | PWA BOM | In Old BOM |
| 204 | R1089,R1460,R1462 | 3 | 61011GN00-017-G | RES,1.6KOhm,+/-1%,1/16W,G,SMD0402 | KOA SPEER ELECTRONICS, INC. | RK73H1ETTP1601F | G | PWA BOM | In New BOM |
|  |  |  | 61011GN00-012-G | RES,1.6KOhm,+/-1%,1/16W,G,SMD0402 | WALSIN TECHNOLOGY CORPORATION | WR04X1601FTL | G | PWA BOM | In New BOM |
|  |  |  | 61011GN00-011-G | RES,1.6KOhm,+/-1%,1/16W,G,SMD0402 | YAGEO CORPORATION COMPONENT | RC0402FR-071K6L | G | PWA BOM | In New BOM |
|  |  |  | 61011GN00-044-G | RES,1.6KOhm,+/-1%,1/16W,G,SMD0402 | TA-I TECHNOLOGY CO., LTD | RM04FTN1601 | G | PWA BOM | In New BOM |
|  | R1089,R1460,R1462 | 3 | 61011GN00-017-G | RES,1.6KOhm,+/-1%,1/16W,G,SMD0402 | KOA SPEER ELECTRONICS, INC. | RK73H1ETTP1601F | N | PWA BOM | In Old BOM |
|  |  |  | 61011GN00-012-G | RES,1.6KOhm,+/-1%,1/16W,G,SMD0402 | WALSIN | WR04X1601FTL | G | PWA BOM | In Old BOM |
|  |  |  | 61011GN00-011-G | RES,1.6KOhm,+/-1%,1/16W,G,SMD0402 | YAGEO | RC0402FR-071K6L | G | PWA BOM | In Old BOM |
|  |  |  | 61011GN00-044-G | RES,1.6KOhm,+/-1%,1/16W,G,SMD0402 | TA-I | RM04FTN1601 | G | PWA BOM | In Old BOM |
| 205 | R1091,R1094,R1095,R1096,R1097,R1098,R1102,R1104,R1105,R1106,R1108,R1109 | 12 | 610118400-017-G | RES,27 Ohm,+/-1%,1/16W,G,SMD0402 | KOA SPEER ELECTRONICS, INC. | RK73H1ETTP27R0F | G | PWA BOM | In New BOM |
|  |  |  | 610118400-012-G | RES,27 Ohm,+/-1%,1/16W,G,SMD0402 | WALSIN TECHNOLOGY CORPORATION | WR04X27R0FTL | G | PWA BOM | In New BOM |
|  |  |  | 610118400-011-G | RES,27 Ohm,+/-1%,1/16W,G,SMD0402 | YAGEO CORPORATION COMPONENT | RC0402FR-0727RL | G | PWA BOM | In New BOM |
|  |  |  | 610118400-044-G | RES,27 Ohm,+/-1%,1/16W,G,SMD0402 | TA-I TECHNOLOGY CO., LTD | RM04FTN27R0 | G | PWA BOM | In New BOM |
|  | R1091,R1094,R1095,R1096,R1097,R1098,R1102,R1104,R1105,R1106,R1108,R1109 | 12 | 610118400-017-G | RES,27 Ohm,+/-1%,1/16W,G,SMD0402 | KOA SPEER ELECTRONICS, INC. | RK73H1ETTP27R0F | N | PWA BOM | In Old BOM |
|  |  |  | 610118400-012-G | RES,27 Ohm,+/-1%,1/16W,G,SMD0402 | WALSIN | WR04X27R0FTL | G | PWA BOM | In Old BOM |
|  |  |  | 610118400-011-G | RES,27 Ohm,+/-1%,1/16W,G,SMD0402 | YAGEO | RC0402FR-0727RL | G | PWA BOM | In Old BOM |
|  |  |  | 610118400-044-G | RES,27 Ohm,+/-1%,1/16W,G,SMD0402 | TA-I | RM04FTN27R0 | G | PWA BOM | In Old BOM |
| 206 | R1092,R1093,R1114,R1115 | 4 | 61100QH00-017-G | RES,510 Ohm,+/-0.1%,1/16W,G,SMD0402 | KOA SPEER ELECTRONICS, INC. | RN731ETTP5100B25 | G | PWA BOM | In New BOM |
|  |  |  | 61100QH00-012-G | RES,510 Ohm,+/-0.1%,1/16W,G,SMD0402 | WALSIN TECHNOLOGY CORPORATION | WF04U5100BTL | G | PWA BOM | In New BOM |
|  |  |  | 61100QH00-011-G | RES,510 Ohm,+/-0.1%,1/16W,G,SMD0402 | YAGEO CORPORATION COMPONENT | RT0402BRD07510RL | G | PWA BOM | In New BOM |
|  |  |  | 61100QH00-044-G | RES,510 Ohm,+/-0.1%,1/16W,G,SMD0402 | TA-I TECHNOLOGY CO., LTD | RB04BTP5100 | G | PWA BOM | In New BOM |
|  | R1092,R1093,R1114,R1115 | 4 | 61100QH00-017-G | RES,510 Ohm,+/-0.1%,1/16W,G,SMD0402 | KOA SPEER ELECTRONICS, INC. | RN731ETTP5100B25 | Y | PWA BOM | In Old BOM |
|  |  |  | 61100QH00-012-G | RES,510 Ohm,+/-0.1%,1/16W,G,SMD0402 | WALSIN | WF04U5100BTL | G | PWA BOM | In Old BOM |
|  |  |  | 61100QH00-011-G | RES,510 Ohm,+/-0.1%,1/16W,G,SMD0402 | YAGEO | RT0402BRD07510RL | G | PWA BOM | In Old BOM |
|  |  |  | 61100QH00-044-G | RES,510 Ohm,+/-0.1%,1/16W,G,SMD0402 | TA-I | RB04BTP5100 | G | PWA BOM | In Old BOM |
| 207 | R1147 | 1 | 610112800-017-G | RES,6.04KOhm,+/-1%,1/16W,G,SMD0402 | KOA SPEER ELECTRONICS, INC. | RK73H1ETTP6041F | G | PWA BOM | In New BOM |
|  |  |  | 610112800-012-G | RES,6.04KOhm,+/-1%,1/16W,G,SMD0402 | WALSIN TECHNOLOGY CORPORATION | WR04X6041FTL | G | PWA BOM | In New BOM |
|  |  |  | 610112800-011-G | RES,6.04KOhm,+/-1%,1/16W,G,SMD0402 | YAGEO CORPORATION COMPONENT | RC0402FR-076K04L | G | PWA BOM | In New BOM |
|  |  |  | 610112800-044-G | RES,6.04KOhm,+/-1%,1/16W,G,SMD0402 | TA-I TECHNOLOGY CO., LTD | RM04FTN6041 | G | PWA BOM | In New BOM |
|  |  |  | 610112800-029-G | RES,6.04KOhm,+/-1%,1/16W,G,SMD0402 | VISHAY ENTER TECHNO LOGY.INC | CRCW04026K04FKED | G | PWA BOM | In New BOM |
|  | R1147 | 1 | 610112800-017-G | RES,6.04KOhm,+/-1%,1/16W,G,SMD0402 | KOA SPEER ELECTRONICS, INC. | RK73H1ETTP6041F | N | PWA BOM | In Old BOM |
|  |  |  | 610112800-012-G | RES,6.04KOhm,+/-1%,1/16W,G,SMD0402 | WALSIN | WR04X6041FTL | G | PWA BOM | In Old BOM |
|  |  |  | 610112800-011-G | RES,6.04KOhm,+/-1%,1/16W,G,SMD0402 | YAGEO | RC0402FR-076K04L | G | PWA BOM | In Old BOM |
|  |  |  | 610112800-044-G | RES,6.04KOhm,+/-1%,1/16W,G,SMD0402 | TA-I | RM04FTN6041 | G | PWA BOM | In Old BOM |
|  |  |  | 610112800-029-G | RES,6.04KOhm,+/-1%,1/16W,G,SMD0402 | VISHAY ENTER TECHNO LOGY.INC | CRCW04026K04FKED | G | PWA BOM | In Old BOM |
| 208 | R1255 | 1 | 61100FR00-017-G | RES,13KOhm,+/-1%,1/16W,G,SMD0402 | KOA SPEER ELECTRONICS, INC. | RN731ETTP1302F25 | G | PWA BOM | In New BOM |
|  |  |  | 61100FR00-044-G | RES,13KOhm,+/-1%,1/16W,G,SMD0402 | TA-I TECHNOLOGY CO., LTD | RB04FTP1302 | G | PWA BOM | In New BOM |
|  | R1255 | 1 | 61100FR00-017-G | RES,13KOhm,+/-1%,1/16W,G,SMD0402 | KOA SPEER ELECTRONICS, INC. | RN731ETTP1302F25 |  | PWA BOM | In Old BOM |
|  |  |  | 61100FR00-044-G | RES,13KOhm,+/-1%,1/16W,G,SMD0402 | TA-I | RB04FTP1302 | G | PWA BOM | In Old BOM |
| 209 | R1262 | 1 | 61100BK00-017-G | RES,47KOhm,+/-1%,1/16W,G,SMD0402 | KOA SPEER ELECTRONICS, INC. | RN731ETTP4702F25 | G | PWA BOM | In New BOM |
|  |  |  | 61100BK00-012-G | RES,47KOhm,+/-1%,1/16W,G,SMD0402 | WALSIN TECHNOLOGY CORPORATION | WF04U4702FTL | G | PWA BOM | In New BOM |
|  |  |  | 61100BK00-011-G | RES,47KOhm,+/-1%,1/16W,G,SMD0402 | YAGEO CORPORATION COMPONENT | RT0402FRD0747KL | G | PWA BOM | In New BOM |
|  |  |  | 61100BK00-044-G | RES,47KOhm,+/-1%,1/16W,G,SMD0402 | TA-I TECHNOLOGY CO., LTD | RB04FTP4702 | G | PWA BOM | In New BOM |
|  | R1262 | 1 | 61100BK00-017-G | RES,47KOhm,+/-1%,1/16W,G,SMD0402 | KOA SPEER ELECTRONICS, INC. | RN731ETTP4702F25 |  | PWA BOM | In Old BOM |
|  |  |  | 61100BK00-012-G | RES,47KOhm,+/-1%,1/16W,G,SMD0402 | WALSIN | WF04U4702FTL | G | PWA BOM | In Old BOM |
|  |  |  | 61100BK00-011-G | RES,47KOhm,+/-1%,1/16W,G,SMD0402 | YAGEO | RT0402FRD0747KL | G | PWA BOM | In Old BOM |
|  |  |  | 61100BK00-044-G | RES,47KOhm,+/-1%,1/16W,G,SMD0402 | TA-I | RB04FTP4702 | G | PWA BOM | In Old BOM |
| 210 | R1280 | 1 | 610112N00-017-G | RES,130 Ohm,+/-1%,1/16W,G,SMD0402 | KOA SPEER ELECTRONICS, INC. | RK73H1ETTP1300F | G | PWA BOM | In New BOM |
|  |  |  | 610112N00-012-G | RES,130 Ohm,+/-1%,1/16W,G,SMD0402 | WALSIN TECHNOLOGY CORPORATION | WR04X1300FTL | G | PWA BOM | In New BOM |
|  |  |  | 610112N00-011-G | RES,130 Ohm,+/-1%,1/16W,G,SMD0402 | YAGEO CORPORATION COMPONENT | RC0402FR-07130RL | G | PWA BOM | In New BOM |
|  |  |  | 610112N00-044-G | RES,130 Ohm,+/-1%,1/16W,G,SMD0402 | TA-I TECHNOLOGY CO., LTD | RM04FTN1300 | G | PWA BOM | In New BOM |
|  |  |  | 610112N00-029-G | RES,130 Ohm,+/-1%,1/16W,G,SMD0402 | VISHAY ENTER TECHNO LOGY.INC | CRCW0402130RFKED | G | PWA BOM | In New BOM |
|  |  |  | 610112N00-024-G | RES,130 Ohm,+/-1%,1/16W,G,SMD0402 | PANASONIC INDUSTRIAL CO.,LTD. | ERJ2RKF1300X | G | PWA BOM | In New BOM |
|  | R1280 | 1 | 610112N00-017-G | RES,130 Ohm,+/-1%,1/16W,G,SMD0402 | KOA SPEER ELECTRONICS, INC. | RK73H1ETTP1300F | N | PWA BOM | In Old BOM |
|  |  |  | 610112N00-012-G | RES,130 Ohm,+/-1%,1/16W,G,SMD0402 | WALSIN | WR04X1300FTL | G | PWA BOM | In Old BOM |
|  |  |  | 610112N00-011-G | RES,130 Ohm,+/-1%,1/16W,G,SMD0402 | YAGEO | RC0402FR-07130RL | G | PWA BOM | In Old BOM |
|  |  |  | 610112N00-044-G | RES,130 Ohm,+/-1%,1/16W,G,SMD0402 | TA-I | RM04FTN1300 | G | PWA BOM | In Old BOM |
|  |  |  | 610112N00-029-G | RES,130 Ohm,+/-1%,1/16W,G,SMD0402 | VISHAY ENTER TECHNO LOGY.INC | CRCW0402130RFKED | G | PWA BOM | In Old BOM |
|  |  |  | 610112N00-024-G | RES,130 Ohm,+/-1%,1/16W,G,SMD0402 | PANASONIC INDUSTRIAL CO.,LTD. | ERJ2RKF1300X | G | PWA BOM | In Old BOM |
| 211 | R1288 | 1 | 61011CB00-017-G | RES,64.9 Ohm,+/-1%,1/16W,G,SMD0402 | KOA SPEER ELECTRONICS, INC. | RK73H1ETTP64R9F | G | PWA BOM | In New BOM |
|  |  |  | 61011CB00-012-G | RES,64.9 Ohm,+/-1%,1/16W,G,SMD0402 | WALSIN TECHNOLOGY CORPORATION | WR04X64R9FTL | G | PWA BOM | In New BOM |
|  |  |  | 61011CB00-011-G | RES,64.9 Ohm,+/-1%,1/16W,G,SMD0402 | YAGEO CORPORATION COMPONENT | RC0402FR-0764R9L | G | PWA BOM | In New BOM |
|  |  |  | 61011CB00-044-G | RES,64.9 Ohm,+/-1%,1/16W,G,SMD0402 | TA-I TECHNOLOGY CO., LTD | RM04FTN64R9 | G | PWA BOM | In New BOM |
|  | R1288 | 1 | 61011CB00-017-G | RES,64.9 Ohm,+/-1%,1/16W,G,SMD0402 | KOA SPEER ELECTRONICS, INC. | RK73H1ETTP64R9F | N | PWA BOM | In Old BOM |
|  |  |  | 61011CB00-012-G | RES,64.9 Ohm,+/-1%,1/16W,G,SMD0402 | WALSIN | WR04X64R9FTL | G | PWA BOM | In Old BOM |
|  |  |  | 61011CB00-011-G | RES,64.9 Ohm,+/-1%,1/16W,G,SMD0402 | YAGEO | RC0402FR-0764R9L | G | PWA BOM | In Old BOM |
|  |  |  | 61011CB00-044-G | RES,64.9 Ohm,+/-1%,1/16W,G,SMD0402 | TA-I | RM04FTN64R9 | G | PWA BOM | In Old BOM |
| 212 | R1298 | 1 | 61010AC00-017-G | RES,2.2 Ohm,+/-1%,1/10W,G,SMD0603 | KOA SPEER ELECTRONICS, INC. | RK73H1JTTD2R20F | G | PWA BOM | In New BOM |
|  |  |  | 61010AC00-012-G | RES,2.2 Ohm,+/-1%,1/10W,G,SMD0603 | WALSIN TECHNOLOGY CORPORATION | WR06W2R20FTL | G | PWA BOM | In New BOM |
|  |  |  | 61010AC00-011-G | RES,2.2 Ohm,+/-1%,1/10W,G,SMD0603 | YAGEO CORPORATION COMPONENT | RC0603FR-072R2L | G | PWA BOM | In New BOM |
|  |  |  | 61010AC00-044-G | RES,2.2 Ohm,+/-1%,1/10W,G,SMD0603 | TA-I TECHNOLOGY CO., LTD | RM06FTN2R20 | G | PWA BOM | In New BOM |
|  |  |  | 61010AC00-024-G | RES,2.2 Ohm,+/-1%,1/10W,G,SMD0603 | PANASONIC INDUSTRIAL CO.,LTD. | ERJ3RQF2R2V | G | PWA BOM | In New BOM |
|  | R1298 | 1 | 61010AC00-017-G | RES,2.2 Ohm,+/-1%,1/10W,G,SMD0603 | KOA SPEER ELECTRONICS, INC. | RK73H1JTTD2R20F | N | PWA BOM | In Old BOM |
|  |  |  | 61010AC00-012-G | RES,2.2 Ohm,+/-1%,1/10W,G,SMD0603 | WALSIN | WR06W2R20FTL | G | PWA BOM | In Old BOM |
|  |  |  | 61010AC00-011-G | RES,2.2 Ohm,+/-1%,1/10W,G,SMD0603 | YAGEO | RC0603FR-072R2L | G | PWA BOM | In Old BOM |
|  |  |  | 61010AC00-044-G | RES,2.2 Ohm,+/-1%,1/10W,G,SMD0603 | TA-I | RM06FTN2R20 | G | PWA BOM | In Old BOM |
|  |  |  | 61010AC00-024-G | RES,2.2 Ohm,+/-1%,1/10W,G,SMD0603 | PANASONIC INDUSTRIAL CO.,LTD. | ERJ3RQF2R2V | G | PWA BOM | In Old BOM |
| 213 | R1303,R1304,R1305,R1308,R1310,R1311,R1312,R1313 | 8 | 61100AH00-017-G | RES,10KOhm,+/-0.5%,1/16W,G,SMD0402 | KOA SPEER ELECTRONICS, INC. | RN731ETTP1002D25 | G | PWA BOM | In New BOM |
|  |  |  | 61100AH00-012-G | RES,10KOhm,+/-0.5%,1/16W,G,SMD0402 | WALSIN TECHNOLOGY CORPORATION | WF04U1002DTL | G | PWA BOM | In New BOM |
|  |  |  | 61100AH00-011-G | RES,10KOhm,+/-0.5%,1/16W,G,SMD0402 | YAGEO CORPORATION COMPONENT | RT0402DRE0710KL | G | PWA BOM | In New BOM |
|  |  |  | 61100AH00-044-G | RES,10KOhm,+/-0.5%,1/16W,G,SMD0402 | TA-I TECHNOLOGY CO., LTD | RB04DTP1002 | G | PWA BOM | In New BOM |
|  | R1303,R1304,R1305,R1308,R1310,R1311,R1312,R1313 | 8 | 61100AH00-017-G | RES,10KOhm,+/-0.5%,1/16W,G,SMD0402 | KOA SPEER ELECTRONICS, INC. | RN731ETTP1002D25 | Y | PWA BOM | In Old BOM |
|  |  |  | 61100AH00-012-G | RES,10KOhm,+/-0.5%,1/16W,G,SMD0402 | WALSIN | WF04U1002DTL | G | PWA BOM | In Old BOM |
|  |  |  | 61100AH00-011-G | RES,10KOhm,+/-0.5%,1/16W,G,SMD0402 | YAGEO | RT0402DRE0710KL | G | PWA BOM | In Old BOM |
|  |  |  | 61100AH00-044-G | RES,10KOhm,+/-0.5%,1/16W,G,SMD0402 | TA-I | RB04DTP1002 | G | PWA BOM | In Old BOM |
| 214 | R1331,R1332 | 2 | 610115N00-017-G | RES,2.4KOhm,+/-1%,1/16W,G,SMD0402 | KOA SPEER ELECTRONICS, INC. | RK73H1ETTP2401F | G | PWA BOM | In New BOM |
|  |  |  | 610115N00-012-G | RES,2.4KOhm,+/-1%,1/16W,G,SMD0402 | WALSIN TECHNOLOGY CORPORATION | WR04X2401FTL | G | PWA BOM | In New BOM |
|  |  |  | 610115N00-011-G | RES,2.4KOhm,+/-1%,1/16W,G,SMD0402 | YAGEO CORPORATION COMPONENT | RC0402FR-072K4L | G | PWA BOM | In New BOM |
|  |  |  | 610115N00-044-G | RES,2.4KOhm,+/-1%,1/16W,G,SMD0402 | TA-I TECHNOLOGY CO., LTD | RM04FTN2401 | G | PWA BOM | In New BOM |
|  | R1331,R1332 | 2 | 610115N00-017-G | RES,2.4KOhm,+/-1%,1/16W,G,SMD0402 | KOA SPEER ELECTRONICS, INC. | RK73H1ETTP2401F | N | PWA BOM | In Old BOM |
|  |  |  | 610115N00-012-G | RES,2.4KOhm,+/-1%,1/16W,G,SMD0402 | WALSIN | WR04X2401FTL | G | PWA BOM | In Old BOM |
|  |  |  | 610115N00-011-G | RES,2.4KOhm,+/-1%,1/16W,G,SMD0402 | YAGEO | RC0402FR-072K4L | G | PWA BOM | In Old BOM |
|  |  |  | 610115N00-044-G | RES,2.4KOhm,+/-1%,1/16W,G,SMD0402 | TA-I | RM04FTN2401 | G | PWA BOM | In Old BOM |
| 215 | R1393,R1394 | 2 | 61011BW00-017-G | RES,1.2KOhm,+/-1%,1/16W,G,SMD0402 | KOA SPEER ELECTRONICS, INC. | RK73H1ETTP1201F | G | PWA BOM | In New BOM |
|  |  |  | 61011BW00-012-G | RES,1.2KOhm,+/-1%,1/16W,G,SMD0402 | WALSIN TECHNOLOGY CORPORATION | WR04X1201FTL | G | PWA BOM | In New BOM |
|  |  |  | 61011BW00-011-G | RES,1.2KOhm,+/-1%,1/16W,G,SMD0402 | YAGEO CORPORATION COMPONENT | RC0402FR-071K2L | G | PWA BOM | In New BOM |
|  |  |  | 61011BW00-044-G | RES,1.2KOhm,+/-1%,1/16W,G,SMD0402 | TA-I TECHNOLOGY CO., LTD | RM04FTN1201 | G | PWA BOM | In New BOM |
|  | R1393,R1394 | 2 | 61011BW00-017-G | RES,1.2KOhm,+/-1%,1/16W,G,SMD0402 | KOA SPEER ELECTRONICS, INC. | RK73H1ETTP1201F | N | PWA BOM | In Old BOM |
|  |  |  | 61011BW00-012-G | RES,1.2KOhm,+/-1%,1/16W,G,SMD0402 | WALSIN | WR04X1201FTL | G | PWA BOM | In Old BOM |
|  |  |  | 61011BW00-011-G | RES,1.2KOhm,+/-1%,1/16W,G,SMD0402 | YAGEO | RC0402FR-071K2L | G | PWA BOM | In Old BOM |
|  |  |  | 61011BW00-044-G | RES,1.2KOhm,+/-1%,1/16W,G,SMD0402 | TA-I | RM04FTN1201 | G | PWA BOM | In Old BOM |
| 216 | R1395,R1398 | 2 | 610103300-017-G | RES,100KOhm,+/-5%,1/16W,G,SMD0402 | KOA SPEER ELECTRONICS, INC. | RK73B1ETTP104J | G | PWA BOM | In New BOM |
|  |  |  | 610103300-012-G | RES,100KOhm,+/-5%,1/16W,G,SMD0402 | WALSIN TECHNOLOGY CORPORATION | WR04X104JTL | G | PWA BOM | In New BOM |
|  |  |  | 610103300-011-G | RES,100KOhm,+/-5%,1/16W,G,SMD0402 | YAGEO CORPORATION COMPONENT | RC0402JR-07100KL | G | PWA BOM | In New BOM |
|  |  |  | 610103300-044-G | RES,100KOhm,+/-5%,1/16W,G,SMD0402 | TA-I TECHNOLOGY CO., LTD | RM04JTN104 | G | PWA BOM | In New BOM |
|  |  |  | 610103300-029-G | RES,100KOhm,+/-5%,1/16W,G,SMD0402 | VISHAY ENTER TECHNO LOGY.INC | CRCW0402100KJNED | G | PWA BOM | In New BOM |
|  | R1395,R1398 | 2 | 610103300-017-G | RES,100KOhm,+/-5%,1/16W,G,SMD0402 | KOA SPEER ELECTRONICS, INC. | RK73B1ETTP104J | N | PWA BOM | In Old BOM |
|  |  |  | 610103300-012-G | RES,100KOhm,+/-5%,1/16W,G,SMD0402 | WALSIN | WR04X104JTL | G | PWA BOM | In Old BOM |
|  |  |  | 610103300-011-G | RES,100KOhm,+/-5%,1/16W,G,SMD0402 | YAGEO | RC0402JR-07100KL | G | PWA BOM | In Old BOM |
|  |  |  | 610103300-044-G | RES,100KOhm,+/-5%,1/16W,G,SMD0402 | TA-I | RM04JTN104 | G | PWA BOM | In Old BOM |
|  |  |  | 610103300-029-G | RES,100KOhm,+/-5%,1/16W,G,SMD0402 | VISHAY ENTER TECHNO LOGY.INC | CRCW0402100KJNED | G | PWA BOM | In Old BOM |
| 217 | R1480 | 1 | 61012LR00-017-G | RES,1KOhm,+/-0.5%,1/16W,G,SMD0402 | KOA SPEER ELECTRONICS, INC. | RK73H1ETTP1001D | G | PWA BOM | In New BOM |
|  |  |  | 61012LR00-012-G | RES,1KOhm,+/-0.5%,1/16W,G,SMD0402 | WALSIN TECHNOLOGY CORPORATION | WF04H1001DTL | G | PWA BOM | In New BOM |
|  |  |  | 61012LR00-011-G | RES,1KOhm,+/-0.5%,1/16W,G,SMD0402 | YAGEO CORPORATION COMPONENT | RC0402DR-071KL | G | PWA BOM | In New BOM |
|  |  |  | 61012LR00-044-G | RES,1KOhm,+/-0.5%,1/16W,G,SMD0402 | TA-I TECHNOLOGY CO., LTD | RM04DTN1001 | G | PWA BOM | In New BOM |
|  | R1480 | 1 | 61012LR00-017-G | RES,1KOhm,+/-0.5%,1/16W,G,SMD0402 | KOA SPEER ELECTRONICS, INC. | RK73H1ETTP1001D | N | PWA BOM | In Old BOM |
|  |  |  | 61012LR00-012-G | RES,1KOhm,+/-0.5%,1/16W,G,SMD0402 | WALSIN | WF04H1001DTL | G | PWA BOM | In Old BOM |
|  |  |  | 61012LR00-011-G | RES,1KOhm,+/-0.5%,1/16W,G,SMD0402 | YAGEO | RC0402DR-071KL | G | PWA BOM | In Old BOM |
|  |  |  | 61012LR00-044-G | RES,1KOhm,+/-0.5%,1/16W,G,SMD0402 | TA-I | RM04DTN1001 | G | PWA BOM | In Old BOM |
| 218 | R1488 | 1 | 61100LQ00-017-G | RES,20KOhm,+/-1%,1/16W,G,SMD0402 | KOA SPEER ELECTRONICS, INC. | RN731ETTP2002F50 | G | PWA BOM | In New BOM |
|  |  |  | 61100LQ00-012-G | RES,20KOhm,+/-1%,1/16W,G,SMD0402 | WALSIN TECHNOLOGY CORPORATION | WF04T2002FTL | G | PWA BOM | In New BOM |
|  |  |  | 61100LQ00-011-G | RES,20KOhm,+/-1%,1/16W,G,SMD0402 | YAGEO CORPORATION COMPONENT | RT0402FRE0720KL | G | PWA BOM | In New BOM |
|  |  |  | 61100LQ00-044-G | RES,20KOhm,+/-1%,1/16W,G,SMD0402 | TA-I TECHNOLOGY CO., LTD | RB04FTS2002 | G | PWA BOM | In New BOM |
|  | R1488 | 1 | 61100LQ00-017-G | RES,20KOhm,+/-1%,1/16W,G,SMD0402 | KOA SPEER ELECTRONICS, INC. | RN731ETTP2002F50 |  | PWA BOM | In Old BOM |
|  |  |  | 61100LQ00-012-G | RES,20KOhm,+/-1%,1/16W,G,SMD0402 | WALSIN | WF04T2002FTL | G | PWA BOM | In Old BOM |
|  |  |  | 61100LQ00-011-G | RES,20KOhm,+/-1%,1/16W,G,SMD0402 | YAGEO | RT0402FRE0720KL | G | PWA BOM | In Old BOM |
|  |  |  | 61100LQ00-044-G | RES,20KOhm,+/-1%,1/16W,G,SMD0402 | TA-I | RB04FTS2002 | G | PWA BOM | In Old BOM |
| 219 | R1493,R1847 | 2 | 61011LF00-017-G | RES,499KOhm,+/-1%,1/16W,G,SMD0402 | KOA SPEER ELECTRONICS, INC. | RK73H1ETTP4993F | G | PWA BOM | In New BOM |
|  |  |  | 61011LF00-012-G | RES,499KOhm,+/-1%,1/16W,G,SMD0402 | WALSIN TECHNOLOGY CORPORATION | WR04X4993FTL | G | PWA BOM | In New BOM |
|  |  |  | 61011LF00-011-G | RES,499KOhm,+/-1%,1/16W,G,SMD0402 | YAGEO CORPORATION COMPONENT | RC0402FR-07499KL | G | PWA BOM | In New BOM |
|  |  |  | 61011LF00-044-G | RES,499KOhm,+/-1%,1/16W,G,SMD0402 | TA-I TECHNOLOGY CO., LTD | RM04FTN4993 | G | PWA BOM | In New BOM |
|  | R1493,R1847 | 2 | 61011LF00-017-G | RES,499KOhm,+/-1%,1/16W,G,SMD0402 | KOA SPEER ELECTRONICS, INC. | RK73H1ETTP4993F | N | PWA BOM | In Old BOM |
|  |  |  | 61011LF00-012-G | RES,499KOhm,+/-1%,1/16W,G,SMD0402 | WALSIN | WR04X4993FTL | G | PWA BOM | In Old BOM |
|  |  |  | 61011LF00-011-G | RES,499KOhm,+/-1%,1/16W,G,SMD0402 | YAGEO | RC0402FR-07499KL | G | PWA BOM | In Old BOM |
|  |  |  | 61011LF00-044-G | RES,499KOhm,+/-1%,1/16W,G,SMD0402 | TA-I | RM04FTN4993 | G | PWA BOM | In Old BOM |
| 220 | R1754 | 1 | 61011HC00-017-G | RES,2.7KOhm,+/-1%,1/16W,G,SMD0402 | KOA SPEER ELECTRONICS, INC. | RK73H1ETTP2701F | G | PWA BOM | In New BOM |
|  |  |  | 61011HC00-012-G | RES,2.7KOhm,+/-1%,1/16W,G,SMD0402 | WALSIN TECHNOLOGY CORPORATION | WR04X2701FTL | G | PWA BOM | In New BOM |
|  |  |  | 61011HC00-011-G | RES,2.7KOhm,+/-1%,1/16W,G,SMD0402 | YAGEO CORPORATION COMPONENT | RC0402FR-072K7L | G | PWA BOM | In New BOM |
|  |  |  | 61011HC00-044-G | RES,2.7KOhm,+/-1%,1/16W,G,SMD0402 | TA-I TECHNOLOGY CO., LTD | RM04FTN2701 | G | PWA BOM | In New BOM |
|  |  |  | 61011HC00-029-G | RES,2.7KOhm,+/-1%,1/16W,G,SMD0402 | VISHAY ENTER TECHNO LOGY.INC | CRCW04022K70FKED | G | PWA BOM | In New BOM |
|  |  |  | 61011HC00-024-G | RES,2.7KOhm,+/-1%,1/16W,G,SMD0402 | PANASONIC INDUSTRIAL CO.,LTD. | ERJ2RKF2701X | G | PWA BOM | In New BOM |
|  | R1754 | 1 | 61011HC00-017-G | RES,2.7KOhm,+/-1%,1/16W,G,SMD0402 | KOA SPEER ELECTRONICS, INC. | RK73H1ETTP2701F | N | PWA BOM | In Old BOM |
|  |  |  | 61011HC00-012-G | RES,2.7KOhm,+/-1%,1/16W,G,SMD0402 | WALSIN | WR04X2701FTL | G | PWA BOM | In Old BOM |
|  |  |  | 61011HC00-011-G | RES,2.7KOhm,+/-1%,1/16W,G,SMD0402 | YAGEO | RC0402FR-072K7L | G | PWA BOM | In Old BOM |
|  |  |  | 61011HC00-044-G | RES,2.7KOhm,+/-1%,1/16W,G,SMD0402 | TA-I | RM04FTN2701 | G | PWA BOM | In Old BOM |
|  |  |  | 61011HC00-029-G | RES,2.7KOhm,+/-1%,1/16W,G,SMD0402 | VISHAY ENTER TECHNO LOGY.INC | CRCW04022K70FKED | G | PWA BOM | In Old BOM |
|  |  |  | 61011HC00-024-G | RES,2.7KOhm,+/-1%,1/16W,G,SMD0402 | PANASONIC INDUSTRIAL CO.,LTD. | ERJ2RKF2701X | G | PWA BOM | In Old BOM |
| 221 | R1756 | 1 | 61010KR00-017-G | RES,4.99 Ohm,+/-1%,1/10W,G,SMD0603 | KOA SPEER ELECTRONICS, INC. | RK73H1JTTD4R99F | G | PWA BOM | In New BOM |
|  |  |  | 61010KR00-011-G | RES,4.99 Ohm,+/-1%,1/10W,G,SMD0603 | YAGEO CORPORATION COMPONENT | RC0603FR-074R99L | G | PWA BOM | In New BOM |
|  |  |  | 61010KR00-044-G | RES,4.99 Ohm,+/-1%,1/10W,G,SMD0603 | TA-I TECHNOLOGY CO., LTD | RM06FTN4R99 | G | PWA BOM | In New BOM |
|  | R1756 | 1 | 61010KR00-017-G | RES,4.99 Ohm,+/-1%,1/10W,G,SMD0603 | KOA SPEER ELECTRONICS, INC. | RK73H1JTTD4R99F | N | PWA BOM | In Old BOM |
|  |  |  | 61010KR00-011-G | RES,4.99 Ohm,+/-1%,1/10W,G,SMD0603 | YAGEO | RC0603FR-074R99L | G | PWA BOM | In Old BOM |
|  |  |  | 61010KR00-044-G | RES,4.99 Ohm,+/-1%,1/10W,G,SMD0603 | TA-I | RM06FTN4R99 | G | PWA BOM | In Old BOM |
| 222 | R1838,R1839 | 2 | 610124C00-017-G | RES,57.6 Ohm,+/-1%,1/16W,G,SMD0402 | KOA SPEER ELECTRONICS, INC. | RK73H1ETTP57R6F | G | PWA BOM | In New BOM |
|  |  |  | 610124C00-012-G | RES,57.6 Ohm,+/-1%,1/16W,G,SMD0402 | WALSIN TECHNOLOGY CORPORATION | WR04X57R6FTL | G | PWA BOM | In New BOM |
|  |  |  | 610124C00-011-G | RES,57.6 Ohm,+/-1%,1/16W,G,SMD0402 | YAGEO CORPORATION COMPONENT | RC0402FR-0757R6L | G | PWA BOM | In New BOM |
|  | R1838,R1839 | 2 | 610124C00-017-G | RES,57.6 Ohm,+/-1%,1/16W,G,SMD0402 | KOA SPEER ELECTRONICS, INC. | RK73H1ETTP57R6F | N | PWA BOM | In Old BOM |
|  |  |  | 610124C00-012-G | RES,57.6 Ohm,+/-1%,1/16W,G,SMD0402 | WALSIN | WR04X57R6FTL | G | PWA BOM | In Old BOM |
|  |  |  | 610124C00-011-G | RES,57.6 Ohm,+/-1%,1/16W,G,SMD0402 | YAGEO | RC0402FR-0757R6L | G | PWA BOM | In Old BOM |
| 223 | U_TMP | 1 | 320403K00-183-G | IC,Temp Sensor,TMP75AIDR,3°C,G,SOIC-8,SMD | TEXAS INSTRUMENTS | TMP75AIDR | G | PWA BOM | In New BOM |
|  |  |  | 320404J00-190-G | IC,Temp Sensor,ADT75ARZ-REEL,1°C,G,SOIC-8,SMD | ANALOG DEVICES INC | ADT75ARZ-REEL | G | PWA BOM | In New BOM |
|  |  |  | 320403Q00-173-G | IC,Temp Sensor,DS75S+T&R,3°C,G,SO-8,SMD | MAXIM INTEGRATED PRODUCTS, INC. | DS75S+T&R | G | PWA BOM | In New BOM |
|  |  |  | 320405300-214-G | IC,Temp Sensor,STLM75M2F,±0.5°C,G,SO-8,SMD | ST MICRO ELECTRONICS,INC | STLM75M2F | G | PWA BOM | In New BOM |
|  |  |  | 32040SL00-223-G | IC,Temperature Sensor,NCT75DR2G,G,SOIC-8,SMD | ON SEMICONDUCTOR CORP | NCT75DR2G | G | PWA BOM | In New BOM |
|  |  |  | 32040FL00-031-G | IC,Temperature Sensor,LM75BD,G,SO-8,SMD | NXP SEMICONDUCTORS | LM75BD | G | PWA BOM | In New BOM |
|  | U_TMP | 1 | 320403K00-183-G | IC,Temp Sensor,TMP75AIDR,3°C,G,SOIC-8,SMD | TEXAS INSTRUMENTS | TMP75AIDR | N | PWA BOM | In Old BOM |
| 224 | U2,U11 | 2 | 31050KS00-185-G | IC,Buffer,NC7SV17P5X,0.9V~3.6V,G,SC70-5,SMD | FAIRCHILD SEMICONDUCTOR CORP | NC7SV17P5X | G | PWA BOM | In New BOM |
|  |  |  | 310507P00-031-G | Logic IC,Buffer,74AUP1G17GW,0.8V~3.6V,19ns,TSSOP,5P,G | NXP SEMICONDUCTORS | 74AUP1G17GW | G | PWA BOM | In New BOM |
|  | U2,U11 | 2 | 31050KS00-185-G | IC,Buffer,NC7SV17P5X,0.9V~3.6V,G,SC70-5,SMD | FAIRCHILD SEMICONDUCTOR CORP | NC7SV17P5X |  | PWA BOM | In Old BOM |
|  |  |  | 310507P00-031-G | Logic IC,Buffer,74AUP1G17GW,0.8V~3.6V,19ns,TSSOP,5P,G | NXP | 74AUP1G17GW | G | PWA BOM | In Old BOM |
| 225 | U17 | 1 | 420212A00-216-G | DRAM,MT40A512M16JY-083E:B,1.2V,512M*16,1.2GHz,G,FBGA-96,SMD | MICRON SEMICONDUCTOR ASIA PTE.LTD. | MT40A512M16JY-083E:B | G | PWA BOM | In New BOM |
|  |  |  | H5AN8G6NAFR-UHC | DRAM,1.2V,512M*16,1.2GHz,G,FBGA-96,SMD | HYNIX SEMICONDUCTOR INC | H5AN8G6NAFR-UHC | G | PWA BOM | In New BOM |
|  | U17 | 1 | 420212A00-216-G | DRAM,MT40A512M16JY-083E:B,1.2V,512M*16,1.2GHz,G,FBGA-96,SMD | MICRON SEMICONDUCTOR ASIA PTE.LTD. | MT40A512M16JY-083E:B |  | PWA BOM | In Old BOM |
|  |  |  | H5AN8G6NAFR-UHC | DRAM,1.2V,512M*16,1.2GHz,G,FBGA-96,SMD | Hynix | H5AN8G6NAFR-UHC | G | PWA BOM | In Old BOM |
| 226 | U20,U21 | 2 | 410512F00-233-G | Flash,MX66L51235FMI-10G,2.7V~3.6V,512M,SPI,G,SOP-16,SMD | MACRONIX INTERNATIONAL CO.,LTD. | MX66L51235FMI-10G | G | PWA BOM | In New BOM |
|  |  |  | 410513L00-216-G | Flash,SOP-16,MT25QL512ABB8ESF-0SIT | MICRON SEMICONDUCTOR ASIA PTE.LTD. | MT25QL512ABB8ESF-0SIT | G | PWA BOM | In New BOM |
|  | U20,U21 | 2 | 410512F00-233-G | Flash,MX66L51235FMI-10G,2.7V~3.6V,512M,SPI,G,SOP-16,SMD | MACRONIX INTERNATIONAL CO.,LTD. | MX66L51235FMI-10G |  | PWA BOM | In Old BOM |
| 227 | U24 | 1 | 41050DL00-233-G | Flash,MX25L6445EMI-10G,2.7~3.6V,64M,SPI,G,SOP-16,SMD | MACRONIX INTERNATIONAL CO.,LTD. | MX25L6445EMI-10G | G | PWA BOM | In New BOM |
|  |  |  | 41050DW00-396-G | Flash,S25FL064P0XMFI001,2.7~3.6V,64M,SPI,G,SO-16,SMD | SPANSION INTERNATIONAL LLC | S25FL064P0XMFI001 | G | PWA BOM | In New BOM |
|  |  |  | W25Q64JVSFIM | Flash,2.7~3.6V,64M,SPI,G,SOP-16,SMD | WINBOND | W25Q64JVSFIM |  | PWA BOM | In New BOM |
|  |  |  | 41050SF00-233-G | Flash,MX25L6435EMI-10G,2.7~3.6V,64M,SPI,G,SOP-16,SMD | MACRONIX INTERNATIONAL CO.,LTD. | MX25L6435EMI-10G | G | PWA BOM | In New BOM |
|  | U24 | 1 | 41050DL00-233-G | Flash,MX25L6445EMI-10G,2.7~3.6V,64M,SPI,G,SOP-16,SMD | MACRONIX INTERNATIONAL CO.,LTD. | MX25L6445EMI-10G | N | PWA BOM | In Old BOM |
|  |  |  | 41050SF00-233-G | Flash,MX25L6435EMI-10G,2.7~3.6V,64M,SPI,G,SOP-16,SMD | MACRONIX INTERNATIONAL CO.,LTD. | MX25L6435EMI-10G | G | PWA BOM | In Old BOM |
|  |  |  | 41050DW00-396-G | Flash,S25FL064P0XMFI001,2.7~3.6V,64M,SPI,G,SO-16,SMD | SPANSION INTERNATIONAL LLC | S25FL064P0XMFI001 | G | PWA BOM | In Old BOM |
|  |  |  | 41050P500-205-G | NOR Flash,W25Q64FVSFIG,2.7V,3V,3.6V,64M,SPI,-40_x0003_~85_x0003_,SOIC,16P,G | WINBOND | W25Q64FVSFIG | G | PWA BOM | In Old BOM |
| 228 | U29 | 1 | 21050F900-217-G | IC,IDT,2305B-1DCG8,B,G,SOIC-8,SMD | INTEGRATED DEVICE TECHNOLOGY | 2305B-1DCG8 | G | PWA BOM | In New BOM |
|  |  |  | 31050JC00-223-G | Logic IC,Buffer,NB2305AI1DR2G,3.0V~3.6V,0.35ns,SOIC,8P,G | ON SEMICONDUCTOR CORP | NB2305AI1DR2G | G | PWA BOM | In New BOM |
|  |  |  | SL2305SC-1 | IC,IDT,2305B-1DCG8,B,G,SOIC-8,SMD | Silicon Laboratories Inc. | SL2305SC-1 | G | PWA BOM | In New BOM |
|  | U29 | 1 | 21050F900-217-G | IC,IDT,2305B-1DCG8,B,G,SOIC-8,SMD | INTEGRATED DEVICE TECHNOLOGY | 2305B-1DCG8 |  | PWA BOM | In Old BOM |
|  |  |  | 31050JC00-223-G | Logic IC,Buffer,NB2305AI1DR2G,3.0V~3.6V,0.35ns,SOIC,8P,G | ON SEMICONDUCTOR CORP | NB2305AI1DR2G | G | PWA BOM | In Old BOM |
|  |  |  | SL2305SC-1 | IC,IDT,2305B-1DCG8,B,G,SOIC-8,SMD | Silicon Labs | SL2305SC-1 |  | PWA BOM | In Old BOM |
| 229 | U83,U101,U102 | 3 | 310500F00-031-G | IC,Buffer,74LVC07APW,1.65~5.5V,G,TSSOP-14,SMD | NXP SEMICONDUCTORS | 74LVC07APW | G | PWA BOM | In New BOM |
|  |  |  | 74LVC0AT14-13 | IC,Buffer,74LVC07A,1.65~5.5V,G,TSSOP-14,SMD | DIODES INCORPORATION | 74LVC0AT14-13 | G | PWA BOM | In New BOM |
|  | U83,U101,U102 | 3 | 310500F00-031-G | IC,Buffer,74LVC07APW,1.65~5.5V,G,TSSOP-14,SMD | NXP SEMICONDUCTORS | 74LVC07APW | N | PWA BOM | In Old BOM |
|  |  |  | 31050HP00-131-G | IC,Buffer,74LCX07FT,1.65V~5.5V,G,TSSOP-14,SMD | TOSHIBA ELECTRONICS ASIA LTD | 74LCX07FT | G | PWA BOM | In Old BOM |
|  |  |  | 31050BY00-183-G | IC,Buffer,74LVC07A,1.65~5.5V,G,TSSOP-14,SMD | DIODES INC | 74LVC0AT14-13 | G | PWA BOM | In Old BOM |
| 230 | U90,U91,U112 | 3 | 310201900-031-G | IC,Gate&Inverter,74LVC2G14GW,1.65~5.5V,G,SOT363-6,SMD | NXP SEMICONDUCTORS | 74LVC2G14GW | G | PWA BOM | In New BOM |
|  |  |  | 310203300-223-G | Logic IC,Trigger,NL27WZ14DFT2G,1.65V~5.5V,7.4ns,SC-70/SOT-323,6P,G | ON SEMICONDUCTOR CORP | NL27WZ14DFT2G | G | PWA BOM | In New BOM |
|  | U90,U91,U112 | 3 | 310201900-031-G | IC,Gate&Inverter,74LVC2G14GW,1.65~5.5V,G,SOT363-6,SMD | NXP SEMICONDUCTORS | 74LVC2G14GW | N | PWA BOM | In Old BOM |
|  |  |  | 31010M000-131-G | IC,Gate&Inverter,TC7PZ14FU,1.65~5.5V,G,SSOP-6,SMD | TOSHIBA ELECTRONICS ASIA LTD | TC7PZ14FU | G | PWA BOM | In Old BOM |
|  |  |  | 310203300-223-G | Logic IC,Trigger,NL27WZ14DFT2G,1.65V~5.5V,7.4ns,SC-70/SOT-323,6P,G | ON SEMICONDUCTOR CORP | NL27WZ14DFT2G | G | PWA BOM | In Old BOM |
| 231 | U98 | 1 | 410403P00-214-G | EEPROM,M24512-WMN6TP,2.5~5.5V,512K,I2C,G,SO-8,SMD | ST MICRO ELECTRONICS,INC | M24512-WMN6TP | G | PWA BOM | In New BOM |
|  |  |  | 410406K00-214-G | EEP Memory,M24512-RMN6TP,1.8V,N/A,5.5V,512K,I2C,-40_x0003_~85_x0003_,SO,8P,G | ST MICRO ELECTRONICS,INC | M24512-RMN6TP | G | PWA BOM | In New BOM |
|  |  |  | 41040D200-191-G | EEP Memory,AT24C512C-SSHM-T,1.7V,N/A,3.6V,512K,I2C,-40_x0003_~85_x0003_,SOIC,8P,G | ATMEL CORPORATION | AT24C512C-SSHM-T | G | PWA BOM | In New BOM |
|  | U98 | 1 | 410403P00-214-G | EEPROM,M24512-WMN6TP,2.5~5.5V,512K,I2C,G,SO-8,SMD | ST MICRO ELECTRONICS,INC | M24512-WMN6TP | Y | PWA BOM | In Old BOM |
|  |  |  | 410406K00-214-G | EEP Memory,M24512-RMN6TP,1.8V,N/A,5.5V,512K,I2C,-40_x0003_~85_x0003_,SO,8P,G | ST | M24512-RMN6TP | G | PWA BOM | In Old BOM |
|  |  |  | 41040D200-191-G | EEP Memory,AT24C512C-SSHM-T,1.7V,N/A,3.6V,512K,I2C,-40_x0003_~85_x0003_,SOIC,8P,G | ATMEL | AT24C512C-SSHM-T | G | PWA BOM | In Old BOM |
| 232 | X1 | 1 | 71011RD00-100-G | XTAL,25MHz,+/-25ppm,20pF,G,SMD | TXC CORPORATION | 7V25000016 | G | PWA BOM | In New BOM |
|  |  |  | 1N225000CC0DT | XTAL,25MHz,+/-25ppm,20pF,G,SMD | KDS | 1N225000CC0DT |  | PWA BOM | In New BOM |
|  |  |  | 1C225000CC0DT | XTAL,25MHz,+/-25ppm,20pF,G,SMD | KDS | 1C225000CC0DT |  | PWA BOM | In New BOM |
|  | X1 | 1 | 71011RD00-100-G | XTAL,25MHz,+/-25ppm,20pF,G,SMD | TXC CORPORATION | 7V25000016 |  | PWA BOM | In Old BOM |
| 233 | X2 | 1 | 71010SY00-107-G | XTAL,25MHz,+/-30ppm,20pF,G,SMD | DAISHINKU CORPORATION/DAISHINKU SINGAPORE PTE LTD/KDS | 1Y725000CC1G | G | PWA BOM | In New BOM |
|  |  |  | 71010V100-100-G | XTAL,25MHz,+/-30ppm,20pF,G,SMD-2P | TXC CORPORATION | 7A25000058 | G | PWA BOM | In New BOM |
|  | X2 | 1 | 71010SY00-107-G | XTAL,25MHz,+/-30ppm,20pF,G,SMD | DAISHINKU CORPORATION/DAISHINKU SINGAPORE PTE LTD/KDS | 1Y725000CC1G | N | PWA BOM | In Old BOM |
|  |  |  | 71010V100-100-G | XTAL,25MHz,+/-30ppm,20pF,G,SMD-2P | TXC | 7A25000058 | G | PWA BOM | In Old BOM |
| 234 | X3 | 1 | 710113800-100-G | XTAL,24MHz,+/-30ppm,20pF,G,SMD | TXC CORPORATION | 7B24000038 | G | PWA BOM | In New BOM |
|  | X3 | 1 | 710113800-100-G | XTAL,24MHz,+/-30ppm,20pF,G,SMD | TXC CORPORATION | 7B24000038 |  | PWA BOM | In Old BOM |
|  |  |  | 17064-X-144-3 | XTAL,17064-X-144-3 | TAITIEN ELECTRONICS CO.,LTD | 17064-X-144-3 | G | PWA BOM | In Old BOM |
| 235 | X5 | 1 | 71011UL00-107-G | XTAL,25MHz,+/-15ppm,16pF,G,SMD | DAISHINKU CORPORATION/DAISHINKU SINGAPORE PTE LTD/KDS | 1ZHY25000BB0A | G | PWA BOM | In New BOM |
|  | X5 | 1 | 71011UL00-107-G | XTAL,25MHz,+/-15ppm,16pF,G,SMD | DAISHINKU CORPORATION/DAISHINKU SINGAPORE PTE LTD/KDS | 1ZHY25000BB0A |  | PWA BOM | In Old BOM |
|  |  |  | 17064-X-099-3 | XTAL,17064-X-099-3 | TAITIEN ELECTRONICS CO.,LTD | 17064-X-099-3 | G | PWA BOM | In Old BOM |
| 236 | X6 | 1 | 710106900-162-G | XTAL,32.768KHz,+/-20ppm,12.5pF,G,SMD | EPSON ELECTRONICS AMERICA,INC. | Q13FC1350000400 | G | PWA BOM | In New BOM |
|  |  |  | 71011P300-100-G | XTAL,32.768KHz,+/-20ppm,12.5pF,G,SMD | TXC CORPORATION | 9H03200031 | G | PWA BOM | In New BOM |
|  |  |  | 710123400-061-G | XTAL,32.768KHz,+/-20ppm,12.5pF,-40℃~85℃,SMD,G | TAITIEN | 06172-W-052-3 |  | PWA BOM | In New BOM |
|  | X6 | 1 | 710106900-162-G | XTAL,32.768KHz,+/-20ppm,12.5pF,G,SMD | EPSON ELECTRONICS AMERICA,INC. | Q13FC1350000400 | N | PWA BOM | In Old BOM |
|  |  |  | 71011P300-100-G | XTAL,32.768KHz,+/-20ppm,12.5pF,G,SMD | TXC CORPORATION | 9H03200031 | G | PWA BOM | In Old BOM |
| 237 | Y1 | 1 | 71020SC00-107-G | OSC,24MHz,+/-25ppm,3.3V,15pF,G,SMD | DAISHINKU CORPORATION/DAISHINKU SINGAPORE PTE LTD/KDS | 1XSE024000AR40 | G | PWA BOM | In New BOM |
|  | Y1 | 1 | 71020SC00-107-G | OSC,24MHz,+/-25ppm,3.3V,15pF,G,SMD | DAISHINKU CORPORATION/DAISHINKU SINGAPORE PTE LTD/KDS | 1XSE024000AR40 |  | PWA BOM | In Old BOM |
|  |  |  | 71020B500-100-G | OSC,24MHz,+/-25ppm,3.3V,15pF,G,SMD | TXC CORPORATION | 7X24000014 | G | PWA BOM | In Old BOM |
| 238 | Y2 | 1 | 71020Q600-16G-G | OSC,50MHz,50ppm,3.3V,G,SMD | SiTime Corporation | SIT1602AC-23-33E-50.000000T | G | PWA BOM | In New BOM |
|  |  |  | 71012DA00-100-G | OSC,50MHz,+/-25ppm,15pF,G,SMD | TXC CORPORATION | 7X50000015 | G | PWA BOM | In New BOM |
|  |  |  | SSW050000I3CHE-ST7R2 | OSC,50MHz,+/-25ppm,15pF,G,SMD | HARMONY | SSW050000I3CHE-ST7R2 |  | PWA BOM | In New BOM |
|  | Y2 | 1 | 71020Q600-16G-G | OSC,50MHz,50ppm,3.3V,G,SMD | SiTime Corporation | SIT1602AC-23-33E-50.000000T |  | PWA BOM | In Old BOM |
|  |  |  | 71012DA00-100-G | OSC,50MHz,+/-25ppm,15pF,G,SMD | TXC CORPORATION | 7X50000015 | G | PWA BOM | In Old BOM |
| 239 | Y4 | 1 | 71020KL00-100-G | OSC,33MHz,+/-50ppm,3.3V,15pF,G,SMD | TXC CORPORATION | 7X33000013 | G | PWA BOM | In New BOM |
|  |  |  | 710211800-967-G | OSC,33MHz,+/-50ppm,3.3V,15pF,,-40℃~85℃,SMD,G | eCERA | FK3300011 | G | PWA BOM | In New BOM |
|  |  |  | SSW033000I3CH-SR5 | OSC,33MHz,+/-50ppm,3.3V,15pF,,-40℃~85℃,SMD,G | HARMONY | SSW033000I3CH-SR5 |  | PWA BOM | In New BOM |
|  | Y4 | 1 | 71020KL00-100-G | OSC,33MHz,+/-50ppm,3.3V,15pF,G,SMD | TXC CORPORATION | 7X33000013 |  | PWA BOM | In Old BOM |
|  |  |  | 710211700-16G-G | OSC,33MHz,+/-25ppm,3.3V,15pF,,-40_x0003_~85_x0003_,SMD,G | SiTime Corporation | SIT1602AI-22-33E-33.000000D | G | PWA BOM | In Old BOM |
| 240 | DIMM02,DIMM04,DIMM06,DIMM09,DIMM11,DIMM13,DIMM15,DIMM16,DIMM18,DIMM20,DIMM22,DIMM25,DIMM27,DIMM29,DIMM31,DIMM00 | 16 | 34021BC00-G78-G | CONN,DDR IV,V/T,1.2V,Blu,0.85mm,15u,G,SMD-288 | FCI CONNECTORS HONGKONG LTD. | 10140702-0302K11LF | G | PWA BOM | In New BOM |
|  |  |  | 34021CD00-600-G | Memory Connector,AH58897-T2L31-3F,DDR IV,288,SMD,THERMOPLASTIC,0.85mm,15u",Blue,G | FOXCONN TECHNOLOGY CO.,LTD. | AH58897-T2L31-3F | G | PWA BOM | In New BOM |
|  |  |  | 34021CC00-245-G | Memory Connector,DDR4288S05A1H,DDR IV,288,SMD,NYLON,0.85mm,15u",Blue,G | AMPHENOL SHANGHAI CORP. | DDR4288S05A1H | G | PWA BOM | In New BOM |
|  | DIMM02,DIMM04,DIMM06,DIMM09,DIMM11,DIMM13,DIMM15,DIMM16,DIMM18,DIMM20,DIMM22,DIMM25,DIMM27,DIMM29,DIMM31,DIMM00 | 16 | 34021BC00-G78-G | CONN,DDR IV,V/T,1.2V,Blu,0.85mm,15u,G,SMD-288 | FCI CONNECTORS HONGKONG LTD. | 10140702-0302K11LF |  | PWA BOM | In Old BOM |
|  |  |  | ADDR0245-K010C | CONN,ADDR0245-K010C | LOTES | ADDR0245-K010C |  | PWA BOM | In Old BOM |
|  |  |  | 34021CD00-600-G | Memory Connector,AH58897-T2L31-3F,DDR IV,288,SMD,THERMOPLASTIC,0.85mm,15u",Blue,G | FOXCONN | AH58897-T2L31-3F | G | PWA BOM | In Old BOM |
|  |  |  | 34021CC00-245-G | Memory Connector,DDR4288S05A1H,DDR IV,288,SMD,NYLON,0.85mm,15u",Blue,G | AMPHENOL SHANGHAI CORP. | DDR4288S05A1H | G | PWA BOM | In Old BOM |
| 241 | DIMM01,DIMM03,DIMM05,DIMM07,DIMM08,DIMM10,DIMM12,DIMM14,DIMM17,DIMM19,DIMM21,DIMM23,DIMM24,DIMM26,DIMM28,DIMM30 | 16 | 34021BD00-G78-G | CONN,DDR IV,V/T,1.2V,Bla,0.85mm,15u,G,SMD-288 | FCI CONNECTORS HONGKONG LTD. | 10140702-0301K11LF | G | PWA BOM | In New BOM |
|  |  |  | 34021CF00-600-G | Memory Connector,AH58897-T2B21-3F,DDR IV,288,SMD,THERMOPLASTIC,0.85mm,15u",Black,G | FOXCONN TECHNOLOGY CO.,LTD. | AH58897-T2B21-3F | G | PWA BOM | In New BOM |
|  |  |  | 34021CE00-245-G | Memory Connector,DDR4288S0511H,DDR IV,288,SMD,NYLON,0.85mm,15u",Black,G | AMPHENOL SHANGHAI CORP. | DDR4288S0511H | G | PWA BOM | In New BOM |
|  | DIMM01,DIMM03,DIMM05,DIMM07,DIMM08,DIMM10,DIMM12,DIMM14,DIMM17,DIMM19,DIMM21,DIMM23,DIMM24,DIMM26,DIMM28,DIMM30 | 16 | 34021BD00-G78-G | CONN,DDR IV,V/T,1.2V,Bla,0.85mm,15u,G,SMD-288 | FCI CONNECTORS HONGKONG LTD. | 10140702-0301K11LF |  | PWA BOM | In Old BOM |
|  |  |  | ADDR0245-P009C | CONN,ADDR0245-P009C | LOTES | ADDR0245-P009C |  | PWA BOM | In Old BOM |
|  |  |  | 34021CF00-600-G | Memory Connector,AH58897-T2B21-3F,DDR IV,288,SMD,THERMOPLASTIC,0.85mm,15u",Black,G | FOXCONN | AH58897-T2B21-3F | G | PWA BOM | In Old BOM |
|  |  |  | 34021CE00-245-G | Memory Connector,DDR4288S0511H,DDR IV,288,SMD,NYLON,0.85mm,15u",Black,G | AMPHENOL SHANGHAI CORP. | DDR4288S0511H | G | PWA BOM | In Old BOM |
| 242 | J_BMC_DEBUG1,J1,J3,J4,J5,J36,J41,J43,J48,J147,J149 | 11 | 34068LN00-317-G | CONN,Header,Pin Header,1X3,V/T,2.54mm,30u,G,SMD-3 | MOLEX INCORPORATED | 87898-0315 | G | PWA BOM | In New BOM |
|  |  |  | 34068HT00-245-G | CONN,Header,Pin Header,1X3,V/T,Bla,2.54mm,30u,SMD-3 | AMPHENOL SHANGHAI CORP. | G800MU305010EU |  | PWA BOM | In New BOM |
|  |  |  | 34068GU00-309-G | CONN,Header,Pin Header,1X3,V/T,Bla,2.54mm,30u,SMD-3 | SAMTEC INC. | TSM-103-01-S-SV-P-TR | 3 | PWA BOM | In New BOM |
|  | J_BMC_DEBUG1,J1,J3,J4,J5,J36,J41,J43,J48,J147,J149 | 11 | 34068LN00-317-G | CONN,Header,Pin Header,1X3,V/T,2.54mm,30u,G,SMD-3 | MOLEX INCORPORATED | 87898-0315 |  | PWA BOM | In Old BOM |
|  |  |  | 34066M800-GRT-G | CONN,Pin Header,1X3,V/T,Bla,2.54mm,30u,G,SMD-3 | PINREX TECHNOLOGY CORP. | 212-91-03SBEJ | G | PWA BOM | In Old BOM |
|  |  |  | 34068HT00-245-G | CONN,Header,Pin Header,1X3,V/T,Bla,2.54mm,30u,SMD-3 | AMPHENOL SHANGHAI CORP. | G800MU305010EU | G | PWA BOM | In Old BOM |
|  |  |  | 34068GU00-309-G | CONN,Header,Pin Header,1X3,V/T,Bla,2.54mm,30u,SMD-3 | SAMTEC INC. | TSM-103-01-S-SV-P-TR | G | PWA BOM | In Old BOM |
|  |  |  | 3406AN600-637-G | CONN,Header,Pin Header,1X3,V/T,Bla,2.54mm,30u,G,SMD-3 | LONG SHOUNG CO.,LTD. | 11003A5708 | G | PWA BOM | In Old BOM |
| 243 | J15 | 1 | 34031RP00-600-G | CONN,NGFF,R/A,Bla,0.5mm,30u,G,SMD-67 | FOXCONN TECHNOLOGY CO.,LTD. | 2E0BC23-S85BM-7H | G | PWA BOM | In New BOM |
|  |  |  | 34031T300-GRS-G | CONN,NGFF,R/A,Bla,0.5mm,30u,G,SMD-67 | LOTES CO LTD | APCI0164-P004A | G | PWA BOM | In New BOM |
|  | J15 | 1 | 34031RP00-600-G | CONN,NGFF,R/A,Bla,0.5mm,30u,G,SMD-67 | FOXCONN TECHNOLOGY CO.,LTD. | 2E0BC23-S85BM-7H |  | PWA BOM | In Old BOM |
|  |  |  | 34031T300-GRS-G | CONN,NGFF,R/A,Bla,0.5mm,30u,G,SMD-67 | LOTES | APCI0164-P004A | G | PWA BOM | In Old BOM |
| 244 | J35,J37,J39,J42,J45 | 5 | 3406AQH00-317-G | CONN,Header,Pin Header,1X6,V/T,Bla,2.54mm,G,SMD-6 | MOLEX INCORPORATED | 87898-0656 | G | PWA BOM | In New BOM |
|  |  |  | 3406A9F00-GRT-G | Header&Socket Connector,212-91-06GBE2,Pin Header,6,SMD,NY6T,2.54mm,3u",Black,G | PINREX TECHNOLOGY CORP. | 212-91-06GBE2 | G | PWA BOM | In New BOM |
|  |  |  | G800MR302032HR | Header&Socket Connector,G800MR302032EU,Pin Header,6,DIP,LCP,2.54mm,999.9999u",Black,G | AMPHENOL SHANGHAI CORP. | G800MR302032HR | G | PWA BOM | In New BOM |
|  | J35,J37,J39,J42,J45 | 5 | 3406AQH00-317-G | CONN,Header,Pin Header,1X6,V/T,Bla,2.54mm,G,SMD-6 | MOLEX INCORPORATED | 87898-0656 |  | PWA BOM | In Old BOM |
|  |  |  | 3406A9F00-GRT-G | Header&Socket Connector,212-91-06GBE2,Pin Header,6,SMD,NY6T,2.54mm,3u",Black,G | PINREX TECHNOLOGY CORP. | 212-91-06GBE2 | G | PWA BOM | In Old BOM |
|  |  |  | 3406AYA00-245-G | Header&Socket Connector,G800MR302032EU,Pin Header,6,DIP,LCP,2.54mm,999.9999u",Black,G | AMPHENOL SHANGHAI CORP. | G800MR302032EU | G | PWA BOM | In Old BOM |
| 245 | J101 | 1 | 34062MW00-309-G | CONN,Header,WTB,2X5,V/T,Bla,1.27mm,10u,G,SMD-10 | SAMTEC INC. | FTSH-105-01-L-DV-K-P-TR | G | PWA BOM | In New BOM |
|  |  |  | 3406AR700-GRT-G | Header&Socket Connector,232-9B-05SBEC,Pin Header,10,SMD,NY6T,1.27mm,10u",Black,G | PINREX TECHNOLOGY CORP. | 232-9B-05SBEC | G | PWA BOM | In New BOM |
|  | J101 | 1 | 34062MW00-309-G | CONN,Header,WTB,2X5,V/T,Bla,1.27mm,10u,G,SMD-10 | SAMTEC INC. | FTSH-105-01-L-DV-K-P-TR |  | PWA BOM | In Old BOM |
|  |  |  | 3406AR700-GRT-G | Header&Socket Connector,232-9B-05SBEC,Pin Header,10,SMD,NY6T,1.27mm,10u",Black,G | PINREX TECHNOLOGY CORP. | 232-9B-05SBEC | G | PWA BOM | In Old BOM |
|  |  |  | 3406ATS00-637-G | CONN,Header,Pin Header,2X5,V/T,Bla,1.27mm,10u,G,SMD-10 | LONG SHOUNG CO.,LTD. | 11210B5805 | G | PWA BOM | In Old BOM |
| 246 | LAN1 | 1 | 34050PV00-48U-G | CONN,Modular Jack,RJ45X2,R/A,Bla,1.27mm,50u,G,DIP-28 | TRP CONNECTOR B.V. | 1840855-5 | G | PWA BOM | In New BOM |
|  |  |  | 34051E700-609-G | CONN,Modular Jack,RJ45X2,R/A,Bla,1.27mm,50u,G,DIP-28 | U.D. Electronic Corp. | MA-FN-0003 | G | PWA BOM | In New BOM |
|  |  |  | 34050BF00-245-G | CONN,RJ45,Multi port,R/A,Bla,1.27mm,30u,G,DIP-28 | AMPHENOL | RJMG221031470NR | G | PWA BOM | In New BOM |
|  | LAN1 | 1 | 34050PV00-48U-G | CONN,Modular Jack,RJ45X2,R/A,Bla,1.27mm,50u,G,DIP-28 | TRP CONNECTOR B.V. | 1840855-5 |  | PWA BOM | In Old BOM |
|  |  |  | 34051E700-609-G | CONN,Modular Jack,RJ45X2,R/A,Bla,1.27mm,50u,G,DIP-28 | U.D. Electronic Corp. | MA-FN-0003 |  | PWA BOM | In Old BOM |
| 247 | PBAR65,PAAR65 | 2 | TLRH3APTTE20L0F | RES,20mOhm,+/-1%,2W,G,SMD2512 | KOA SPEER ELECTRONICS, INC. | TLRH3APTTE20L0F | G | PWA BOM | In New BOM |
|  |  |  | LRMAP2512-R01FT4 | RES,20mOhm,+/-1%,2W,G,SMD2512 | INTERNATIONAL RESISTIVE COMPANY, INC. | LRMAP2512-R01FT4 |  | PWA BOM | In New BOM |
|  | PBAR65,PAAR65 | 2 | TLRH3APTTE20L0F | RES,20mOhm,+/-1%,2W,G,SMD2512 | KOA SPEER ELECTRONICS, INC. | TLRH3APTTE20L0F |  | PWA BOM | In Old BOM |
| 248 | PBER65,PAFR65,PAER65,PBFR66 | 4 | SLW1TTE50L0F | RES,50mOhm,+/-1%,1.5W,G,SMD2512 | KOA SPEER ELECTRONICS, INC. | SLW1TTE50L0F | G | PWA BOM | In New BOM |
|  |  |  | LRMAP2512-R05FT4 | RES,50mOhm,+/-1%,1.5W,G,SMD2512 | INTERNATIONAL RESISTIVE COMPANY, INC. | LRMAP2512-R05FT4 |  | PWA BOM | In New BOM |
|  | PBER65,PAFR65,PAER65,PBFR66 | 4 | SLW1TTE50L0F | RES,50mOhm,+/-1%,1.5W,G,SMD2512 | KOA | SLW1TTE50L0F |  | PWA BOM | In Old BOM |
| 249 | PBMR65,PAMR65 | 2 | SLW1TTE75L0F | RES,75mOhm,+/-1%,1.5W,G,SMD2512 | KOA SPEER ELECTRONICS, INC. | SLW1TTE75L0F | G | PWA BOM | In New BOM |
|  |  |  | LRMAP2512-R075FT4 | RES,75mOhm,+/-1%,1.5W,G,SMD2512 | INTERNATIONAL RESISTIVE COMPANY, INC. | LRMAP2512-R075FT4 |  | PWA BOM | In New BOM |
|  | PBMR65,PAMR65 | 2 | SLW1TTE75L0F | RES,75mOhm,+/-1%,1.5W,G,SMD2512 | KOA | SLW1TTE75L0F |  | PWA BOM | In Old BOM |
| 250 | BAT1 | 1 | 890100800-024-G | Battery,PANASONIC,CR-2032L/BE,Lithium,3V,225mAH,G | PANASONIC INDUSTRIAL CO.,LTD. | CR-2032L/BE | G | PWA BOM | In New BOM |
|  |  |  | 6032-101-501 | Battery,6032-101-501 | Varta | 6032-101-501 | G | PWA BOM | In New BOM |
|  | BAT1 | 1 | 890100800-024-G | Battery,PANASONIC,CR-2032L/BE,Lithium,3V,225mAH,G | PANASONIC INDUSTRIAL CO.,LTD. | CR-2032L/BE | N | PWA BOM | In Old BOM |
|  |  |  | 6032-101-501 | Battery,6032-101-501 | Varta | 6032-101-501 | G | PWA BOM | In Old BOM |
| 251 | CE1,CE4,CE5,CE6,CE33,CE34 | 6 | 622202200-022-G | SPET CAP,220uF,+/-20%,10V,105℃,G,SMD2816,ESR<=40mOhm | SANYO ELECTRIC CO., LTD. | 10TPB220ML | G | PWA BOM | In New BOM |
|  |  |  | 622202201-025-G | SPET CAP,220uF,+/-20%,10V,105℃,G,SMD2816,ESR<=40mOhm | KEMET ELECTRONICS CORPORATION | T520D227M010ATE040 | G | PWA BOM | In New BOM |
|  | CE1,CE4,CE5,CE6,CE33,CE34 | 6 | 622202200-022-G | SPET CAP,220uF,+/-20%,10V,105℃,G,SMD2816,ESR<=40mOhm | SANYO ELECTRIC CO., LTD. | 10TPB220ML | N | PWA BOM | In Old BOM |
|  |  |  | 622202201-025-G | SPET CAP,220uF,+/-20%,10V,105℃,G,SMD2816,ESR<=40mOhm | KEMET ELECTRONICS CORPORATION | T520D227M010ATE040 | G | PWA BOM | In Old BOM |
| 252 | CE17,CE18,CE19,CE20 | 4 | 62120FL00-022-G | SPEA CAP,100uF,+/-20%,16V,105℃,G,SMD6.3*5.9,ESR<=24mOhm | SANYO ELECTRIC CO., LTD. | 16SVPC100M | G | PWA BOM | In New BOM |
|  |  |  | 62120CB00-025-G | ECAP,Solid Polymer Electrolytic Aluminium Capacitor (SPEA),Low ESR(LESR),100uF,+/-20%,16V,105_x0003_,25mOhm,SMD,6.3*5.7,G | KEMET ELECTRONICS CORPORATION | A765EB107M1CLAE025 | G | PWA BOM | In New BOM |
|  | CE17,CE18,CE19,CE20 | 4 | 62120FL00-022-G | SPEA CAP,100uF,+/-20%,16V,105℃,G,SMD6.3*5.9,ESR<=24mOhm | SANYO ELECTRIC CO., LTD. | 16SVPC100M |  | PWA BOM | In Old BOM |
|  |  |  | 62120CB00-025-G | ECAP,Solid Polymer Electrolytic Aluminium Capacitor (SPEA),Low ESR(LESR),100uF,+/-20%,16V,105_x0003_,25mOhm,SMD,6.3*5.7,G | KEMET ELECTRONICS CORPORATION | A765EB107M1CLAE025 | G | PWA BOM | In Old BOM |
| 253 | CE21,CE22,CE23,CE24,CE25,CE26,CE27,CE28,CE29,CE30 | 10 | 62120BE00-015-G | SP-CAP,100uF,+/-20%,16V,105℃,G,SMD2816,ESR<=12mOhm | MURATA ELEC. NORTH AMERICA | ECASD91C107M012K01 | G | PWA BOM | In New BOM |
|  | CE21,CE22,CE23,CE24,CE25,CE26,CE27,CE28,CE29,CE30 | 10 | 62120BE00-015-G | SP-CAP,100uF,+/-20%,16V,105℃,G,SMD2816,ESR<=12mOhm | MURATA ELEC. NORTH AMERICA | ECASD91C107M012K01 | Y | PWA BOM | In Old BOM |
| 254 | C36,C191,C193,C195,C197,C207,C208,C217,C218,C219,C220,C221,C222,C223,C315,C317,C319,C321,C439,C441,C443,C445,C563,C565,C567,C569,C699,C703,C704,C749,C752,C907,C909,C911,C913,C1031,C1033,C1035,C1037,C1155,C1157,C1159,C1161,C1279,C1281,C1283,C1285,C1514,C1517,C1519,C1716,C1720,C1724,C1728,C1947,C1948,C2047,C2124,C2187 | 59 | 62010P501-015-G | CAP,1nF,+/-10%,X7R,16V,G,SMD0402 | MURATA ELEC. NORTH AMERICA | GRM155R71C102KA01D | G | PWA BOM | In New BOM |
|  |  |  | 62010P500-026-G | CAP,1nF,+/-10%,X7R,16V,G,SMD0402 | SAMSUNG SEMICONDUCTOR | CL05B102KO5NNNC | G | PWA BOM | In New BOM |
|  |  |  | 62010P500-023-G | CAP,1nF,+/-10%,X7R,16V,G,SMD0402 | TAIYO ELECTRIC IND.CO.LTD | EMK105B7102KV-F | G | PWA BOM | In New BOM |
|  | C36,C191,C193,C195,C197,C207,C208,C217,C218,C219,C220,C221,C222,C223,C315,C317,C319,C321,C439,C441,C443,C445,C563,C565,C567,C569,C699,C703,C704,C749,C752,C907,C909,C911,C913,C1031,C1033,C1035,C1037,C1155,C1157,C1159,C1161,C1279,C1281,C1283,C1285,C1514,C1517,C1519,C1716,C1720,C1724,C1728,C1947,C1948,C2047,C2124,C2187 | 59 | 62010P501-015-G | CAP,1nF,+/-10%,X7R,16V,G,SMD0402 | MURATA ELEC. NORTH AMERICA | GRM155R71C102KA01D | N | PWA BOM | In Old BOM |
|  |  |  | 62010P500-026-G | CAP,1nF,+/-10%,X7R,16V,G,SMD0402 | SAMSUNG SEMICONDUCTOR | CL05B102KO5NNNC | G | PWA BOM | In Old BOM |
|  |  |  | 62010P500-023-G | CAP,1nF,+/-10%,X7R,16V,G,SMD0402 | TAIYO ELECTRIC IND.CO.LTD | EMK105B7102KV-F | G | PWA BOM | In Old BOM |
| 255 | C38,C39,C47,C78,C95,C96,C137,C141,C143,C145,C148,C150,C183,C185,C186,C188,C236,C241,C242,C243,C244,C251,C252,C253,C254,C269,C270,C271,C272,C287,C288,C289,C290,C365,C366,C367,C368,C375,C376,C377,C378,C393,C394,C395,C396,C411,C412,C413,C414,C489,C490,C491,C492,C499,C500,C501,C502,C517,C518,C519,C520,C535,C536,C537,C538,C613,C614,C615,C616,C623,C624,C625,C626,C641,C642,C643,C644,C659,C660,C661,C662,C766,C768,C786,C791,C792,C811,C847,C851,C852,C853,C854,C857,C858,C866,C902,C957,C958,C959,C960,C967,C968,C969,C970,C985,C986,C987,C988,C1003,C1004,C1005,C1006,C1081,C1082,C1083,C1084,C1091,C1092,C1093,C1094,C1109,C1110,C1111,C1112,C1127,C1128,C1129,C1130,C1205,C1206,C1207,C1208,C1215,C1216,C1217,C1218,C1233,C1234,C1235,C1236,C1251,C1252,C1253,C1254,C1329,C1330,C1331,C1332,C1339,C1340,C1341,C1342,C1357,C1358,C1359,C1360,C1375,C1376,C1377,C1378 | 160 | 62011SJ00-026-G | CAP,470nF,+/-10%,X7R,6.3V,G,SMD0402 | SAMSUNG SEMICONDUCTOR | CL05B474KQ5NNNC | G | PWA BOM | In New BOM |
|  |  |  | 62011SJ00-023-G | CAP,470nF,+/-10%,X7R,6.3V,G,SMD0402 | TAIYO ELECTRIC IND.CO.LTD | JMK105B7474KV-F | G | PWA BOM | In New BOM |
|  | C38,C39,C47,C78,C95,C96,C137,C141,C143,C145,C148,C150,C183,C185,C186,C188,C236,C241,C242,C243,C244,C251,C252,C253,C254,C269,C270,C271,C272,C287,C288,C289,C290,C365,C366,C367,C368,C375,C376,C377,C378,C393,C394,C395,C396,C411,C412,C413,C414,C489,C490,C491,C492,C499,C500,C501,C502,C517,C518,C519,C520,C535,C536,C537,C538,C613,C614,C615,C616,C623,C624,C625,C626,C641,C642,C643,C644,C659,C660,C661,C662,C766,C768,C786,C791,C792,C811,C847,C851,C852,C853,C854,C857,C858,C866,C902,C957,C958,C959,C960,C967,C968,C969,C970,C985,C986,C987,C988,C1003,C1004,C1005,C1006,C1081,C1082,C1083,C1084,C1091,C1092,C1093,C1094,C1109,C1110,C1111,C1112,C1127,C1128,C1129,C1130,C1205,C1206,C1207,C1208,C1215,C1216,C1217,C1218,C1233,C1234,C1235,C1236,C1251,C1252,C1253,C1254,C1329,C1330,C1331,C1332,C1339,C1340,C1341,C1342,C1357,C1358,C1359,C1360,C1375,C1376,C1377,C1378 | 160 | 62011SJ00-026-G | CAP,470nF,+/-10%,X7R,6.3V,G,SMD0402 | SAMSUNG SEMICONDUCTOR | CL05B474KQ5NNNC | N | PWA BOM | In Old BOM |
|  |  |  | 62011SJ00-023-G | CAP,470nF,+/-10%,X7R,6.3V,G,SMD0402 | TAIYO ELECTRIC IND.CO.LTD | JMK105B7474KV-F | G | PWA BOM | In Old BOM |
| 256 | C40,C53,C56,C62,C65,C73,C74,C147,C689,C690,C694,C764,C767,C775,C777,C787,C788,C790,C860,C2166 | 20 | 62012WD00-015-G | CAP,4.7uF,+/-20%,X6S,6.3V,G,SMD0402 | MURATA ELEC. NORTH AMERICA | GRM155C80J475MEAAD | G | PWA BOM | In New BOM |
|  |  |  | 62012WD00-023-G | CAP,4.7uF,+/-20%,X6S,6.3V,G,SMD0402 | TAIYO ELECTRIC IND.CO.LTD | JMK105BC6475MV-F | G | PWA BOM | In New BOM |
|  | C40,C53,C56,C62,C65,C73,C74,C147,C689,C690,C694,C764,C767,C775,C777,C787,C788,C790,C860,C2166 | 20 | 62012WD00-015-G | CAP,4.7uF,+/-20%,X6S,6.3V,G,SMD0402 | MURATA ELEC. NORTH AMERICA | GRM155C80J475MEAAD |  | PWA BOM | In Old BOM |
|  |  |  | 62012WD00-023-G | CAP,4.7uF,+/-20%,X6S,6.3V,G,SMD0402 | TAIYO ELECTRIC IND.CO.LTD | JMK105BC6475MV-F | G | PWA BOM | In Old BOM |
| 257 | C41,C42,C43,C44,C45,C48,C49,C50,C51,C52,C54,C55,C57,C58,C59,C61,C64,C67,C68,C71,C72,C134,C136,C146,C149,C159,C160,C169,C170,C181,C199,C200,C201,C228,C697,C754,C755,C756,C758,C759,C760,C761,C763,C765,C769,C770,C771,C772,C773,C776,C778,C779,C780,C782,C783,C784,C789,C799,C848,C849,C855,C875,C876,C885,C886,C903,C916,C917,C1475,C1482,C1483,C1500,C1501,C1505,C1506,C1507,C1508,C1509,C1510,C1512,C1572,C1573,C1574,C1575,C1578,C1579,C1580,C1581,C1582,C1583,C1586,C1587,C1588,C1589,C1590,C1591,C1593,C1594,C1595,C1599,C1602,C1605,C1650,C1748,C1833,C2072,C2074,C2076,C2143 | 109 | 62012NU00-015-G | CAP,1uF,+/-10%,X7R,6.3V,G,SMD0402 | MURATA ELEC. NORTH AMERICA | GRM155R70J105KA12D | G | PWA BOM | In New BOM |
|  |  |  | 62012NU00-026-G | CAP,1uF,+/-10%,X7R,6.3V,G,SMD0402 | SAMSUNG SEMICONDUCTOR | CL05B105KQ5NQNC | G | PWA BOM | In New BOM |
|  | C41,C42,C43,C44,C45,C48,C49,C50,C51,C52,C54,C55,C57,C58,C59,C61,C64,C67,C68,C71,C72,C134,C136,C146,C149,C159,C160,C169,C170,C181,C199,C200,C201,C228,C697,C754,C755,C756,C758,C759,C760,C761,C763,C765,C769,C770,C771,C772,C773,C776,C778,C779,C780,C782,C783,C784,C789,C799,C848,C849,C855,C875,C876,C885,C886,C903,C916,C917,C1475,C1482,C1483,C1500,C1501,C1505,C1506,C1507,C1508,C1509,C1510,C1512,C1572,C1573,C1574,C1575,C1578,C1579,C1580,C1581,C1582,C1583,C1586,C1587,C1588,C1589,C1590,C1591,C1593,C1594,C1595,C1599,C1602,C1605,C1650,C1748,C1833,C2072,C2074,C2076,C2143 | 109 | 62012NU00-015-G | CAP,1uF,+/-10%,X7R,6.3V,G,SMD0402 | MURATA ELEC. NORTH AMERICA | GRM155R70J105KA12D | N | PWA BOM | In Old BOM |
|  |  |  | 62012NU00-026-G | CAP,1uF,+/-10%,X7R,6.3V,G,SMD0402 | SAMSUNG SEMICONDUCTOR | CL05B105KQ5NQNC | G | PWA BOM | In Old BOM |
| 258 | C66,C70,C75,C76,C77,C81,C82,C97,C109,C110,C111,C112,C113,C114,C115,C116,C117,C118,C119,C120,C121,C122,C123,C124,C125,C126,C127,C128,C129,C130,C131,C132,C133,C135,C139,C140,C151,C152,C153,C154,C155,C156,C161,C162,C163,C164,C165,C166,C171,C172,C173,C174,C175,C176,C177,C178,C179,C180,C187,C203,C206,C224,C233,C235,C245,C762,C796,C797,C798,C800,C825,C826,C827,C828,C829,C830,C831,C832,C833,C834,C835,C836,C837,C838,C839,C840,C841,C842,C843,C844,C845,C846,C850,C859,C861,C862,C863,C865,C867,C868,C869,C870,C871,C872,C877,C878,C879,C880,C881,C882,C887,C888,C889,C890,C891,C892,C893,C894,C895,C896,C898,C901,C915,C1753,C1754,C1755,C1756,C1757,C1758,C1759,C1760,C1761,C1762,C1763,C1764,C1765,C1766,C1767,C1768,C1782,C1783,C1784,C1785,C1788,C1789,C1790,C1791,C1792,C1794,C1798,C1799,C1800,C1801,C1802,C1803,C1805,C1806,C1807,C1808,C1809,C1811,C1812,C1813,C1814,C1815,C1819,C1820,C1821,C1822,C1823,C1824,C1826,C1828,C1829,C1830,C1831,C1834,C1835,C1836,C1837,C1838,C1843,C1844,C1845,C1846,C1847,C1848,C1849,C1851,C1852,C1853,C1854,C1855,C1856,C1858,C1859,C1860,C1861,C1862,C1866,C1867,C1868,C1869,C1872,C1873,C1874,C1877,C1878,C1879,C1880,C1881,C1882,C1884,C1888,C1889,C1890,C1891,C1892,C1893,C1895,C1896,C1897,C1898,C1899,C1901,C1902,C1903,C1904,C1905,C1909,C1910,C1911,C1912,C1913,C1914,C1917,C1918,C1919,C1920,C1921,C1922,C1923,C1924,C1925,C1926,C1927,C1928,C1929,C1930,C1931,C1932,C1952,C1953,C1954,C1955,C1956,C1957,C1962,C1963,C1964,C1965,C1966,C1967,C1968,C1969,C1974,C1975,C1984,C1985,C1986,C1987,C1988,C1989,C1990,C1991,C1992,C1993,C1994,C1995,C1996,C1997,C1998,C1999 | 283 | 62011DF01-015-G | CAP,220nF,+/-10%,X7R,16V,G,SMD0402 | MURATA ELEC. NORTH AMERICA | GRM155R71C224K | G | PWA BOM | In New BOM |
|  |  |  | 62011DF00-026-G | CAP,220nF,+/-10%,X7R,16V,G,SMD0402 | SAMSUNG SEMICONDUCTOR | CL05B224KO5NNNC | G | PWA BOM | In New BOM |
|  |  |  | 62011DF00-023-G | CAP,220nF,+/-10%,X7R,16V,G,SMD0402 | TAIYO ELECTRIC IND.CO.LTD | EMK105B7224KV-FR | G | PWA BOM | In New BOM |
|  | C66,C70,C75,C76,C77,C81,C82,C97,C109,C110,C111,C112,C113,C114,C115,C116,C117,C118,C119,C120,C121,C122,C123,C124,C125,C126,C127,C128,C129,C130,C131,C132,C133,C135,C139,C140,C151,C152,C153,C154,C155,C156,C161,C162,C163,C164,C165,C166,C171,C172,C173,C174,C175,C176,C177,C178,C179,C180,C187,C203,C206,C224,C233,C235,C245,C762,C796,C797,C798,C800,C825,C826,C827,C828,C829,C830,C831,C832,C833,C834,C835,C836,C837,C838,C839,C840,C841,C842,C843,C844,C845,C846,C850,C859,C861,C862,C863,C865,C867,C868,C869,C870,C871,C872,C877,C878,C879,C880,C881,C882,C887,C888,C889,C890,C891,C892,C893,C894,C895,C896,C898,C901,C915,C1753,C1754,C1755,C1756,C1757,C1758,C1759,C1760,C1761,C1762,C1763,C1764,C1765,C1766,C1767,C1768,C1782,C1783,C1784,C1785,C1788,C1789,C1790,C1791,C1792,C1794,C1798,C1799,C1800,C1801,C1802,C1803,C1805,C1806,C1807,C1808,C1809,C1811,C1812,C1813,C1814,C1815,C1819,C1820,C1821,C1822,C1823,C1824,C1826,C1828,C1829,C1830,C1831,C1834,C1835,C1836,C1837,C1838,C1843,C1844,C1845,C1846,C1847,C1848,C1849,C1851,C1852,C1853,C1854,C1855,C1856,C1858,C1859,C1860,C1861,C1862,C1866,C1867,C1868,C1869,C1872,C1873,C1874,C1877,C1878,C1879,C1880,C1881,C1882,C1884,C1888,C1889,C1890,C1891,C1892,C1893,C1895,C1896,C1897,C1898,C1899,C1901,C1902,C1903,C1904,C1905,C1909,C1910,C1911,C1912,C1913,C1914,C1917,C1918,C1919,C1920,C1921,C1922,C1923,C1924,C1925,C1926,C1927,C1928,C1929,C1930,C1931,C1932,C1952,C1953,C1954,C1955,C1956,C1957,C1962,C1963,C1964,C1965,C1966,C1967,C1968,C1969,C1974,C1975,C1984,C1985,C1986,C1987,C1988,C1989,C1990,C1991,C1992,C1993,C1994,C1995,C1996,C1997,C1998,C1999 | 283 | 62011DF01-015-G | CAP,220nF,+/-10%,X7R,16V,G,SMD0402 | MURATA ELEC. NORTH AMERICA | GRM155R71C224K | N | PWA BOM | In Old BOM |
|  |  |  | 62011DF00-026-G | CAP,220nF,+/-10%,X7R,16V,G,SMD0402 | SAMSUNG SEMICONDUCTOR | CL05B224KO5NNNC | G | PWA BOM | In Old BOM |
|  |  |  | 62011DF00-023-G | CAP,220nF,+/-10%,X7R,16V,G,SMD0402 | TAIYO ELECTRIC IND.CO.LTD | EMK105B7224KV-FR | G | PWA BOM | In Old BOM |
| 259 | PSPC2,PIPC2,PFPC2,PEPC2,PSPC3,PIPC3,PFPC3,PEPC3,C158,C168,C874,C884,PSPC3000,PIPC3000,PFPC3000,PEPC3000 | 16 | 62012GF00-015-G | CAP,22uF,+/-20%,X6S,6.3V,G,SMD0603 | MURATA ELEC. NORTH AMERICA | GRM188C80J226M | G | PWA BOM | In New BOM |
|  |  |  | 62012GF00-023-G | CAP,22uF,+/-20%,X6S,6.3V,G,SMD0603 | TAIYO ELECTRIC IND.CO.LTD | JDK107BC6226MA-T | G | PWA BOM | In New BOM |
|  | PSPC2,PIPC2,PFPC2,PEPC2,PSPC3,PIPC3,PFPC3,PEPC3,C158,C168,C874,C884,PSPC3000,PIPC3000,PFPC3000,PEPC3000 | 16 | 62012GF00-015-G | CAP,22uF,+/-20%,X6S,6.3V,G,SMD0603 | MURATA ELEC. NORTH AMERICA | GRM188C80J226M |  | PWA BOM | In Old BOM |
|  |  |  | 62012GF00-023-G | CAP,22uF,+/-20%,X6S,6.3V,G,SMD0603 | TAIYO ELECTRIC IND.CO.LTD | JDK107BC6226MA-T | G | PWA BOM | In Old BOM |
| 260 | PSTC16,PFRC16,C182,C225,C273,C812,C2147,C2148,C2149,C2150,C2151 | 11 | 62012H100-015-G | CAP,10uF,+/-20%,X6S,10V,G,SMD0603 | MURATA ELEC. NORTH AMERICA | GRM188C81A106M | G | PWA BOM | In New BOM |
|  |  |  | 62012H100-023-G | CAP,10uF,+/-20%,X6S,10V,G,SMD0603 | TAIYO ELECTRIC IND.CO.LTD | LMK107BC6106MA-T | G | PWA BOM | In New BOM |
|  |  |  | 62012H100-026-G | CAP,10uF,+/-20%,X6S,10V,G,SMD0603 | SAMSUNG SEMICONDUCTOR | CL10X106MP8NRNC | G | PWA BOM | In New BOM |
|  | PSTC16,PFRC16,C182,C225,C273,C812,C2147,C2148,C2149,C2150,C2151 | 11 | 62012H100-015-G | CAP,10uF,+/-20%,X6S,10V,G,SMD0603 | MURATA ELEC. NORTH AMERICA | GRM188C81A106M |  | PWA BOM | In Old BOM |
|  |  |  | 62012H100-023-G | CAP,10uF,+/-20%,X6S,10V,G,SMD0603 | TAIYO ELECTRIC IND.CO.LTD | LMK107BC6106MA-T | G | PWA BOM | In Old BOM |
|  |  |  | 62012H100-026-G | CAP,10uF,+/-20%,X6S,10V,G,SMD0603 | SAMSUNG SEMICONDUCTOR | CL10X106MP8NRNC | G | PWA BOM | In Old BOM |
| 261 | C1424,C1427,C1451,C1455,C1459,C1464,C1466,C1468,C1470,C1499,C1533,C1577,C1585,C1596 | 14 | 620109S00-015-G | CAP,4.7uF,+/-10%,X7R,10V,G,SMD0805 | MURATA ELEC. NORTH AMERICA | GRM21BR71A475K | G | PWA BOM | In New BOM |
|  |  |  | 620109S00-023-G | CAP,4.7uF,+/-10%,X7R,10V,G,SMD0805 | TAIYO ELECTRIC IND.CO.LTD | LMK212B7475KG-T | G | PWA BOM | In New BOM |
|  |  |  | 620109S00-026-G | CAP,4.7uF,+/-10%,X7R,10V,G,SMD0805 | SAMSUNG SEMICONDUCTOR | CL21B475KPFNNNE | G | PWA BOM | In New BOM |
|  | C1424,C1427,C1451,C1455,C1459,C1464,C1466,C1468,C1470,C1499,C1533,C1577,C1585,C1596 | 14 | 620109S00-015-G | CAP,4.7uF,+/-10%,X7R,10V,G,SMD0805 | MURATA ELEC. NORTH AMERICA | GRM21BR71A475K | N | PWA BOM | In Old BOM |
|  |  |  | 620109S00-023-G | CAP,4.7uF,+/-10%,X7R,10V,G,SMD0805 | TAIYO ELECTRIC IND.CO.LTD | LMK212B7475KG-T | G | PWA BOM | In Old BOM |
|  |  |  | 620109S00-026-G | CAP,4.7uF,+/-10%,X7R,10V,G,SMD0805 | SAMSUNG SEMICONDUCTOR | CL21B475KPFNNNE | G | PWA BOM | In Old BOM |
| 262 | C1439,C1440,C1447,C1448,C1456,C1623,C1747 | 7 | 620109200-015-G | CAP,10uF,+/-10%,X7R,6.3V,G,SMD0805 | MURATA ELEC. NORTH AMERICA | GRM21BR70J106K | G | PWA BOM | In New BOM |
|  |  |  | 620109200-023-G | CAP,10uF,+/-10%,X7R,6.3V,G,SMD0805 | TAIYO ELECTRIC IND.CO.LTD | JMK212B7106KG-T | G | PWA BOM | In New BOM |
|  |  |  | 620109200-026-G | CAP,10uF,+/-10%,X7R,6.3V,G,SMD0805 | SAMSUNG SEMICONDUCTOR | CL21B106KQQNNNE | G | PWA BOM | In New BOM |
|  | C1439,C1440,C1447,C1448,C1456,C1623,C1747 | 7 | 620109200-015-G | CAP,10uF,+/-10%,X7R,6.3V,G,SMD0805 | MURATA ELEC. NORTH AMERICA | GRM21BR70J106K | N | PWA BOM | In Old BOM |
|  |  |  | 620109200-023-G | CAP,10uF,+/-10%,X7R,6.3V,G,SMD0805 | TAIYO ELECTRIC IND.CO.LTD | JMK212B7106KG-T | G | PWA BOM | In Old BOM |
|  |  |  | 620109200-026-G | CAP,10uF,+/-10%,X7R,6.3V,G,SMD0805 | SAMSUNG SEMICONDUCTOR | CL21B106KQQNNNE | G | PWA BOM | In Old BOM |
| 263 | C1476,C1477 | 2 | 62010MU00-015-G | CAP,20pF,+/-5%,NPO(C0G),50V,G,SMD0402 | MURATA ELEC. NORTH AMERICA | GRM1555C1H200J | G | PWA BOM | In New BOM |
|  | C1476,C1477 | 2 | 62010MU00-015-G | CAP,20pF,+/-5%,NPO(C0G),50V,G,SMD0402 | MURATA ELEC. NORTH AMERICA | GRM1555C1H200J | N | PWA BOM | In Old BOM |
| 264 | C1478,C1479,C1485,C1495,C1584,C1778,C1786,C1832,C1875,C1942,C2035 | 11 | 62010DW00-015-G | CAP,10uF,+/-10%,X7R,16V,G,SMD1206 | MURATA ELEC. NORTH AMERICA | GRM31CR71C106K | G | PWA BOM | In New BOM |
|  |  |  | 62010DW00-026-G | CAP,10uF,+/-10%,X7R,16V,G,SMD1206 | SAMSUNG SEMICONDUCTOR | CL31B106KOHNNNE | G | PWA BOM | In New BOM |
|  |  |  | 62010DW00-023-G | CAP,10uF,+/-10%,X7R,16V,G,SMD1206 | TAIYO ELECTRIC IND.CO.LTD | EMK316B7106KL-TD | G | PWA BOM | In New BOM |
|  | C1478,C1479,C1485,C1495,C1584,C1778,C1786,C1832,C1875,C1942,C2035 | 11 | 62010DW00-015-G | CAP,10uF,+/-10%,X7R,16V,G,SMD1206 | MURATA ELEC. NORTH AMERICA | GRM31CR71C106K | N | PWA BOM | In Old BOM |
|  |  |  | 62010DW00-026-G | CAP,10uF,+/-10%,X7R,16V,G,SMD1206 | SAMSUNG SEMICONDUCTOR | CL31B106KOHNNNE | G | PWA BOM | In Old BOM |
|  |  |  | 62010DW00-023-G | CAP,10uF,+/-10%,X7R,16V,G,SMD1206 | TAIYO ELECTRIC IND.CO.LTD | EMK316B7106KL-TD | G | PWA BOM | In Old BOM |
| 265 | C1563,C1746 | 2 | 62011D900-015-G | CAP,22uF,+/-10%,X7R,6.3V,G,SMD1206 | MURATA ELEC. NORTH AMERICA | GRM31CR70J226K | G | PWA BOM | In New BOM |
|  |  |  | 62011D900-023-G | CAP,22uF,+/-10%,X7R,6.3V,G,SMD1206 | TAIYO ELECTRIC IND.CO.LTD | JMK316B7226KL-T | G | PWA BOM | In New BOM |
|  |  |  | 62011D900-026-G | CAP,22uF,+/-10%,X7R,6.3V,G,SMD1206 | SAMSUNG SEMICONDUCTOR | CL31B226KQHNNNE | G | PWA BOM | In New BOM |
|  | C1563,C1746 | 2 | 62011D900-015-G | CAP,22uF,+/-10%,X7R,6.3V,G,SMD1206 | MURATA ELEC. NORTH AMERICA | GRM31CR70J226K | N | PWA BOM | In Old BOM |
|  |  |  | 62011D900-023-G | CAP,22uF,+/-10%,X7R,6.3V,G,SMD1206 | TAIYO ELECTRIC IND.CO.LTD | JMK316B7226KL-T | G | PWA BOM | In Old BOM |
|  |  |  | 62011D900-026-G | CAP,22uF,+/-10%,X7R,6.3V,G,SMD1206 | SAMSUNG SEMICONDUCTOR | CL31B226KQHNNNE | G | PWA BOM | In Old BOM |
| 266 | C1683,C1687,C1703,C1709,C1717,C1721,C1725,C1729 | 8 | 620109N00-015-G | CAP,2.2uF,+/-10%,X7R,10V,G,SMD0603 | MURATA ELEC. NORTH AMERICA | GRM188R71A225K | G | PWA BOM | In New BOM |
|  |  |  | 620109N00-023-G | CAP,2.2uF,+/-10%,X7R,10V,G,SMD0603 | TAIYO ELECTRIC IND.CO.LTD | LMK107B7225KA-T | G | PWA BOM | In New BOM |
|  |  |  | 620109N00-026-G | CAP,2.2uF,+/-10%,X7R,10V,G,SMD0603 | SAMSUNG SEMICONDUCTOR | CL10B225KP8NNNC | G | PWA BOM | In New BOM |
|  | C1683,C1687,C1703,C1709,C1717,C1721,C1725,C1729 | 8 | 620109N00-015-G | CAP,2.2uF,+/-10%,X7R,10V,G,SMD0603 | MURATA ELEC. NORTH AMERICA | GRM188R71A225K | N | PWA BOM | In Old BOM |
|  |  |  | 620109N00-023-G | CAP,2.2uF,+/-10%,X7R,10V,G,SMD0603 | TAIYO ELECTRIC IND.CO.LTD | LMK107B7225KA-T | G | PWA BOM | In Old BOM |
|  |  |  | 620109N00-026-G | CAP,2.2uF,+/-10%,X7R,10V,G,SMD0603 | SAMSUNG SEMICONDUCTOR | CL10B225KP8NNNC | G | PWA BOM | In Old BOM |
| 267 | C1769,C1804,C1850,C1894,C1933,C1958,C1970,C2032 | 8 | 62011HS01-015-G | CAP,10uF,+/-10%,X7R,25V,G,SMD1206 | MURATA ELEC. NORTH AMERICA | GRM31CR71E106K | G | PWA BOM | In New BOM |
|  |  |  | 62011HS00-026-G | CAP,10uF,+/-10%,X7R,25V,G,SMD1206 | SAMSUNG SEMICONDUCTOR | CL31B106KAHNNNE | G | PWA BOM | In New BOM |
|  |  |  | 62011HS00-023-G | CAP,10uF,+/-10%,X7R,25V,G,SMD1206 | TAIYO ELECTRIC IND.CO.LTD | TMK316B7106KL-TD | G | PWA BOM | In New BOM |
|  | C1769,C1804,C1850,C1894,C1933,C1958,C1970,C2032 | 8 | 62011HS01-015-G | CAP,10uF,+/-10%,X7R,25V,G,SMD1206 | MURATA ELEC. NORTH AMERICA | GRM31CR71E106K | N | PWA BOM | In Old BOM |
|  |  |  | 62011HS00-026-G | CAP,10uF,+/-10%,X7R,25V,G,SMD1206 | SAMSUNG SEMICONDUCTOR | CL31B106KAHNNNE | G | PWA BOM | In Old BOM |
|  |  |  | 62011HS00-023-G | CAP,10uF,+/-10%,X7R,25V,G,SMD1206 | TAIYO ELECTRIC IND.CO.LTD | TMK316B7106KL-TD | G | PWA BOM | In Old BOM |
| 268 | C2066 | 1 | 620110V00-015-G | CAP,1.2nF,+/-10%,X7R,50V,G,SMD0402 | MURATA ELEC. NORTH AMERICA | GRM155R71H122K | G | PWA BOM | In New BOM |
|  |  |  | 620110V00-026-G | CAP,1.2nF,+/-10%,X7R,50V,G,SMD0402 | SAMSUNG SEMICONDUCTOR | CL05B122KB5NNNC | G | PWA BOM | In New BOM |
|  |  |  | 620110V00-023-G | CAP,1.2nF,+/-10%,X7R,50V,G,SMD0402 | TAIYO ELECTRIC IND.CO.LTD | UMK105B7122KV-F | G | PWA BOM | In New BOM |
|  | C2066 | 1 | 620110V00-015-G | CAP,1.2nF,+/-10%,X7R,50V,G,SMD0402 | MURATA ELEC. NORTH AMERICA | GRM155R71H122K | N | PWA BOM | In Old BOM |
|  |  |  | 620110V00-026-G | CAP,1.2nF,+/-10%,X7R,50V,G,SMD0402 | SAMSUNG SEMICONDUCTOR | CL05B122KB5NNNC | G | PWA BOM | In Old BOM |
|  |  |  | 620110V00-023-G | CAP,1.2nF,+/-10%,X7R,50V,G,SMD0402 | TAIYO ELECTRIC IND.CO.LTD | UMK105B7122KV-F | G | PWA BOM | In Old BOM |
| 269 | C2081,C2082 | 2 | 62012TW00-015-G | CAP,470nF,+/-10%,X7R,16V,G,SMD0402 | MURATA ELEC. NORTH AMERICA | GRM155R71C474KE01D | G | PWA BOM | In New BOM |
|  | C2081,C2082 | 2 | 62012TW00-015-G | CAP,470nF,+/-10%,X7R,16V,G,SMD0402 | MURATA ELEC. NORTH AMERICA | GRM155R71C474KE01D |  | PWA BOM | In Old BOM |
| 270 | PBFC28,PBEC28,PAFC28,PAEC28,PBMC29,PBFC29,PBEC29,PBAC29,PAMC29,PAFC29,PAEC29,PAAC29,PBMC30,PBFC30,PBEC30,PBAC30,PAMC30,PAFC30,PAEC30,PAAC30,PBMC31,PBFC31,PBEC31,PBAC31,PAMC31,PAFC31,PAEC31,PAAC31,PBMC32,PBFC32,PBEC32,PBAC32,PAMC32,PAFC32,PAEC32,PAAC32,PBMC33,PBFC33,PBEC33,PBAC33,PAMC33,PAFC33,PAEC33,PAAC33,PBMC34,PBFC34,PBEC34,PBAC34,PAMC34,PAFC34,PAEC34,PAAC34,PBMC35,PBFC35,PBEC35,PBAC35,PAMC35,PAFC35,PAEC35,PAAC35,PBMC36,PBFC36,PBEC36,PBAC36,PAMC36,PAFC36,PAEC36,PAAC36,PBMC37,PBFC37,PBEC37,PBAC37,PAMC37,PAFC37,PAEC37,PAAC37,PBMC38,PBFC38,PBEC38,PBAC38,PAMC38,PAFC38,PAEC38,PAAC38,PBMC39,PBFC39,PBEC39,PBAC39,PAMC39,PAFC39,PAEC39,PAAC39,PBMC40,PBFC40,PBEC40,PBAC40,PAMC40,PAFC40,PAEC40,PAAC40,PBMC41,PBFC41,PBEC41,PBAC41,PAMC41,PAFC41,PAEC41,PAAC41,PBMC42,PBFC42,PBEC42,PBAC42,PAMC42,PAFC42,PAEC42,PAAC42,PBMC43,PBFC43,PBEC43,PBAC43,PAMC43,PAFC43,PAEC43,PAAC43,PBMC44,PBFC44,PBEC44,PBAC44,PAMC44,PAFC44,PAEC44,PAAC44,PBMC45,PBFC45,PBEC45,PBAC45,PAMC45,PAFC45,PAEC45,PAAC45,PBMC46,PBFC46,PBEC46,PBAC46,PAMC46,PAFC46,PAEC46,PAAC46,PBMC47,PBFC47,PBEC47,PBAC47,PAMC47,PAFC47,PAEC47,PAAC47,PBMC48,PBFC48,PBEC48,PBAC48,PAMC48,PAFC48,PAEC48,PAAC48,PBMC49,PBFC49,PBEC49,PBAC49,PAMC49,PAFC49,PAEC49,PAAC49,PBMC50,PBFC50,PBEC50,PBAC50,PAMC50,PAFC50,PAEC50,PAAC50,PBMC51,PBFC51,PBEC51,PBAC51,PAMC51,PAFC51,PAEC51,PAAC51,PBMC52,PBFC52,PBEC52,PBAC52,PAMC52,PAFC52,PAEC52,PAAC52,PBMC53,PBFC53,PBEC53,PBAC53,PAMC53,PAFC53,PAEC53,PAAC53,PBMC54,PBFC54,PBEC54,PBAC54,PAMC54,PAFC54,PAEC54,PAAC54,PBMC55,PBFC55,PBEC55,PBAC55,PAMC55,PAFC55,PAEC55,PAAC55,PBMC56,PBFC56,PBEC56,PBAC56,PAMC56,PAFC56,PAEC56,PAAC56,PBMC57,PBFC57,PBEC57,PBAC57,PAMC57,PAFC57,PAEC57,PAAC57,PBMC58,PBAC58,PAMC58,PAAC58,PBAC59,PAAC59,PBAC60,PAAC60,PBAC61,PAAC61,PBFC62,PBEC62,PBAC62,PAFC62,PAEC62,PAAC62,PBMC63,PBFC63,PBEC63,PBAC63,PAMC63,PAFC63,PAEC63,PAAC63,PBMC64,PBFC64,PBEC64,PBAC64,PAMC64,PAFC64,PAEC64,PAAC64,PBMC65,PBFC65,PBEC65,PBAC65,PAMC65,PAFC65,PAEC65,PAAC65,PBMC66,PBFC66,PBEC66,PBAC66,PAMC66,PAFC66,PAEC66,PAAC66,PBMC67,PBFC67,PBEC67,PBAC67,PAMC67,PAFC67,PAEC67,PAAC67,PBMC68,PBFC68,PBEC68,PBAC68,PAMC68,PAFC68,PAEC68,PAAC68,PBMC69,PBFC69,PBEC69,PBAC69,PAMC69,PAFC69,PAEC69,PAAC69,PBMC70,PBFC70,PBEC70,PBAC70,PAMC70,PAFC70,PAEC70,PAAC70,PBMC71,PBFC71,PBEC71,PBAC71,PAMC71,PAFC71,PAEC71,PAAC71,PBMC72,PBAC72,PAMC72,PAAC72,PBAC73,PAAC73,PBAC74,PAAC74,PBAC75,PAAC75,PBAC76,PAAC76,PBAC77,PAAC77,PBAC78,PAAC78,PBAC81,PAAC81,PBAC82,PAAC82,PBAC83,PAAC83,PBAC84,PAAC84,PBAC85,PAAC85,PBAC86,PAAC86,PBAC87,PAAC87,PBAC88,PAAC88,PBAC89,PAAC89,PBAC90,PAAC90,PBAC91,PAAC91,PBAC92,PAAC92,PBAC93,PAAC93,PBAC94,PAAC94,PBAC95,PAAC95,PBAC96,PAAC96,PBAC97,PAAC97,PBAC98,PAAC98,PBAC99,PAAC99,PBAC100,PAAC100,PBAC101,PAAC101,PBAC102,PAAC102,PBAC103,PAAC103,PBAC104,PAAC104,PBAC105,PAAC105,PBAC106,PAAC106,PBAC107,PAAC107,PBAC108,PAAC108,PBAC109,PAAC109,PBAC110,PAAC110,PBAC113,PAAC113,PBAC114,PAAC114,PBAC115,PAAC115,PBAC116,PAAC116,PBAC117,PAAC117,PBAC118,PAAC118,PBAC119,PAAC119,PBAC120,PAAC120,PBAC121,PAAC121,PBAC122,PAAC122,PBAC127,PAAC127,PBAC128,PAAC128,PBAC129,PAAC129,PBAC130,PAAC130,PBAC131,PAAC131,PBAC132,PAAC132,PBAC133,PAAC133,PBAC134,PAAC134,PBAC135,PAAC135,PBAC136,PAAC136,PBAC137,PAAC137,PBAC138,PAAC138,PBAC139,PAAC139,PBAC140,PAAC140,PBAC141,PAAC141,PBAC142,PAAC142,PBAC143,PAAC143,PBAC144,PAAC144,PBAC145,PAAC145,PBAC146,PAAC146,PBAC147,PAAC147,PBAC148,PAAC148,PBAC149,PAAC149,PBAC150,PAAC150,PBAC151,PAAC151,PBAC152,PAAC152,PBAC153,PAAC153,PBAC154,PAAC154,PBAC155,PAAC155,PBAC156,PAAC156,PBFC501,PBEC501,PAFC501,PAEC501,C2168,C2169,C2170,C2172,C2173,C2174,C2175,C2176,C2177,C2178,C2179 | 495 | 62012PS00-015-G | CAP,10uF,+/-20%,X6S,4V,G,SMD0402 | MURATA ELEC. NORTH AMERICA | GRM155C80G106M | G | PWA BOM | In New BOM |
|  |  |  | 62012PS00-023-G | CAP,10uF,+/-20%,X6S,4V,G,SMD0402 | TAIYO ELECTRIC IND.CO.LTD | AMK105CC6106MV-F | G | PWA BOM | In New BOM |
|  | PBFC28,PBEC28,PAFC28,PAEC28,PBMC29,PBFC29,PBEC29,PBAC29,PAMC29,PAFC29,PAEC29,PAAC29,PBMC30,PBFC30,PBEC30,PBAC30,PAMC30,PAFC30,PAEC30,PAAC30,PBMC31,PBFC31,PBEC31,PBAC31,PAMC31,PAFC31,PAEC31,PAAC31,PBMC32,PBFC32,PBEC32,PBAC32,PAMC32,PAFC32,PAEC32,PAAC32,PBMC33,PBFC33,PBEC33,PBAC33,PAMC33,PAFC33,PAEC33,PAAC33,PBMC34,PBFC34,PBEC34,PBAC34,PAMC34,PAFC34,PAEC34,PAAC34,PBMC35,PBFC35,PBEC35,PBAC35,PAMC35,PAFC35,PAEC35,PAAC35,PBMC36,PBFC36,PBEC36,PBAC36,PAMC36,PAFC36,PAEC36,PAAC36,PBMC37,PBFC37,PBEC37,PBAC37,PAMC37,PAFC37,PAEC37,PAAC37,PBMC38,PBFC38,PBEC38,PBAC38,PAMC38,PAFC38,PAEC38,PAAC38,PBMC39,PBFC39,PBEC39,PBAC39,PAMC39,PAFC39,PAEC39,PAAC39,PBMC40,PBFC40,PBEC40,PBAC40,PAMC40,PAFC40,PAEC40,PAAC40,PBMC41,PBFC41,PBEC41,PBAC41,PAMC41,PAFC41,PAEC41,PAAC41,PBMC42,PBFC42,PBEC42,PBAC42,PAMC42,PAFC42,PAEC42,PAAC42,PBMC43,PBFC43,PBEC43,PBAC43,PAMC43,PAFC43,PAEC43,PAAC43,PBMC44,PBFC44,PBEC44,PBAC44,PAMC44,PAFC44,PAEC44,PAAC44,PBMC45,PBFC45,PBEC45,PBAC45,PAMC45,PAFC45,PAEC45,PAAC45,PBMC46,PBFC46,PBEC46,PBAC46,PAMC46,PAFC46,PAEC46,PAAC46,PBMC47,PBFC47,PBEC47,PBAC47,PAMC47,PAFC47,PAEC47,PAAC47,PBMC48,PBFC48,PBEC48,PBAC48,PAMC48,PAFC48,PAEC48,PAAC48,PBMC49,PBFC49,PBEC49,PBAC49,PAMC49,PAFC49,PAEC49,PAAC49,PBMC50,PBFC50,PBEC50,PBAC50,PAMC50,PAFC50,PAEC50,PAAC50,PBMC51,PBFC51,PBEC51,PBAC51,PAMC51,PAFC51,PAEC51,PAAC51,PBMC52,PBFC52,PBEC52,PBAC52,PAMC52,PAFC52,PAEC52,PAAC52,PBMC53,PBFC53,PBEC53,PBAC53,PAMC53,PAFC53,PAEC53,PAAC53,PBMC54,PBFC54,PBEC54,PBAC54,PAMC54,PAFC54,PAEC54,PAAC54,PBMC55,PBFC55,PBEC55,PBAC55,PAMC55,PAFC55,PAEC55,PAAC55,PBMC56,PBFC56,PBEC56,PBAC56,PAMC56,PAFC56,PAEC56,PAAC56,PBMC57,PBFC57,PBEC57,PBAC57,PAMC57,PAFC57,PAEC57,PAAC57,PBMC58,PBAC58,PAMC58,PAAC58,PBAC59,PAAC59,PBAC60,PAAC60,PBAC61,PAAC61,PBFC62,PBEC62,PBAC62,PAFC62,PAEC62,PAAC62,PBMC63,PBFC63,PBEC63,PBAC63,PAMC63,PAFC63,PAEC63,PAAC63,PBMC64,PBFC64,PBEC64,PBAC64,PAMC64,PAFC64,PAEC64,PAAC64,PBMC65,PBFC65,PBEC65,PBAC65,PAMC65,PAFC65,PAEC65,PAAC65,PBMC66,PBFC66,PBEC66,PBAC66,PAMC66,PAFC66,PAEC66,PAAC66,PBMC67,PBFC67,PBEC67,PBAC67,PAMC67,PAFC67,PAEC67,PAAC67,PBMC68,PBFC68,PBEC68,PBAC68,PAMC68,PAFC68,PAEC68,PAAC68,PBMC69,PBFC69,PBEC69,PBAC69,PAMC69,PAFC69,PAEC69,PAAC69,PBMC70,PBFC70,PBEC70,PBAC70,PAMC70,PAFC70,PAEC70,PAAC70,PBMC71,PBFC71,PBEC71,PBAC71,PAMC71,PAFC71,PAEC71,PAAC71,PBMC72,PBAC72,PAMC72,PAAC72,PBAC73,PAAC73,PBAC74,PAAC74,PBAC75,PAAC75,PBAC76,PAAC76,PBAC77,PAAC77,PBAC78,PAAC78,PBAC81,PAAC81,PBAC82,PAAC82,PBAC83,PAAC83,PBAC84,PAAC84,PBAC85,PAAC85,PBAC86,PAAC86,PBAC87,PAAC87,PBAC88,PAAC88,PBAC89,PAAC89,PBAC90,PAAC90,PBAC91,PAAC91,PBAC92,PAAC92,PBAC93,PAAC93,PBAC94,PAAC94,PBAC95,PAAC95,PBAC96,PAAC96,PBAC97,PAAC97,PBAC98,PAAC98,PBAC99,PAAC99,PBAC100,PAAC100,PBAC101,PAAC101,PBAC102,PAAC102,PBAC103,PAAC103,PBAC104,PAAC104,PBAC105,PAAC105,PBAC106,PAAC106,PBAC107,PAAC107,PBAC108,PAAC108,PBAC109,PAAC109,PBAC110,PAAC110,PBAC113,PAAC113,PBAC114,PAAC114,PBAC115,PAAC115,PBAC116,PAAC116,PBAC117,PAAC117,PBAC118,PAAC118,PBAC119,PAAC119,PBAC120,PAAC120,PBAC121,PAAC121,PBAC122,PAAC122,PBAC127,PAAC127,PBAC128,PAAC128,PBAC129,PAAC129,PBAC130,PAAC130,PBAC131,PAAC131,PBAC132,PAAC132,PBAC133,PAAC133,PBAC134,PAAC134,PBAC135,PAAC135,PBAC136,PAAC136,PBAC137,PAAC137,PBAC138,PAAC138,PBAC139,PAAC139,PBAC140,PAAC140,PBAC141,PAAC141,PBAC142,PAAC142,PBAC143,PAAC143,PBAC144,PAAC144,PBAC145,PAAC145,PBAC146,PAAC146,PBAC147,PAAC147,PBAC148,PAAC148,PBAC149,PAAC149,PBAC150,PAAC150,PBAC151,PAAC151,PBAC152,PAAC152,PBAC153,PAAC153,PBAC154,PAAC154,PBAC155,PAAC155,PBAC156,PAAC156,PBFC501,PBEC501,PAFC501,PAEC501,C2168,C2169,C2170,C2172,C2173,C2174,C2175,C2176,C2177,C2178,C2179 | 495 | 62012PS00-015-G | CAP,10uF,+/-20%,X6S,4V,G,SMD0402 | MURATA ELEC. NORTH AMERICA | GRM155C80G106M |  | PWA BOM | In Old BOM |
|  |  |  | 62012PS00-023-G | CAP,10uF,+/-20%,X6S,4V,G,SMD0402 | TAIYO ELECTRIC IND.CO.LTD | AMK105CC6106MV-F | G | PWA BOM | In Old BOM |
| 271 | PBNC1,PANC8,PQPC16,C2188,PSRC3008 | 5 | 620130V00-015-G | CAP,10uF,+/-20%,X6S,16V,G,SMD0603 | MURATA ELEC. NORTH AMERICA | GRM188C81C106MA73D | G | PWA BOM | In New BOM |
|  |  |  | 620130V00-023-G | CAP,10uF,+/-20%,X6S,16V,G,SMD0603 | TAIYO ELECTRIC IND.CO.LTD | EMK107BC6106MA-T | G | PWA BOM | In New BOM |
|  | PBNC1,PANC8,PQPC16,C2188,PSRC3008 | 5 | 620130V00-015-G | CAP,10uF,+/-20%,X6S,16V,G,SMD0603 | MURATA ELEC. NORTH AMERICA | GRM188C81C106MA73D |  | PWA BOM | In Old BOM |
|  |  |  | 620130V00-023-G | CAP,10uF,+/-20%,X6S,16V,G,SMD0603 | TAIYO ELECTRIC IND.CO.LTD | EMK107BC6106MA-T | G | PWA BOM | In Old BOM |
| 272 | D9,D10,D11,D12,D13,D16,D18 | 7 | 520300500-223-G | DIODE,Schottky,BAT54SLT1G,30V,0.2A,G,SOT23-3,SMD | ON SEMICONDUCTOR CORP | BAT54SLT1G | G | PWA BOM | In New BOM |
|  | D9,D10,D11,D12,D13,D16,D18 | 7 | 520300500-223-G | DIODE,Schottky,BAT54SLT1G,30V,0.2A,G,SOT23-3,SMD | ON SEMICONDUCTOR CORP | BAT54SLT1G | N | PWA BOM | In Old BOM |
| 273 | D14 | 1 | 520305J00-223-G | DIODE,Schottky,MBR130LSFT1G,30V,1A,G,SOD123FL-2,SMD | ON SEMICONDUCTOR CORP | MBR130LSFT1G | G | PWA BOM | In New BOM |
|  | D14 | 1 | 520305J00-223-G | DIODE,Schottky,MBR130LSFT1G,30V,1A,G,SOD123FL-2,SMD | ON SEMICONDUCTOR CORP | MBR130LSFT1G | Y | PWA BOM | In Old BOM |
| 274 | D15,D17 | 2 | 520306Y00-223-G | DIODE,Schottky Rectifier,MBR0530T1G,30V,0.5A,G,SOD123-2,SMD | ON SEMICONDUCTOR CORP | MBR0530T1G | G | PWA BOM | In New BOM |
|  | D15,D17 | 2 | 520306Y00-223-G | DIODE,Schottky Rectifier,MBR0530T1G,30V,0.5A,G,SOD123-2,SMD | ON SEMICONDUCTOR CORP | MBR0530T1G | Y | PWA BOM | In Old BOM |
| 275 | D19 | 1 | 520300A00-237-G | DIODE,Schottky,SD103AW-7-F,40V,0.35A,G,SOD123-2,SMD | DIODES INEORPORATION | SD103AW-7-F | G | PWA BOM | In New BOM |
|  |  |  | 520302L00-223-G | Diode,Schottky,MBR0540T1G,40V,500mA,SOD-123,2P,G | ON SEMICONDUCTOR CORP | MBR0540T1G | G | PWA BOM | In New BOM |
|  | D19 | 1 | 520300A00-237-G | DIODE,Schottky,SD103AW-7-F,40V,0.35A,G,SOD123-2,SMD | DIODES INEORPORATION | SD103AW-7-F | N | PWA BOM | In Old BOM |
|  |  |  | 520302L00-223-G | Diode,Schottky,MBR0540T1G,40V,500mA,SOD-123,2P,G | ON SEMICONDUCTOR CORP | MBR0540T1G | G | PWA BOM | In Old BOM |
| 276 | D28,D35,D36 | 3 | 52010MP00-237-G | Diode,Rectifier,ES2D-13-F,200V,2A,G,SMB-2,SMD | DIODES INCORPORATION | ES2D-13-F | G | PWA BOM | In New BOM |
|  |  |  | 52010N000-223-G | Diode,Rectifier&Switching,MURS220T3G,200V,2A,SMB/DO-214AA,2P,G | ON SEMICONDUCTOR CORP | MURS220T3G | G | PWA BOM | In New BOM |
|  | D28,D35,D36 | 3 | 52010MP00-237-G | Diode,Rectifier,ES2D-13-F,200V,2A,G,SMB-2,SMD | DIODES INCORPORATION | ES2D-13-F |  | PWA BOM | In Old BOM |
|  |  |  | 52010N000-223-G | Diode,Rectifier&Switching,MURS220T3G,200V,2A,SMB/DO-214AA,2P,G | ON SEMICONDUCTOR CORP | MURS220T3G | G | PWA BOM | In Old BOM |
| 277 | D34 | 1 | 520401Y00-237-G | DIODE,Zener,BZT52C3V6-7-F,3.6V,5mA,G,SOD123-2,SMD | DIODES INEORPORATION | BZT52C3V6-7-F | G | PWA BOM | In New BOM |
|  |  |  | 520407600-223-G | Diode,ZENER,MMSZ3V6T1G,3.6V,5mA,SOD-123,2P,G | ON SEMICONDUCTOR CORP | MMSZ3V6T1G | G | PWA BOM | In New BOM |
|  | D34 | 1 | 520401Y00-237-G | DIODE,Zener,BZT52C3V6-7-F,3.6V,5mA,G,SOD123-2,SMD | DIODES INEORPORATION | BZT52C3V6-7-F | N | PWA BOM | In Old BOM |
|  |  |  | 520407600-223-G | Diode,ZENER,MMSZ3V6T1G,3.6V,5mA,SOD-123,2P,G | ON SEMICONDUCTOR CORP | MMSZ3V6T1G | G | PWA BOM | In Old BOM |
| 278 | D53,D54,D56 | 3 | 520304B00-237-G | DIODE,Schottky,BAT54WS-7-F,30V,0.1A,G,SOD323-2,SMD | DIODES INEORPORATION | BAT54WS-7-F | G | PWA BOM | In New BOM |
|  |  |  | 520303500-223-G | Diode,Schottky,BAT54HT1G,30V,200mA,SOD-323,2P,G | ON SEMICONDUCTOR CORP | BAT54HT1G | G | PWA BOM | In New BOM |
|  |  |  | 520308200-031-G | DIODE,Schottky,1PS76SB10,30V,200mA,G,SOD323-2,SMD | NXP SEMICONDUCTORS | 1PS76SB10 | G | PWA BOM | In New BOM |
|  | D53,D54,D56 | 3 | 520304B00-237-G | DIODE,Schottky,BAT54WS-7-F,30V,0.1A,G,SOD323-2,SMD | DIODES INEORPORATION | BAT54WS-7-F | N | PWA BOM | In Old BOM |
|  |  |  | 520303500-223-G | Diode,Schottky,BAT54HT1G,30V,200mA,SOD-323,2P,G | ON SEMICONDUCTOR CORP | BAT54HT1G | G | PWA BOM | In Old BOM |
|  |  |  | 520308200-031-G | DIODE,Schottky,1PS76SB10,30V,200mA,G,SOD323-2,SMD | NXP SEMICONDUCTORS | 1PS76SB10 | G | PWA BOM | In Old BOM |
| 279 | ED1,ED2,ED3 | 3 | 521800900-227-G | DIODE,Array-TVS,SRV05-4.TCT,5V,12A,G,SOT23-6,SMD | SEMTECH CORPORATION. | SRV05-4.TCT | G | PWA BOM | In New BOM |
|  |  |  | 52180H500-086-G | Diode,Array-TVS,SRV05-04HTG,SOT-23,6P,G | LITTELFUSE FAR EAST PTE LTD | SRV05-04HTG | G | PWA BOM | In New BOM |
|  | ED1,ED2,ED3 | 3 | 521800900-227-G | DIODE,Array-TVS,SRV05-4.TCT,5V,12A,G,SOT23-6,SMD | SEMTECH CORPORATION. | SRV05-4.TCT | N | PWA BOM | In Old BOM |
|  |  |  | 52180H500-086-G | Diode,Array-TVS,SRV05-04HTG,SOT-23,6P,G | LITTELFUSE FAR EAST PTE LTD | SRV05-04HTG | G | PWA BOM | In Old BOM |
| 280 | FS1 | 1 | 730200800-101-G | Polyswitch,PTC,6V,1.5A,G,SMD1206 | BOURNS INC | MF-NSMF150-2 | G | PWA BOM | In New BOM |
|  | FS1 | 1 | 730200800-101-G | Polyswitch,PTC,6V,1.5A,G,SMD1206 | BOURNS INC | MF-NSMF150-2 |  | PWA BOM | In Old BOM |
| 281 | FS2,FS3 | 2 | 730100400-086-G | Fuse,Very fast acting,3A,32V,G,SMD0603 | LITTELFUSE FAR EAST PTE LTD | 0467003.NR | G | PWA BOM | In New BOM |
|  | FS2,FS3 | 2 | 730100400-086-G | Fuse,Very fast acting,3A,32V,G,SMD0603 | LITTELFUSE FAR EAST PTE LTD | 0467003.NR | N | PWA BOM | In Old BOM |
| 282 | FS5,FS8,FS11,FS14,FS17,FS19,FS20 | 7 | 730103M00-086-G | Fuse,Fast acting,32V,5A,G,SMD0603 | LITTELFUSE FAR EAST PTE LTD | 0438005.WR | G | PWA BOM | In New BOM |
|  |  |  | 730103M00-088-G | Fuse,Fast acting,32V,5A,SMD0603,G | COOPER BUSSMANN, INC. | CC06H5A-TR | G | PWA BOM | In New BOM |
|  | FS5,FS8,FS11,FS14,FS17,FS19,FS20 | 7 | 730103M00-086-G | Fuse,Fast acting,32V,5A,G,SMD0603 | LITTELFUSE FAR EAST PTE LTD | 0438005.WR | Y | PWA BOM | In Old BOM |
|  |  |  | 730103M00-088-G | Fuse,Fast acting,32V,5A,SMD0603,G | COOPER BUSSMANN, INC. | CC06H5A-TR | G | PWA BOM | In Old BOM |
| 283 | FS6,FS7,FS10,FS13,FS18 | 5 | 730102B01-086-G | Fuse,Fast acting,32V,1A,G,SMD0603 | LITTELFUSE FAR EAST PTE LTD | 0438001.WR | G | PWA BOM | In New BOM |
|  |  |  | 730102B03-088-G | Fuse,Fast acting,32V,1A,SMD0603,G | COOPER BUSSMANN, INC. | CC06H1A-TR | G | PWA BOM | In New BOM |
|  | FS6,FS7,FS10,FS13,FS18 | 5 | 730102B01-086-G | Fuse,Fast acting,32V,1A,G,SMD0603 | LITTELFUSE FAR EAST PTE LTD | 0438001.WR | Y | PWA BOM | In Old BOM |
|  |  |  | 730102B03-088-G | Fuse,Fast acting,32V,1A,SMD0603,G | COOPER BUSSMANN, INC. | CC06H1A-TR | G | PWA BOM | In Old BOM |
| 284 | FS22 | 1 | 730102000-086-G | Fuse,Fast acting,24V,10A,G,SMD1206 | LITTELFUSE FAR EAST PTE LTD | 0501010.WR | G | PWA BOM | In New BOM |
|  | FS22 | 1 | 730102000-086-G | Fuse,Fast acting,24V,10A,G,SMD1206 | LITTELFUSE FAR EAST PTE LTD | 0501010.WR |  | PWA BOM | In Old BOM |
| 285 | FS27,FS28 | 2 | 730108F00-086-G | Fuse,Fast acting,500V,30A,G,SMD | LITTELFUSE FAR EAST PTE LTD | 0505030.MXP | G | PWA BOM | In New BOM |
|  | FS27,FS28 | 2 | 730108F00-086-G | Fuse,Fast acting,500V,30A,G,SMD | LITTELFUSE FAR EAST PTE LTD | 0505030.MXP |  | PWA BOM | In Old BOM |
| 286 | FS29 | 1 | 730106S00-088-G | Fuse,Fast acting,125V,15A,G,SMD2010 | COOPER BUSSMANN, INC. | CB61F15A-TR2 | G | PWA BOM | In New BOM |
|  | FS29 | 1 | 730106S00-088-G | Fuse,Fast acting,125V,15A,G,SMD2010 | COOPER BUSSMANN, INC. | CB61F15A-TR2 |  | PWA BOM | In Old BOM |
| 287 | FS30 | 1 | 730101C00-086-G | Fuse,Slow blow,125V,30A,G,SMD | LITTELFUSE FAR EAST PTE LTD | 0456030.ER | G | PWA BOM | In New BOM |
|  | FS30 | 1 | 730101C00-086-G | Fuse,Slow blow,125V,30A,G,SMD | LITTELFUSE FAR EAST PTE LTD | 0456030.ER | N | PWA BOM | In Old BOM |
| 288 | LED1 | 1 | 52112H800-289-G | LED,Blu,LTST-C193TBKT-LO,5V,20mA,G,SMD | LITE-ON TECHNOLOGY CORPORATION | LTST-C193TBKT-LO | G | PWA BOM | In New BOM |
|  |  |  | 52112H900-354-G | LED LAMP,LG-192DBK-CT/T-SD,Blue,24mcd@IF=5mA,475nm,999.9999V,20mA,N/A,,SMD0603,2P,G | Ligitek Electronics Co., Ltd. | LG-192DBK-CT/T-SD | G | PWA BOM | In New BOM |
|  | LED1 | 1 | 52112H800-289-G | LED,Blu,LTST-C193TBKT-LO,5V,20mA,G,SMD | LITE-ON TECHNOLOGY CORPORATION | LTST-C193TBKT-LO |  | PWA BOM | In Old BOM |
|  |  |  | 52112H900-354-G | LED LAMP,LG-192DBK-CT/T-SD,Blue,24mcd@IF=5mA,475nm,999.9999V,20mA,N/A,,SMD0603,2P,G | Ligitek Electronics Co., Ltd. | LG-192DBK-CT/T-SD | G | PWA BOM | In Old BOM |
| 289 | LED2,LED6 | 2 | 52111AE00-289-G | LED,Ora,LTST-C281KFKT-5A,5V,30mA,G,SMD0402 | LITE-ON TECHNOLOGY CORPORATION | LTST-C281KFKT-5A | G | PWA BOM | In New BOM |
|  |  |  | 52113GM00-290-G | LED LAMP,B1851UD--05D-000214,Orange,28.5mcd@IF=20mA,605nm,5V,20mA,N/A,,SMD0402,2P,G | HARVATEK | B1851UD--05D-000214 | G | PWA BOM | In New BOM |
|  | LED2,LED6 | 2 | 52111AE00-289-G | LED,Ora,LTST-C281KFKT-5A,5V,30mA,G,SMD0402 | LITE-ON TECHNOLOGY CORPORATION | LTST-C281KFKT-5A |  | PWA BOM | In Old BOM |
|  |  |  | 52113GM00-290-G | LED LAMP,B1851UD--05D-000214,Orange,28.5mcd@IF=20mA,605nm,5V,20mA,N/A,,SMD0402,2P,G | HARVATEK | B1851UD--05D-000214 | G | PWA BOM | In Old BOM |
| 290 | LED3,LED7 | 2 | 52111J100-289-G | LED,Gre,LTST-C281KGKT-5A,2.3V,30mA,G,SMD0402 | LITE-ON TECHNOLOGY CORPORATION | LTST-C281KGKT-5A | G | PWA BOM | In New BOM |
|  |  |  | 52113AE00-290-G | LED LAMP,B1851UYG-05D-000114,Ultra Bright Yellow Green,11.25mcd@IF=5mA,571nm,5V,20mA,N/A,,SMD0402,2P,G | HARVATEK | B1851UYG-05D-000114 | G | PWA BOM | In New BOM |
|  | LED3,LED7 | 2 | 52111J100-289-G | LED,Gre,LTST-C281KGKT-5A,2.3V,30mA,G,SMD0402 | LITE-ON TECHNOLOGY CORPORATION | LTST-C281KGKT-5A |  | PWA BOM | In Old BOM |
|  |  |  | 52113AE00-290-G | LED LAMP,B1851UYG-05D-000114,Ultra Bright Yellow Green,11.25mcd@IF=5mA,571nm,5V,20mA,N/A,,SMD0402,2P,G | HARVATEK | B1851UYG-05D-000114 | G | PWA BOM | In Old BOM |
| 291 | LED8,LED9 | 2 | 52113AY00-289-G | LED,Red,LTL-42NEW8DH184P,5V,20mA,G,DIP-2 | LITE-ON TECHNOLOGY CORPORATION | LTL-42NEW8DH184P | G | PWA BOM | In New BOM |
|  | LED8,LED9 | 2 | 52113AY00-289-G | LED,Red,LTL-42NEW8DH184P,5V,20mA,G,DIP-2 | LITE-ON TECHNOLOGY CORPORATION | LTL-42NEW8DH184P |  | PWA BOM | In Old BOM |
| 292 | LED10,LED14 | 2 | 52113B000-289-G | LED,Yellow,LTL-42NSV8DH184P,5V,20mA,G,DIP-2 | LITE-ON TECHNOLOGY CORPORATION | LTL-42NSV8DH184P | G | PWA BOM | In New BOM |
|  |  |  | L-7104ADFX012-TW | LED,L-7104ADFX012-TW | Kingbright | L-7104ADFX012-TW | G | PWA BOM | In New BOM |
|  | LED10,LED14 | 2 | 52113B000-289-G | LED,Yellow,LTL-42NSV8DH184P,5V,20mA,G,DIP-2 | LITE-ON TECHNOLOGY CORPORATION | LTL-42NSV8DH184P |  | PWA BOM | In Old BOM |
|  |  |  | L-7104ADFX012-TW | LED,L-7104ADFX012-TW | Kingbright | L-7104ADFX012-TW | G | PWA BOM | In Old BOM |
| 293 | LED63,LED64,LED65 | 3 | 52110FE00-289-G | LED,Red,LTST-C190KRKT,2.4V,30mA,G,SMD0603 | LITE-ON TECHNOLOGY CORPORATION | LTST-C190KRKT | G | PWA BOM | In New BOM |
|  | LED63,LED64,LED65 | 3 | 52110FE00-289-G | LED,Red,LTST-C190KRKT,2.4V,30mA,G,SMD0603 | LITE-ON TECHNOLOGY CORPORATION | LTST-C190KRKT |  | PWA BOM | In Old BOM |
| 294 | LED66,LED67,LED68,LED69,LED70,LED71,LED72,LED73,LED74,LED75,LED76,LED77,LED78,LED79,LED80,LED81,LED82,LED83,LED84,LED85,LED86,LED87,LED88,LED89,LED90,LED91,LED92,LED93,LED94,LED95,LED96,LED97,LED98,LED99,LED100,LED101,LED102 | 37 | 52110LN00-289-G | LED,Gre,LTST-C191KGKT,2.4V,30mA,G,SMD0603 | LITE-ON TECHNOLOGY CORPORATION | LTST-C191KGKT | G | PWA BOM | In New BOM |
|  |  |  | 52110K100-030-G | LED LAMP,SML-512MWT86,Green,40mcd@If=20mA,N/A,5V,25mA,N/A,,SMD0603,2P,G | ROHM CORPORATION | SML-512MWT86 | G | PWA BOM | In New BOM |
|  | LED66,LED67,LED68,LED69,LED70,LED71,LED72,LED73,LED74,LED75,LED76,LED77,LED78,LED79,LED80,LED81,LED82,LED83,LED84,LED85,LED86,LED87,LED88,LED89,LED90,LED91,LED92,LED93,LED94,LED95,LED96,LED97,LED98,LED99,LED100,LED101,LED102 | 37 | 52110LN00-289-G | LED,Gre,LTST-C191KGKT,2.4V,30mA,G,SMD0603 | LITE-ON TECHNOLOGY CORPORATION | LTST-C191KGKT |  | PWA BOM | In Old BOM |
|  |  |  | 52110K100-030-G | LED LAMP,SML-512MWT86,Green,40mcd@If=20mA,N/A,5V,25mA,N/A,,SMD0603,2P,G | ROHM CORPORATION | SML-512MWT86 | G | PWA BOM | In Old BOM |
| 295 | LOM1 | 1 | 21040HY00-283-G | IC,BROADCOM,BCM5719A1KFBG,A1,G,FBGA-256,SMD | BROADCOM SINGAPORE PTE LTD. | BCM5719A1KFBG | G | PWA BOM | In New BOM |
|  | LOM1 | 1 | 21040HY00-283-G | IC,BROADCOM,BCM5719A1KFBG,A1,G,FBGA-256,SMD | BROADCOM SINGAPORE PTE LTD. | BCM5719A1KFBG |  | PWA BOM | In Old BOM |
| 296 | L18,L19,L20 | 3 | 630100U00-016-G | IND,68nH@50MHz,+/-20%,50mA,300mOhm,G,SMD0603 | TDK ELECTRONICS EUROPE GMBH | MLF1608D68NMT | G | PWA BOM | In New BOM |
|  | L18,L19,L20 | 3 | 630100U00-016-G | IND,68nH@50MHz,+/-20%,50mA,300mOhm,G,SMD0603 | TDK ELECTRONICS EUROPE GMBH | MLF1608D68NMT | N | PWA BOM | In Old BOM |
| 297 | L21 | 1 | 720107U00-015-G | FB,220 Ohm@100MHz,+/-25%,2A,50mOhm,G,SMD0805 | MURATA ELEC. NORTH AMERICA | BLM21PG221SN1D | G | PWA BOM | In New BOM |
|  | L21 | 1 | 720107U00-015-G | FB,220 Ohm@100MHz,+/-25%,2A,50mOhm,G,SMD0805 | MURATA ELEC. NORTH AMERICA | BLM21PG221SN1D | N | PWA BOM | In Old BOM |
| 298 | L26,L28,L47 | 3 | 72010CB00-015-G | FB,22 Ohm@100MHz,+/-25%,6A,10mOhm,G,SMD0805 | MURATA ELEC. NORTH AMERICA | BLM21PG220SN1D | G | PWA BOM | In New BOM |
|  |  |  | 72010CB00-059-G | FB,22 Ohm@100MHz,+/-25%,6A,10mOhm,G,SMD0805 | TAI-TECH ADVANCED ELECTRONICS CO., LTD. | HCB2012KF-220T60 | G | PWA BOM | In New BOM |
|  |  |  | 72010Y600-174-G | FB,22 Ohm@100MHz,+/-25%,6A,8mOhm,G,SMD0805 | MAX ECHO TECHNOLOGIES CORP | BCMS201209A220 | G | PWA BOM | In New BOM |
|  | L26,L28,L47 | 3 | 72010CB00-015-G | FB,22 Ohm@100MHz,+/-25%,6A,10mOhm,G,SMD0805 | MURATA ELEC. NORTH AMERICA | BLM21PG220SN1D | N | PWA BOM | In Old BOM |
|  |  |  | 72010CB00-059-G | FB,22 Ohm@100MHz,+/-25%,6A,10mOhm,G,SMD0805 | TAI-TECH ADVANCED ELECTRONICS CO., LTD. | HCB2012KF-220T60 | G | PWA BOM | In Old BOM |
|  |  |  | 72010Y600-174-G | FB,22 Ohm@100MHz,+/-25%,6A,8mOhm,G,SMD0805 | MAX ECHO TECHNOLOGIES CORP | BCMS201209A220 | G | PWA BOM | In Old BOM |
| 299 | L35,L37,L38,L39,L40,L41,L42 | 7 | 72010MK00-015-G | FB,80 Ohm@100MHz,+/-25%,1.5A,70mOhm,G,SMD0402 | MURATA ELEC. NORTH AMERICA | BLM15PD800SN1D | G | PWA BOM | In New BOM |
|  |  |  | 72010MK00-174-G | FB,80 Ohm@100MHz,+/-25%,1.5A,Multilayer,70mOhm,SMD0402,G | MAX ECHO TECHNOLOGIES CORP | ACMS100505A800 1.5A | G | PWA BOM | In New BOM |
|  | L35,L37,L38,L39,L40,L41,L42 | 7 | 72010MK00-015-G | FB,80 Ohm@100MHz,+/-25%,1.5A,70mOhm,G,SMD0402 | MURATA ELEC. NORTH AMERICA | BLM15PD800SN1D | N | PWA BOM | In Old BOM |
|  |  |  | 72010MK00-174-G | FB,80 Ohm@100MHz,+/-25%,1.5A,Multilayer,70mOhm,SMD0402,G | MAX ECHO TECHNOLOGIES CORP | ACMS100505A800 1.5A | G | PWA BOM | In Old BOM |
| 300 | L45 | 1 | 720101M00-015-G | FB,600 Ohm@100MHz,+/-25%,200mA,650mOhm,G,SMD0603 | MURATA ELEC. NORTH AMERICA | BLM18BD601SN1D | G | PWA BOM | In New BOM |
|  |  |  | 720103000-023-G | FB,600 Ohm@100MHz,+/-25%,250mA,600mOhm,G,SMD0603 | TAIYO ELECTRIC IND.CO.LTD | BK1608HM601-T | G | PWA BOM | In New BOM |
|  | L45 | 1 | 720101M00-015-G | FB,600 Ohm@100MHz,+/-25%,200mA,650mOhm,G,SMD0603 | MURATA ELEC. NORTH AMERICA | BLM18BD601SN1D | N | PWA BOM | In Old BOM |
|  |  |  | 720103000-023-G | FB,600 Ohm@100MHz,+/-25%,250mA,600mOhm,G,SMD0603 | TAIYO ELECTRIC IND.CO.LTD | BK1608HM601-T | G | PWA BOM | In Old BOM |
| 301 | PSUCE1,PBACE1,PAACE1,PSUCE2,PBACE2,PAACE2 | 6 | 62111CS00-024-G | ECAP,68uF,+/-20%,100V,105C,G,SMD12.5*13.5,ESR<=320mOhm | PANASONIC INDUSTRIAL CO.,LTD. | EEVFK2A680Q | G | PWA BOM | In New BOM |
|  |  |  | 62111RR00-025-G | ECAP,AL,Low ESR(LESR),68uF,+/-20%,100V,105_x0003_,500mOhm,SMD,12.5*13.5,G | KEMET ELECTRONICS CORPORATION | EXV686M100A9RAA | G | PWA BOM | In New BOM |
|  |  |  | 62111SK00-021-G | ECAP,AL,Low ESR(LESR),68uF,+/-20%,100V,105_x0003_,330mOhm,SMD,12.5*13.5,G | NIPPON CHEMI-CON CORPORATION | EMVY101ARA680MKE0S | G | PWA BOM | In New BOM |
|  | PSUCE1,PBACE1,PAACE1,PSUCE2,PBACE2,PAACE2 | 6 | 62111CS00-024-G | ECAP,68uF,+/-20%,100V,105C,G,SMD12.5*13.5,ESR<=320mOhm | PANASONIC INDUSTRIAL CO.,LTD. | EEVFK2A680Q |  | PWA BOM | In Old BOM |
|  |  |  | 62111RR00-025-G | ECAP,AL,Low ESR(LESR),68uF,+/-20%,100V,105_x0003_,500mOhm,SMD,12.5*13.5,G | KEMET ELECTRONICS CORPORATION | EXV686M100A9RAA | G | PWA BOM | In Old BOM |
|  |  |  | 62111SK00-021-G | ECAP,AL,Low ESR(LESR),68uF,+/-20%,100V,105_x0003_,330mOhm,SMD,12.5*13.5,G | NIPPON CHEMI-CON CORPORATION | EMVY101ARA680MKE0S | G | PWA BOM | In Old BOM |
| 302 | PBMCE1,PAMCE1,PBFCE2,PBECE2,PAFCE2,PAECE2,PBACE3,PAACE3 | 8 | 62111QQ00-019-G | ECAP,82uF,+/-20%,100V,105C,G,SMD12.5*13.5,ESR<=280mOhm | NICHICON CORPORATION | UCZ2A820MNQ1MS | G | PWA BOM | In New BOM |
|  | PBMCE1,PAMCE1,PBFCE2,PBECE2,PAFCE2,PAECE2,PBACE3,PAACE3 | 8 | 62111QQ00-019-G | ECAP,82uF,+/-20%,100V,105C,G,SMD12.5*13.5,ESR<=280mOhm | NICHICON CORPORATION | UCZ2A820MNQ1MS |  | PWA BOM | In Old BOM |
| 303 | PBNCE1,PANCE1,PBNCE2,PANCE2,PBECE3,PALCE3,PAFCE3,PAECE3,PBMCE4,PBFCE4,PBECE4,PBACE4,PAMCE4,PALCE4,PAFCE4,PAECE4,PAACE4,PBMCE5,PBFCE5,PBECE5,PBACE5,PAMCE5,PAFCE5,PAECE5,PAACE5,PBMCE6,PBFCE6,PBECE6,PBACE6,PAMCE6,PAFCE6,PAECE6,PAACE6,PBMCE7,PBLCE7,PBFCE7,PBACE7,PAMCE7,PAACE7,PBLCE8,PBACE8,PAACE8,PBACE9,PAACE9,PBACE10,PAACE10,PBACE11,PAACE11,PBACE12,PAACE12 | 50 | 62120ER01-024-G | ECAP,SPEA,470uF,+/-20%,2.5V,105C,G,SMD2816,ESR<=3mOhm | PANASONIC INDUSTRIAL CO.,LTD. | EEFGX0E471R | G | PWA BOM | In New BOM |
|  |  |  | 62120ER00-025-G | ECAP,SPEA,Low ESR(LESR),470uF,+/-20%,2.5V,105_x0003_,3mOhm,SMD2816,G | KEMET ELECTRONICS CORPORATION | A720V477M2R5APE003 | G | PWA BOM | In New BOM |
|  | PBNCE1,PANCE1,PBNCE2,PANCE2,PBECE3,PALCE3,PAFCE3,PAECE3,PBMCE4,PBFCE4,PBECE4,PBACE4,PAMCE4,PALCE4,PAFCE4,PAECE4,PAACE4,PBMCE5,PBFCE5,PBECE5,PBACE5,PAMCE5,PAFCE5,PAECE5,PAACE5,PBMCE6,PBFCE6,PBECE6,PBACE6,PAMCE6,PAFCE6,PAECE6,PAACE6,PBMCE7,PBLCE7,PBFCE7,PBACE7,PAMCE7,PAACE7,PBLCE8,PBACE8,PAACE8,PBACE9,PAACE9,PBACE10,PAACE10,PBACE11,PAACE11,PBACE12,PAACE12 | 50 | 62120ER01-024-G | ECAP,SPEA,470uF,+/-20%,2.5V,105C,G,SMD2816,ESR<=3mOhm | PANASONIC INDUSTRIAL CO.,LTD. | EEFGX0E471R |  | PWA BOM | In Old BOM |
|  |  |  | 62120ER00-025-G | ECAP,SPEA,Low ESR(LESR),470uF,+/-20%,2.5V,105_x0003_,3mOhm,SMD2816,G | KEMET ELECTRONICS CORPORATION | A720V477M2R5APE003 | G | PWA BOM | In Old BOM |
| 304 | PBMC1,PBFC1,PBEC1,PBAC1,PAMC1,PAFC1,PAEC1,PAAC1,PBMC2,PBFC2,PBEC2,PBAC2,PAMC2,PAFC2,PAEC2,PAAC2,PBMC22,PBFC22,PBEC22,PBAC22,PAMC22,PAFC22,PAEC22,PAAC22,PBMC450,PBFC450,PBEC450,PBAC450,PAMC450,PAFC450,PAEC450,PAAC450,PBAC452,PAAC452 | 34 | 62012RJ00-015-G | CAP,4.7uF,+/-10%,X6S,16V,G,SMD0603 | MURATA ELEC. NORTH AMERICA | GRM188C81C475K | G | PWA BOM | In New BOM |
|  |  |  | 62012RJ00-026-G | CAP,4.7uF,+/-10%,X6S,16V,G,SMD0603 | SAMSUNG SEMICONDUCTOR | CL10X475KO8NQNC | G | PWA BOM | In New BOM |
|  |  |  | 62012RJ00-023-G | CAP,4.7uF,+/-10%,X6S,16V,G,SMD0603 | TAIYO ELECTRIC IND.CO.LTD | EMK107BC6475KA-T | G | PWA BOM | In New BOM |
|  | PBMC1,PBFC1,PBEC1,PBAC1,PAMC1,PAFC1,PAEC1,PAAC1,PBMC2,PBFC2,PBEC2,PBAC2,PAMC2,PAFC2,PAEC2,PAAC2,PBMC22,PBFC22,PBEC22,PBAC22,PAMC22,PAFC22,PAEC22,PAAC22,PBMC450,PBFC450,PBEC450,PBAC450,PAMC450,PAFC450,PAEC450,PAAC450,PBAC452,PAAC452 | 34 | 62012RJ00-015-G | CAP,4.7uF,+/-10%,X6S,16V,G,SMD0603 | MURATA ELEC. NORTH AMERICA | GRM188C81C475K |  | PWA BOM | In Old BOM |
|  |  |  | 62012RJ00-026-G | CAP,4.7uF,+/-10%,X6S,16V,G,SMD0603 | SAMSUNG SEMICONDUCTOR | CL10X475KO8NQNC | G | PWA BOM | In Old BOM |
|  |  |  | 62012RJ00-023-G | CAP,4.7uF,+/-10%,X6S,16V,G,SMD0603 | TAIYO ELECTRIC IND.CO.LTD | EMK107BC6475KA-T | G | PWA BOM | In Old BOM |
| 305 | PBMC6,PBFC6,PBEC6,PBAC6,PAMC6,PAFC6,PAEC6,PAAC6 | 8 | 62011DQ00-015-G | CAP,27nF,+/-10%,X7R,25V,G,SMD0402 | MURATA ELEC. NORTH AMERICA | GRM155R71E273KA88D | G | PWA BOM | In New BOM |
|  | PBMC6,PBFC6,PBEC6,PBAC6,PAMC6,PAFC6,PAEC6,PAAC6 | 8 | 62011DQ00-015-G | CAP,27nF,+/-10%,X7R,25V,G,SMD0402 | MURATA ELEC. NORTH AMERICA | GRM155R71E273KA88D |  | PWA BOM | In Old BOM |
| 306 | PBEC11,PAFC11,PAEC11,PBMC12,PBFC12,PBAC12,PAMC12,PAAC12,PHAC14 | 9 | 62010VD00-015-G | CAP,100nF,+/-10%,X7R,100V,G,SMD0603 | MURATA ELEC. NORTH AMERICA | GRM188R72A104K | G | PWA BOM | In New BOM |
|  |  |  | 62010VD00-026-G | CAP,100nF,+/-10%,X7R,100V,G,SMD0603 | SAMSUNG SEMICONDUCTOR | CL10B104KC8NNNC | G | PWA BOM | In New BOM |
|  | PBEC11,PAFC11,PAEC11,PBMC12,PBFC12,PBAC12,PAMC12,PAAC12,PHAC14 | 9 | 62010VD00-015-G | CAP,100nF,+/-10%,X7R,100V,G,SMD0603 | MURATA ELEC. NORTH AMERICA | GRM188R72A104K |  | PWA BOM | In Old BOM |
|  |  |  | 62010VD00-026-G | CAP,100nF,+/-10%,X7R,100V,G,SMD0603 | SAMSUNG SEMICONDUCTOR | CL10B104KC8NNNC | G | PWA BOM | In Old BOM |
| 307 | PSUC1,PSUC2,PBMC13,PBFC13,PBEC13,PBAC13,PAMC13,PAFC13,PAEC13,PAAC13,PBMC14,PBFC14,PBEC14,PBAC14,PAMC14,PAFC14,PAEC14,PAAC14,PBMC15,PBFC15,PBEC15,PBAC15,PAMC15,PAFC15,PAEC15,PAAC15,PBAC16,PAAC16,PBEC17,PBAC17,PAAC17,PBAC18,PAAC18,PBAC19,PAAC19,PAFC20,PAAC20,PBMC21,PBFC21,PBAC21,PAMC21,PAEC21 | 42 | 62011J601-015-G | CAP,2.2uF,+/-10%,X7R,100V,G,SMD1210 | MURATA ELEC. NORTH AMERICA | GRM32ER72A225K | G | PWA BOM | In New BOM |
|  |  |  | 62011J600-026-G | CAP,2.2uF,+/-10%,X7R,100V,G,SMD1210 | SAMSUNG SEMICONDUCTOR | CL32B225KCJSNNE | G | PWA BOM | In New BOM |
|  | PSUC1,PSUC2,PBMC13,PBFC13,PBEC13,PBAC13,PAMC13,PAFC13,PAEC13,PAAC13,PBMC14,PBFC14,PBEC14,PBAC14,PAMC14,PAFC14,PAEC14,PAAC14,PBMC15,PBFC15,PBEC15,PBAC15,PAMC15,PAFC15,PAEC15,PAAC15,PBAC16,PAAC16,PBEC17,PBAC17,PAAC17,PBAC18,PAAC18,PBAC19,PAAC19,PAFC20,PAAC20,PBMC21,PBFC21,PBAC21,PAMC21,PAEC21 | 42 | 62011J601-015-G | CAP,2.2uF,+/-10%,X7R,100V,G,SMD1210 | MURATA ELEC. NORTH AMERICA | GRM32ER72A225K |  | PWA BOM | In Old BOM |
|  |  |  | 62011J600-026-G | CAP,2.2uF,+/-10%,X7R,100V,G,SMD1210 | SAMSUNG SEMICONDUCTOR | CL32B225KCJSNNE | G | PWA BOM | In Old BOM |
| 308 | PBNC18,PANC18,PBNC19,PANC19,PUAC20,PSAC20,PRAC20,PQAC20,PPAC20,PIAC20,PFAC20,PEAC20,PBNC20,PANC20,PUAC21,PSAC21,PRAC21,PQAC21,PPAC21,PIAC21,PFAC21,PEAC21,PBNC21,PANC21,PUAC22,PSAC22,PRAC22,PQAC22,PPAC22,PIAC22,PFAC22,PEAC22,PBNC22,PANC22,PUAC23,PSAC23,PRAC23,PQAC23,PPAC23,PIAC23,PFAC23,PEAC23,PBNC23,PANC23,PUAC24,PSAC24,PRAC24,PQAC24,PPAC24,PIAC24,PFAC24,PEAC24,PUAC25,PSAC25,PRAC25,PQAC25,PPAC25,PIAC25,PFAC25,PEAC25,PALC25,PALC26,PALC27,PALC28,PALC29,PALC30,PALC31,PALC32,PALC33,PALC34,PBLC45,PBLC46,PBLC47,PBLC48,PBLC49,PBLC50,PBLC51,PBLC52,PBLC53,PBLC63,PBMC73,PAMC73,PBMC74,PAMC74,PBMC75,PAMC75,PBMC76,PAMC76,PBMC77,PAMC77,PBMC78,PAMC78,PBMC79,PAMC79,PBMC80,PAMC80,PBMC81,PAMC81,PBMC82,PAMC82,PBMC83,PAMC83,PBMC84,PAMC84,PBMC85,PAMC85,PBMC86,PAMC86,PBMC87,PAMC87,PBMC88,PAMC88,PBMC89,PAMC89,PBMC90,PAMC90,PBMC91,PAMC91,PBMC92,PAMC92,PBMC93,PAMC93,PBMC94,PAMC94,PBMC96,PAMC96,PBMC97,PAMC97,PBMC98,PAMC98,PBMC99,PAMC99,PBMC100,PAMC100,PBMC101,PAMC101,PBMC102,PAMC102,PBMC103,PAMC103,PBAC167,PAAC167,PBAC168,PAAC168,PBAC169,PAAC169,PBAC170,PAAC170,PBAC171,PAAC171,PBAC172,PAAC172,PBAC173,PAAC173,PBAC174,PAAC174,PBAC175,PAAC175,PBAC176,PAAC176,PBAC177,PAAC177,PBAC178,PAAC178,PBAC179,PAAC179,PBAC180,PAAC180,PBAC181,PAAC181,PBAC182,PAAC182,PBAC183,PAAC183,PBAC184,PAAC184,PBAC185,PAAC185,PBAC186,PAAC186,PBAC187,PAAC187,PBAC188,PAAC188,PBAC189,PAAC189,PBAC190,PAAC190,PBAC191,PAAC191,PBAC192,PAAC192,PBAC193,PAAC193,PBAC194,PAAC194,PBAC195,PAAC195,PBAC196,PAAC196,PBAC197,PAAC197,PBAC198,PAAC198,PBAC199,PAAC199,PBAC200,PAAC200,PBAC201,PAAC201,PBAC202,PAAC202,PBAC203,PAAC203,PBAC204,PAAC204,PBAC205,PAAC205,PBAC206,PAAC206,PBAC207,PAAC207,PBAC208,PAAC208,PBAC209,PAAC209,PBAC210,PAAC210,PBAC211,PAAC211,PBAC212,PAAC212,PBAC213,PAAC213,PBAC214,PAAC214,PBAC215,PAAC215,PBAC216,PAAC216,PBAC217,PAAC217,PBAC218,PAAC218,PBAC219,PAAC219,PBAC220,PAAC220,PBAC221,PAAC221,PBAC222,PAAC222,PBAC223,PAAC223,PBAC224,PAAC224,PBAC225,PAAC225,PBAC226,PAAC226,PBAC227,PAAC227,PBAC228,PAAC228,PBAC229,PAAC229,PBAC230,PAAC230,PBAC231,PAAC231,PBAC232,PAAC232,PBAC233,PAAC233,PBAC234,PAAC234,PBAC235,PAAC235,PBAC236,PAAC236,PBAC237,PAAC237,PBAC238,PAAC238,PBAC239,PAAC239,PBAC240,PAAC240,PBAC241,PAAC241,PBAC242,PAAC242,PBAC243,PAAC243,PBAC244,PAAC244,PBAC245,PAAC245,PBAC246,PAAC246,PBFC300,PBEC300,PAFC300,PAEC300,PBFC301,PBEC301,PAFC301,PAEC301,PBFC302,PBEC302,PAFC302,PAEC302,PBFC303,PBEC303,PAFC303,PAEC303,PBFC304,PBEC304,PAFC304,PAEC304,PBFC305,PBEC305,PAFC305,PAEC305,PBFC306,PBEC306,PAFC306,PAEC306,PBFC307,PBEC307,PAFC307,PAEC307,PBFC308,PBEC308,PAFC308,PAEC308,PBFC309,PBEC309,PAFC309,PAEC309,PBFC310,PBEC310,PAFC310,PAEC310,PBFC311,PBEC311,PAFC311,PAEC311,PBFC312,PBEC312,PAFC312,PAEC312,PBFC313,PBEC313,PAFC313,PAEC313,PBFC314,PBEC314,PAFC314,PAEC314,PBFC315,PBEC315,PAFC315,PAEC315,PBFC316,PBEC316,PAFC316,PAEC316,PBFC317,PBEC317,PAFC317,PAEC317,PBFC318,PBEC318,PAFC318,PAEC318,PBFC319,PBEC319,PAFC319,PAEC319,PBFC320,PBEC320,PAFC320,PAEC320,PBFC321,PBEC321,PAFC321,PAEC321,PBFC322,PBEC322,PAFC322,PAEC322,PBFC323,PBEC323,PAFC323,PAEC323,PBFC324,PBEC324,PAFC324,PAEC324,PBFC325,PBEC325,PAFC325,PAEC325,PBFC326,PBEC326,PAFC326,PAEC326,PBFC327,PBEC327,PAFC327,PAEC327,PBFC328,PBEC328,PAFC328,PAEC328,PBFC329,PBEC329,PAFC329,PAEC329,PBFC330,PBEC330,PAFC330,PAEC330,PBFC331,PBEC331,PAFC331,PAEC331,PBFC332,PBEC332,PAFC332,PAEC332,PBFC333,PBEC333,PAFC333,PAEC333,PBFC334,PBEC334,PAFC334,PAEC334,PBFC335,PBEC335,PAFC335,PAEC335,PBFC336,PBEC336,PAFC336,PAEC336,PBFC337,PBEC337,PAFC337,PAEC337,PBFC338,PBEC338,PAFC338,PAEC338,PBFC339,PBEC339,PAFC339,PAEC339,PBFC340,PBEC340,PAFC340,PAEC340,PBFC341,PBEC341,PAFC341,PAEC341,PBFC342,PBEC342,PAFC342,PAEC342,PBFC343,PBEC343,PAFC343,PAEC343,PBFC344,PBEC344,PAFC344,PAEC344,PBFC345,PBEC345,PAFC345,PAEC345,PBFC346,PBEC346,PAFC346,PAEC346,PBFC347,PBEC347,PAFC347,PAEC347,PBFC348,PBEC348,PAFC348,PAEC348,PBFC349,PBEC349,PAFC349,PAEC349,PBFC350,PBEC350,PAFC350,PAEC350,PBFC351,PBEC351,PAFC351,PAEC351,PBFC352,PBEC352,PAFC352,PAEC352,PBFC353,PBEC353,PAFC353,PAEC353,PBFC354,PBEC354,PAFC354,PAEC354,PBFC355,PBEC355,PAFC355,PAEC355,PBFC356,PBEC356,PAFC356,PAEC356,PBFC357,PBEC357,PAFC357,PAEC357,PBFC358,PBEC358,PAFC358,PAEC358,PBFC359,PBEC359,PAFC359,PAEC359,PBFC360,PBEC360,PAFC360,PAEC360,PBFC361,PBEC361,PAFC361,PAEC361,PBFC362,PBEC362,PAFC362,PAEC362,PBFC363,PBEC363,PAFC363,PAEC363,PBFC364,PBEC364,PAFC364,PAEC364,PBFC365,PBEC365,PAFC365,PAEC365,PBFC366,PBEC366,PAFC366,PAEC366,PBFC367,PBEC367,PAFC367,PAEC367,PBFC368,PBEC368,PAFC368,PAEC368,PBFC369,PBEC369,PAFC369,PAEC369,PBFC370,PBEC370,PAFC370,PAEC370,PBFC371,PBEC371,PAFC371,PAEC371,PBFC372,PBEC372,PAFC372,PAEC372,PBFC373,PBEC373,PAFC373,PAEC373,PBFC374,PBEC374,PAFC374,PAEC374,PBFC375,PBEC375,PAFC375,PAEC375,PBFC376,PBEC376,PAFC376,PAEC376,PBFC377,PBEC377,PAFC377,PAEC377,PBFC378,PBEC378,PAFC378,PAEC378,PBFC379,PBEC379,PAFC379,PAEC379,PBFC380,PBEC380,PAFC380,PAEC380,PBFC381,PBEC381,PAFC381,PAEC381,PBFC382,PBEC382,PAFC382,PAEC382,PBFC383,PBEC383,PAFC383,PAEC383,PBFC384,PBEC384,PAFC384,PAEC384,PBFC385,PBEC385,PAFC385,PAEC385,PBFC386,PBEC386,PAFC386,PAEC386,PBFC387,PBEC387,PAFC387,PAEC387,PBFC388,PBEC388,PAFC388,PAEC388,PBFC389,PBEC389,PAFC389,PAEC389,PBFC390,PBEC390,PAFC390,PAEC390,PBFC391,PBEC391,PAFC391,PAEC391,PBFC392,PBEC392,PAFC392,PAEC392,PBFC393,PBEC393,PAFC393,PAEC393,PBFC394,PBEC394,PAFC394,PAEC394,PBFC395,PBEC395,PAFC395,PAEC395 | 684 | 620127602-015-G | CAP,47uF,+/-20%,X6S,4V,G,SMD0805 | MURATA ELEC. NORTH AMERICA | GRM21BC80G476M | G | PWA BOM | In New BOM |
|  |  |  | 620127600-023-G | CAP,47uF,+/-20%,X6S,4V,G,SMD0805 | TAIYO ELECTRIC IND.CO.LTD | AMK212BC6476MG-T | G | PWA BOM | In New BOM |
|  |  |  | 620127600-026-G | CAP,47uF,+/-20%,X6S,4V,G,SMD0805 | SAMSUNG SEMICONDUCTOR | CL21X476MRYNNNE | G | PWA BOM | In New BOM |
|  | PBNC18,PANC18,PBNC19,PANC19,PUAC20,PSAC20,PRAC20,PQAC20,PPAC20,PIAC20,PFAC20,PEAC20,PBNC20,PANC20,PUAC21,PSAC21,PRAC21,PQAC21,PPAC21,PIAC21,PFAC21,PEAC21,PBNC21,PANC21,PUAC22,PSAC22,PRAC22,PQAC22,PPAC22,PIAC22,PFAC22,PEAC22,PBNC22,PANC22,PUAC23,PSAC23,PRAC23,PQAC23,PPAC23,PIAC23,PFAC23,PEAC23,PBNC23,PANC23,PUAC24,PSAC24,PRAC24,PQAC24,PPAC24,PIAC24,PFAC24,PEAC24,PUAC25,PSAC25,PRAC25,PQAC25,PPAC25,PIAC25,PFAC25,PEAC25,PALC25,PALC26,PALC27,PALC28,PALC29,PALC30,PALC31,PALC32,PALC33,PALC34,PBLC45,PBLC46,PBLC47,PBLC48,PBLC49,PBLC50,PBLC51,PBLC52,PBLC53,PBLC63,PBMC73,PAMC73,PBMC74,PAMC74,PBMC75,PAMC75,PBMC76,PAMC76,PBMC77,PAMC77,PBMC78,PAMC78,PBMC79,PAMC79,PBMC80,PAMC80,PBMC81,PAMC81,PBMC82,PAMC82,PBMC83,PAMC83,PBMC84,PAMC84,PBMC85,PAMC85,PBMC86,PAMC86,PBMC87,PAMC87,PBMC88,PAMC88,PBMC89,PAMC89,PBMC90,PAMC90,PBMC91,PAMC91,PBMC92,PAMC92,PBMC93,PAMC93,PBMC94,PAMC94,PBMC96,PAMC96,PBMC97,PAMC97,PBMC98,PAMC98,PBMC99,PAMC99,PBMC100,PAMC100,PBMC101,PAMC101,PBMC102,PAMC102,PBMC103,PAMC103,PBAC167,PAAC167,PBAC168,PAAC168,PBAC169,PAAC169,PBAC170,PAAC170,PBAC171,PAAC171,PBAC172,PAAC172,PBAC173,PAAC173,PBAC174,PAAC174,PBAC175,PAAC175,PBAC176,PAAC176,PBAC177,PAAC177,PBAC178,PAAC178,PBAC179,PAAC179,PBAC180,PAAC180,PBAC181,PAAC181,PBAC182,PAAC182,PBAC183,PAAC183,PBAC184,PAAC184,PBAC185,PAAC185,PBAC186,PAAC186,PBAC187,PAAC187,PBAC188,PAAC188,PBAC189,PAAC189,PBAC190,PAAC190,PBAC191,PAAC191,PBAC192,PAAC192,PBAC193,PAAC193,PBAC194,PAAC194,PBAC195,PAAC195,PBAC196,PAAC196,PBAC197,PAAC197,PBAC198,PAAC198,PBAC199,PAAC199,PBAC200,PAAC200,PBAC201,PAAC201,PBAC202,PAAC202,PBAC203,PAAC203,PBAC204,PAAC204,PBAC205,PAAC205,PBAC206,PAAC206,PBAC207,PAAC207,PBAC208,PAAC208,PBAC209,PAAC209,PBAC210,PAAC210,PBAC211,PAAC211,PBAC212,PAAC212,PBAC213,PAAC213,PBAC214,PAAC214,PBAC215,PAAC215,PBAC216,PAAC216,PBAC217,PAAC217,PBAC218,PAAC218,PBAC219,PAAC219,PBAC220,PAAC220,PBAC221,PAAC221,PBAC222,PAAC222,PBAC223,PAAC223,PBAC224,PAAC224,PBAC225,PAAC225,PBAC226,PAAC226,PBAC227,PAAC227,PBAC228,PAAC228,PBAC229,PAAC229,PBAC230,PAAC230,PBAC231,PAAC231,PBAC232,PAAC232,PBAC233,PAAC233,PBAC234,PAAC234,PBAC235,PAAC235,PBAC236,PAAC236,PBAC237,PAAC237,PBAC238,PAAC238,PBAC239,PAAC239,PBAC240,PAAC240,PBAC241,PAAC241,PBAC242,PAAC242,PBAC243,PAAC243,PBAC244,PAAC244,PBAC245,PAAC245,PBAC246,PAAC246,PBFC300,PBEC300,PAFC300,PAEC300,PBFC301,PBEC301,PAFC301,PAEC301,PBFC302,PBEC302,PAFC302,PAEC302,PBFC303,PBEC303,PAFC303,PAEC303,PBFC304,PBEC304,PAFC304,PAEC304,PBFC305,PBEC305,PAFC305,PAEC305,PBFC306,PBEC306,PAFC306,PAEC306,PBFC307,PBEC307,PAFC307,PAEC307,PBFC308,PBEC308,PAFC308,PAEC308,PBFC309,PBEC309,PAFC309,PAEC309,PBFC310,PBEC310,PAFC310,PAEC310,PBFC311,PBEC311,PAFC311,PAEC311,PBFC312,PBEC312,PAFC312,PAEC312,PBFC313,PBEC313,PAFC313,PAEC313,PBFC314,PBEC314,PAFC314,PAEC314,PBFC315,PBEC315,PAFC315,PAEC315,PBFC316,PBEC316,PAFC316,PAEC316,PBFC317,PBEC317,PAFC317,PAEC317,PBFC318,PBEC318,PAFC318,PAEC318,PBFC319,PBEC319,PAFC319,PAEC319,PBFC320,PBEC320,PAFC320,PAEC320,PBFC321,PBEC321,PAFC321,PAEC321,PBFC322,PBEC322,PAFC322,PAEC322,PBFC323,PBEC323,PAFC323,PAEC323,PBFC324,PBEC324,PAFC324,PAEC324,PBFC325,PBEC325,PAFC325,PAEC325,PBFC326,PBEC326,PAFC326,PAEC326,PBFC327,PBEC327,PAFC327,PAEC327,PBFC328,PBEC328,PAFC328,PAEC328,PBFC329,PBEC329,PAFC329,PAEC329,PBFC330,PBEC330,PAFC330,PAEC330,PBFC331,PBEC331,PAFC331,PAEC331,PBFC332,PBEC332,PAFC332,PAEC332,PBFC333,PBEC333,PAFC333,PAEC333,PBFC334,PBEC334,PAFC334,PAEC334,PBFC335,PBEC335,PAFC335,PAEC335,PBFC336,PBEC336,PAFC336,PAEC336,PBFC337,PBEC337,PAFC337,PAEC337,PBFC338,PBEC338,PAFC338,PAEC338,PBFC339,PBEC339,PAFC339,PAEC339,PBFC340,PBEC340,PAFC340,PAEC340,PBFC341,PBEC341,PAFC341,PAEC341,PBFC342,PBEC342,PAFC342,PAEC342,PBFC343,PBEC343,PAFC343,PAEC343,PBFC344,PBEC344,PAFC344,PAEC344,PBFC345,PBEC345,PAFC345,PAEC345,PBFC346,PBEC346,PAFC346,PAEC346,PBFC347,PBEC347,PAFC347,PAEC347,PBFC348,PBEC348,PAFC348,PAEC348,PBFC349,PBEC349,PAFC349,PAEC349,PBFC350,PBEC350,PAFC350,PAEC350,PBFC351,PBEC351,PAFC351,PAEC351,PBFC352,PBEC352,PAFC352,PAEC352,PBFC353,PBEC353,PAFC353,PAEC353,PBFC354,PBEC354,PAFC354,PAEC354,PBFC355,PBEC355,PAFC355,PAEC355,PBFC356,PBEC356,PAFC356,PAEC356,PBFC357,PBEC357,PAFC357,PAEC357,PBFC358,PBEC358,PAFC358,PAEC358,PBFC359,PBEC359,PAFC359,PAEC359,PBFC360,PBEC360,PAFC360,PAEC360,PBFC361,PBEC361,PAFC361,PAEC361,PBFC362,PBEC362,PAFC362,PAEC362,PBFC363,PBEC363,PAFC363,PAEC363,PBFC364,PBEC364,PAFC364,PAEC364,PBFC365,PBEC365,PAFC365,PAEC365,PBFC366,PBEC366,PAFC366,PAEC366,PBFC367,PBEC367,PAFC367,PAEC367,PBFC368,PBEC368,PAFC368,PAEC368,PBFC369,PBEC369,PAFC369,PAEC369,PBFC370,PBEC370,PAFC370,PAEC370,PBFC371,PBEC371,PAFC371,PAEC371,PBFC372,PBEC372,PAFC372,PAEC372,PBFC373,PBEC373,PAFC373,PAEC373,PBFC374,PBEC374,PAFC374,PAEC374,PBFC375,PBEC375,PAFC375,PAEC375,PBFC376,PBEC376,PAFC376,PAEC376,PBFC377,PBEC377,PAFC377,PAEC377,PBFC378,PBEC378,PAFC378,PAEC378,PBFC379,PBEC379,PAFC379,PAEC379,PBFC380,PBEC380,PAFC380,PAEC380,PBFC381,PBEC381,PAFC381,PAEC381,PBFC382,PBEC382,PAFC382,PAEC382,PBFC383,PBEC383,PAFC383,PAEC383,PBFC384,PBEC384,PAFC384,PAEC384,PBFC385,PBEC385,PAFC385,PAEC385,PBFC386,PBEC386,PAFC386,PAEC386,PBFC387,PBEC387,PAFC387,PAEC387,PBFC388,PBEC388,PAFC388,PAEC388,PBFC389,PBEC389,PAFC389,PAEC389,PBFC390,PBEC390,PAFC390,PAEC390,PBFC391,PBEC391,PAFC391,PAEC391,PBFC392,PBEC392,PAFC392,PAEC392,PBFC393,PBEC393,PAFC393,PAEC393,PBFC394,PBEC394,PAFC394,PAEC394,PBFC395,PBEC395,PAFC395,PAEC395 | 684 | 620127602-015-G | CAP,47uF,+/-20%,X6S,4V,G,SMD0805 | MURATA ELEC. NORTH AMERICA | GRM21BC80G476M |  | PWA BOM | In Old BOM |
|  |  |  | 620127600-023-G | CAP,47uF,+/-20%,X6S,4V,G,SMD0805 | TAIYO ELECTRIC IND.CO.LTD | AMK212BC6476MG-T | G | PWA BOM | In Old BOM |
|  |  |  | 620127600-026-G | CAP,47uF,+/-20%,X6S,4V,G,SMD0805 | SAMSUNG SEMICONDUCTOR | CL21X476MRYNNNE | G | PWA BOM | In Old BOM |
| 309 | PBMD3,PBFD3,PBED3,PBAD3,PAMD3,PAFD3,PAED3,PAAD3 | 8 | 52030TQ00-237-G | Diode,Schottky,BAS40-06-7-F,40V,200mA,G,SOT-23-3,SMD | DIODES INCORPORATION | BAS40-06-7-F | G | PWA BOM | In New BOM |
|  | PBMD3,PBFD3,PBED3,PBAD3,PAMD3,PAFD3,PAED3,PAAD3 | 8 | 52030TQ00-237-G | Diode,Schottky,BAS40-06-7-F,40V,200mA,G,SOT-23-3,SMD | DIODES INCORPORATION | BAS40-06-7-F | N | PWA BOM | In Old BOM |
| 310 | PBML1,PBAL1,PAML1,PAAL1,PBFL2,PBEL2,PAFL2,PAEL2,PBML3,PBFL3,PBEL3,PBAL3,PAML3,PAFL3,PAEL3,PAAL3,PBAL5,PAAL5 | 18 | 63035NQ00-029-G | IND,0.1uH@100KHz,+/-20%,11.5A,6mOhm,SHLD,G,SMD | VISHAY ENTER TECHNO LOGY.INC | IHLP1616ABERR10M01 | G | PWA BOM | In New BOM |
|  |  |  | 63032QU00-034-G | Coil Ind,Shielded(SHLD),100nH@100KHz,+/-20%,12A,4mOhm,SMD,4.15*4.0*1.8,G | CYNTEC CO. LTD | PCMB042T-R10MS | G | PWA BOM | In New BOM |
|  | PBML1,PBAL1,PAML1,PAAL1,PBFL2,PBEL2,PAFL2,PAEL2,PBML3,PBFL3,PBEL3,PBAL3,PAML3,PAFL3,PAEL3,PAAL3,PBAL5,PAAL5 | 18 | 63035NQ00-029-G | IND,0.1uH@100KHz,+/-20%,11.5A,6mOhm,SHLD,G,SMD | VISHAY ENTER TECHNO LOGY.INC | IHLP1616ABERR10M01 |  | PWA BOM | In Old BOM |
|  |  |  | 63032QU00-034-G | Coil Ind,Shielded(SHLD),100nH@100KHz,+/-20%,12A,4mOhm,SMD,4.15*4.0*1.8,G | CYNTEC CO. LTD | PCMB042T-R10MS | G | PWA BOM | In Old BOM |
| 311 | PBAL2,PAAL2 | 2 | 63035R700-57M-G | IND,375nH@1MHz,+/-5%,16A,1.15mOhm,SHLD,G,SMD | Eaton Corporation | CTX01-19603-R | G | PWA BOM | In New BOM |
|  | PBAL2,PAAL2 | 2 | 63035R700-57M-G | IND,375nH@1MHz,+/-5%,16A,1.15mOhm,SHLD,G,SMD | Eaton Corporation | CTX01-19603-R |  | PWA BOM | In Old BOM |
| 312 | PBMQ10,PBAQ10,PAMQ10,PAAQ10,PBFQ11,PBEQ11,PAFQ11,PAEQ11 | 8 | 51032DL00-237-G | MOS N,DMT10H014LSS-13,100V,8.9A,15m@10V,G,SO-8,SMD | DIODES INCORPORATION | DMT10H014LSS-13 | G | PWA BOM | In New BOM |
|  |  |  | Si4190ADY-T1-GE3 | Si4190ADY-T1-GE3 | VISHAY ENTER TECHNO LOGY.INC | Si4190ADY-T1-GE3 | G | PWA BOM | In New BOM |
|  | PBMQ10,PBAQ10,PAMQ10,PAAQ10,PBFQ11,PBEQ11,PAFQ11,PAEQ11 | 8 | 51032DL00-237-G | MOS N,DMT10H014LSS-13,100V,8.9A,15m@10V,G,SO-8,SMD | DIODES INCORPORATION | DMT10H014LSS-13 |  | PWA BOM | In Old BOM |
|  |  |  | Si4190ADY-T1-GE3 | Si4190ADY-T1-GE3 | VISHAY ENTER TECHNO LOGY.INC | Si4190ADY-T1-GE3 | G | PWA BOM | In Old BOM |
| 313 | Q8,PHAQ8,PBMQ11,PBAQ11,PAMQ11,PAAQ11,PBFQ12,PBEQ12,PAFQ12,PAEQ12,Q85 | 11 | 510100W00-237-G | TRANS N,MMBT3904-7-F,40V,0.2A,G,SOT23-3,SMD | DIODES INEORPORATION | MMBT3904-7-F | G | PWA BOM | In New BOM |
|  |  |  | 510100500-031-G | TRANS N,PMBT3904,40V,0.2A,G,SOT23-3,SMD | NXP SEMICONDUCTORS | PMBT3904 | G | PWA BOM | In New BOM |
|  |  |  | 510101700-185-G | TRANS N,MMBT3904,40V,0.2A,G,SOT23-3,SMD | FAIRCHILD SEMICONDUCTOR CORP | MMBT3904 | G | PWA BOM | In New BOM |
|  |  |  | 510100800-223-G | TRANS N,MMBT3904LT1G,40V,0.2A,G,SOT23-3,SMD | ON SEMICONDUCTOR CORP | MMBT3904LT1G | G | PWA BOM | In New BOM |
|  | Q8,PHAQ8,PBMQ11,PBAQ11,PAMQ11,PAAQ11,PBFQ12,PBEQ12,PAFQ12,PAEQ12,Q85 | 11 | 510100W00-237-G | TRANS N,MMBT3904-7-F,40V,0.2A,G,SOT23-3,SMD | DIODES INEORPORATION | MMBT3904-7-F | N | PWA BOM | In Old BOM |
|  |  |  | 510101700-185-G | TRANS N,MMBT3904,40V,0.2A,G,SOT23-3,SMD | FAIRCHILD SEMICONDUCTOR CORP | MMBT3904 | G | PWA BOM | In Old BOM |
|  |  |  | 510100800-223-G | TRANS N,MMBT3904LT1G,40V,0.2A,G,SOT23-3,SMD | ON SEMICONDUCTOR CORP | MMBT3904LT1G | G | PWA BOM | In Old BOM |
|  |  |  | 510100500-031-G | TRANS N,PMBT3904,40V,0.2A,G,SOT23-3,SMD | NXP SEMICONDUCTORS | PMBT3904 | G | PWA BOM | In Old BOM |
| 314 | PBFQ10,PBEQ10,PAFQ10,PAEQ10,PBMQ12,PBAQ12,PAMQ12,PAAQ12 | 8 | 510302R00-185-G | MOS N,BSS138,50V,0.22A,6ohm@4.5V,G,SOT23-3,SMD | FAIRCHILD SEMICONDUCTOR CORP | BSS138 | G | PWA BOM | In New BOM |
|  |  |  | 510309C00-237-G | MOS N,BSS138-7-F,50V,0.2A,3.5ohm@10V,G,SOT23-3,SMD | DIODES INCORPORATION | BSS138-7-F | G | PWA BOM | In New BOM |
|  |  |  | 510301D00-223-G | MOS N,BSS138LT1G,50V,0.2A,3.5ohm@5V,G,SOT23-3,SMD | ON SEMICONDUCTOR CORP | BSS138LT1G | G | PWA BOM | In New BOM |
|  | PBFQ10,PBEQ10,PAFQ10,PAEQ10,PBMQ12,PBAQ12,PAMQ12,PAAQ12 | 8 | 510302R00-185-G | MOS N,BSS138,50V,0.22A,6ohm@4.5V,G,SOT23-3,SMD | FAIRCHILD SEMICONDUCTOR CORP | BSS138 | N | PWA BOM | In Old BOM |
|  |  |  | 510309C00-237-G | MOS N,BSS138-7-F,50V,0.2A,3.5ohm@10V,G,SOT23-3,SMD | DIODES INCORPORATION | BSS138-7-F | G | PWA BOM | In Old BOM |
|  |  |  | 510301D00-223-G | MOS N,BSS138LT1G,50V,0.2A,3.5ohm@5V,G,SOT23-3,SMD | ON SEMICONDUCTOR CORP | BSS138LT1G | G | PWA BOM | In Old BOM |
| 315 | R1,R2,PSTR2,PSPR2,PSLR2,PSFR2,PSER2,PSDR2,PQPR2,PIPR2,PFPR2,PEPR2,PEER2,PEDR2,PBFR2,PBER2,PBAR2,PAFR2,PAER2,PAAR2,PBNR3,PBER3,PBAR3,PANR3,PAER3,PAAR3,PBNR4,PBFR4,PBAR4,PANR4,PAFR4,PAAR4,R6,PBAR6,PAMR6,R7,PSPR7,PIPR7,PFPR7,PEPR7,PBFR7,PAER7,PAAR7,PSRR8,PSPR8,PSLR8,PSFR8,PSDR8,PQPR8,PIPR8,PFRR8,PFPR8,PEPR8,PEER8,PEDR8,PAFR8,PAER8,PSTR9,PSLR9,PSFR9,PSER9,PSDR9,PQPR9,PFRR9,PEER9,PEDR9,PBER9,PBAR9,PAMR9,PHAR10,PBFR10,PAAR10,PBMR11,PBER11,PAFR11,PUAR12,PSIR12,PSAR12,PRAR12,PQAR12,PPAR12,PIAR12,PHAR12,PFAR12,PETR12,PERR12,PEAR12,PBNR12,PANR12,PBER13,PAAR13,PUAR14,PSRR14,PSPR14,PSAR14,PRAR14,PQAR14,PPAR14,PIPR14,PIAR14,PFPR14,PFAR14,PEPR14,PEAR14,PBMR14,PBFR14,PAFR14,PUAR15,PSTR15,PSRR15,PSLR15,PSFR15,PSER15,PSDR15,PSAR15,PRAR15,PQPR15,PQAR15,PPAR15,PIAR15,PFRR15,PFAR15,PEER15,PEDR15,PEAR15,PBFR15,PBER15,PBAR15,PAFR15,PAER15,PAAR15,PSIR16,PETR16,PERR16,PBMR16,PBAR16,PAMR16,PAER16,PALR17,PSTR18,PSLR18,PSFR18,PSER18,PSDR18,PQPR18,PFRR18,PEER18,PEDR18,PBMR18,PBFR18,PBER18,PBAR18,PAMR18,PAFR18,PAER18,PAAR18,PBLR19,PBNR20,PANR20,PSRR22,PSPR22,PIPR22,PFPR22,PEPR22,PBMR22,PBFR22,PBER22,PBAR22,PAMR22,PAFR22,PAER22,PAAR22,PHAR24,PHAR25,PBMR25,PBFR25,PBER25,PBAR25,PAMR25,PAFR25,PAER25,PAAR25,PBMR28,PBFR28,PBER28,PBAR28,PAMR28,PAFR28,PAER28,PAAR28,R29,R30,PBMR30,PBFR30,PBER30,PBAR30,PAMR30,PAFR30,PAER30,PAAR30,PHAR31,PHAR32,PBMR32,PBFR32,PBER32,PBAR32,PAMR32,PAFR32,PAER32,PAAR32,PHAR33,PBMR33,PBFR33,PBER33,PBAR33,PAMR33,PAFR33,PAER33,PAAR33,PHAR34,PBMR35,PBFR35,PBER35,PBAR35,PAMR35,PAFR35,PAER35,PAAR35,PBMR36,PBFR36,PBER36,PBAR36,PAMR36,PAFR36,PAER36,PAAR36,PBMR38,PBFR38,PBER38,PBAR38,PAMR38,PAFR38,PAER38,PAAR38,PBMR39,PBAR39,PAMR39,PAAR39,PBMR42,PBFR42,PBER42,PBAR42,PAMR42,PAFR42,PAER42,PAAR42,PBMR46,PAMR46,PBMR56,PBFR56,PBER56,PBAR56,PAMR56,PAFR56,PAER56,PAAR56,PBMR66,PAMR67,PAAR67,PBAR68,PAMR68,PAAR68,PBAR69,PAAR69,R70,PBMR70,PBAR70,R71,R72,PBAR72,PAAR72,R73,R74,R75,PAFR77,PAER77,PBFR78,PBER78,PAFR78,PAER78,R79,PBMR79,PBFR79,PBER79,PAMR79,PAFR79,PAER79,R80,PBFR80,R81,PBER81,PBAR81,PAFR81,PAER81,PAAR81,R82,PBFR82,PBER82,PAER82,R83,R84,R85,R86,R87,PBMR87,PBER87,PAMR87,PBER89,PBAR89,PAFR89,PAER89,PAAR89,PBFR90,PBER93,PAFR93,PAER93,PBFR94,PBER96,PAFR96,PAER96,PBFR97,PBAR101,PAAR101,PBMR103,PAMR103,PBMR104,PAMR104,PBER105,PAFR105,PAER105,PBFR106,PBER106,PAFR106,PAER106,PBFR107,PBAR109,PAAR109,PBMR110,PBAR110,PAMR110,PAAR110,PBMR111,PAMR111,PBER112,PAFR112,PAER112,PBFR113,PBER113,PAFR113,PAER113,PBFR114,PBMR115,PAMR115,PBMR116,PBAR116,PAMR116,PAAR116,PBER117,PBAR117,PAFR117,PAER117,PAAR117,PBFR118,PBER118,PAFR118,PAER118,PBFR119,PBAR121,PAAR121,PBAR122,PAAR122,PBFR302,PBER302,PBAR302,PAFR302,PAER302,PAAR302,R303,PBMR303,PBFR303,PBER303,PBAR303,PAMR303,PAFR303,PAER303,PAAR303,R306,R308,PBMR308,PBAR308,PAMR308,PAAR308,R309,PBMR309,PBAR309,PAMR309,PAAR309,PBFR310,PAFR310,PAER310,R311,PBER311,R312,PBFR312,PAFR312,PAER312,R313,PBER313,PBAR313,PAAR313,R314,R315,R316,R317,R320,R321,R322,R323,R324,R325,R326,R331,R363,R364,R368,R369,R414,R415,R428,R429,R430,R431,R433,R434,R437,R438,R439,R440,R467,R473,R474,R477,R478,R479,PSUR500,PBNR500,PBMR500,PBFR500,PBER500,PANR500,PAMR500,PAFR500,PAER500,PAAR500,PSUR501,PBNR501,PBMR501,PBFR501,PBER501,PANR501,PAMR501,PAFR501,PAER501,PAAR501,PBAR502,PBAR503,PBFR514,PBER514,PAFR514,PBFR515,PBER515,PAFR515,PAER515,PBFR516,PBER516,PAFR516,PAER516,PAER517,PBMR607,PBAR607,PAMR607,PAAR607,PBMR608,PBAR608,PAMR608,PAAR608,R670,R671,R674,R677,R717,R722,R723,R724,R726,R728,R744,R745,R747,R750,R754,R757,R760,R761,R768,R785,R798,R802,R810,R812,R813,R824,R826,R895,R896,R899,R900,R909,R911,R918,R919,R921,R923,R924,R926,R928,R930,R931,R941,R946,R947,R951,R952,R973,R974,R979,R987,R1004,R1005,R1073,R1082,R1086,R1099,R1100,R1116,R1117,R1130,R1131,R1132,R1133,R1134,R1143,R1145,R1146,R1158,R1160,R1166,R1167,R1168,R1170,R1177,R1178,R1179,R1180,R1182,R1187,R1188,R1191,R1192,R1194,R1200,R1201,R1203,R1204,R1207,R1208,R1214,R1215,R1216,R1226,R1228,R1233,R1235,R1236,R1238,R1241,R1242,R1243,R1244,R1245,R1246,R1247,R1248,R1249,R1250,R1259,R1260,R1281,R1282,R1283,R1284,R1285,R1286,R1289,R1290,R1291,R1292,R1293,R1297,R1321,R1322,R1330,R1339,R1344,R1360,R1362,R1369,R1370,R1372,R1373,R1375,R1376,R1406,R1407,R1432,R1433,R1434,R1435,R1436,R1437,R1438,R1439,R1442,R1443,R1445,R1472,R1473,R1478,R1491,R1496,R1497,R1501,R1502,R1503,R1510,R1514,R1522,R1527,R1528,R1531,R1532,R1549,R1552,R1554,R1555,R1556,R1599,R1600,R1720,R1721,R1722,R1724,R1725,R1752,R1753,R1776,R1787,R1788,R1803,R1804,R1805,R1806,R1807,R1808,R1809,R1810,R1812,R1813,R1814,R1815,R1816,R1817,R1818,R1819,R1825,R1826,R1832,R1833,R1835,R1837,R1840,R1841,R1842,R1843,PSPR3001,PIPR3001,PFPR3001,PEPR3001,PSPR3002,PIPR3002,PFPR3002,PEPR3002,PSRR3003,PSPR3003,PIPR3003,PFPR3003,PEPR3003,PSRR3005,PSRR3008 | 719 | 610107A00-017-G | RES,0 Ohm,+/-5%,1/16W,G,SMD0402 | KOA SPEER ELECTRONICS, INC. | RK73Z1ETTP | G | PWA BOM | In New BOM |
|  |  |  | 610107A00-012-G | RES,0 Ohm,+/-5%,1/16W,G,SMD0402 | WALSIN TECHNOLOGY CORPORATION | WR04X000PTL | G | PWA BOM | In New BOM |
|  |  |  | 610107A00-011-G | RES,0 Ohm,+/-5%,1/16W,G,SMD0402 | YAGEO CORPORATION COMPONENT | RC0402JR-070RL | G | PWA BOM | In New BOM |
|  |  |  | 610107A00-044-G | RES,0 Ohm,+/-5%,1/16W,G,SMD0402 | TA-I TECHNOLOGY CO., LTD | RM04JTN0 | G | PWA BOM | In New BOM |
|  |  |  | 610107A00-024-G | RES,0 Ohm,+/-5%,1/16W,G,SMD0402 | PANASONIC INDUSTRIAL CO.,LTD. | ERJ2GE0R00X | G | PWA BOM | In New BOM |
|  |  |  | 610107A00-029-G | RES,0 Ohm,+/-5%,1/16W,G,SMD0402 | VISHAY ENTER TECHNO LOGY.INC | CRCW04020000Z0ED | G | PWA BOM | In New BOM |
|  | R1,R2,PSTR2,PSPR2,PSLR2,PSFR2,PSER2,PSDR2,PQPR2,PIPR2,PFPR2,PEPR2,PEER2,PEDR2,PBFR2,PBER2,PBAR2,PAFR2,PAER2,PAAR2,PBNR3,PBER3,PBAR3,PANR3,PAER3,PAAR3,PBNR4,PBFR4,PBAR4,PANR4,PAFR4,PAAR4,R6,PBAR6,PAMR6,R7,PSPR7,PIPR7,PFPR7,PEPR7,PBFR7,PAER7,PAAR7,PSRR8,PSPR8,PSLR8,PSFR8,PSDR8,PQPR8,PIPR8,PFRR8,PFPR8,PEPR8,PEER8,PEDR8,PAFR8,PAER8,PSTR9,PSLR9,PSFR9,PSER9,PSDR9,PQPR9,PFRR9,PEER9,PEDR9,PBER9,PBAR9,PAMR9,PHAR10,PBFR10,PAAR10,PBMR11,PBER11,PAFR11,PUAR12,PSIR12,PSAR12,PRAR12,PQAR12,PPAR12,PIAR12,PHAR12,PFAR12,PETR12,PERR12,PEAR12,PBNR12,PANR12,PBER13,PAAR13,PUAR14,PSRR14,PSPR14,PSAR14,PRAR14,PQAR14,PPAR14,PIPR14,PIAR14,PFPR14,PFAR14,PEPR14,PEAR14,PBMR14,PBFR14,PAFR14,PUAR15,PSTR15,PSRR15,PSLR15,PSFR15,PSER15,PSDR15,PSAR15,PRAR15,PQPR15,PQAR15,PPAR15,PIAR15,PFRR15,PFAR15,PEER15,PEDR15,PEAR15,PBFR15,PBER15,PBAR15,PAFR15,PAER15,PAAR15,PSIR16,PETR16,PERR16,PBMR16,PBAR16,PAMR16,PAER16,PALR17,PSTR18,PSLR18,PSFR18,PSER18,PSDR18,PQPR18,PFRR18,PEER18,PEDR18,PBMR18,PBFR18,PBER18,PBAR18,PAMR18,PAFR18,PAER18,PAAR18,PBLR19,PBNR20,PANR20,PSRR22,PSPR22,PIPR22,PFPR22,PEPR22,PBMR22,PBFR22,PBER22,PBAR22,PAMR22,PAFR22,PAER22,PAAR22,PHAR24,PHAR25,PBMR25,PBFR25,PBER25,PBAR25,PAMR25,PAFR25,PAER25,PAAR25,PBMR28,PBFR28,PBER28,PBAR28,PAMR28,PAFR28,PAER28,PAAR28,R29,R30,PBMR30,PBFR30,PBER30,PBAR30,PAMR30,PAFR30,PAER30,PAAR30,PHAR31,PHAR32,PBMR32,PBFR32,PBER32,PBAR32,PAMR32,PAFR32,PAER32,PAAR32,PHAR33,PBMR33,PBFR33,PBER33,PBAR33,PAMR33,PAFR33,PAER33,PAAR33,PHAR34,PBMR35,PBFR35,PBER35,PBAR35,PAMR35,PAFR35,PAER35,PAAR35,PBMR36,PBFR36,PBER36,PBAR36,PAMR36,PAFR36,PAER36,PAAR36,PBMR38,PBFR38,PBER38,PBAR38,PAMR38,PAFR38,PAER38,PAAR38,PBMR39,PBAR39,PAMR39,PAAR39,PBMR42,PBFR42,PBER42,PBAR42,PAMR42,PAFR42,PAER42,PAAR42,PBMR46,PAMR46,PBMR56,PBFR56,PBER56,PBAR56,PAMR56,PAFR56,PAER56,PAAR56,PBMR66,PAMR67,PAAR67,PBAR68,PAMR68,PAAR68,PBAR69,PAAR69,R70,PBMR70,PBAR70,R71,R72,PBAR72,PAAR72,R73,R74,R75,PAFR77,PAER77,PBFR78,PBER78,PAFR78,PAER78,R79,PBMR79,PBFR79,PBER79,PAMR79,PAFR79,PAER79,R80,PBFR80,R81,PBER81,PBAR81,PAFR81,PAER81,PAAR81,R82,PBFR82,PBER82,PAER82,R83,R84,R85,R86,R87,PBMR87,PBER87,PAMR87,PBER89,PBAR89,PAFR89,PAER89,PAAR89,PBFR90,PBER93,PAFR93,PAER93,PBFR94,PBER96,PAFR96,PAER96,PBFR97,PBAR101,PAAR101,PBMR103,PAMR103,PBMR104,PAMR104,PBER105,PAFR105,PAER105,PBFR106,PBER106,PAFR106,PAER106,PBFR107,PBAR109,PAAR109,PBMR110,PBAR110,PAMR110,PAAR110,PBMR111,PAMR111,PBER112,PAFR112,PAER112,PBFR113,PBER113,PAFR113,PAER113,PBFR114,PBMR115,PAMR115,PBMR116,PBAR116,PAMR116,PAAR116,PBER117,PBAR117,PAFR117,PAER117,PAAR117,PBFR118,PBER118,PAFR118,PAER118,PBFR119,PBAR121,PAAR121,PBAR122,PAAR122,PBFR302,PBER302,PBAR302,PAFR302,PAER302,PAAR302,R303,PBMR303,PBFR303,PBER303,PBAR303,PAMR303,PAFR303,PAER303,PAAR303,R306,R308,PBMR308,PBAR308,PAMR308,PAAR308,R309,PBMR309,PBAR309,PAMR309,PAAR309,PBFR310,PAFR310,PAER310,R311,PBER311,R312,PBFR312,PAFR312,PAER312,R313,PBER313,PBAR313,PAAR313,R314,R315,R316,R317,R320,R321,R322,R323,R324,R325,R326,R331,R363,R364,R368,R369,R414,R415,R428,R429,R430,R431,R433,R434,R437,R438,R439,R440,R467,R473,R474,R477,R478,R479,PSUR500,PBNR500,PBMR500,PBFR500,PBER500,PANR500,PAMR500,PAFR500,PAER500,PAAR500,PSUR501,PBNR501,PBMR501,PBFR501,PBER501,PANR501,PAMR501,PAFR501,PAER501,PAAR501,PBAR502,PBAR503,PBFR514,PBER514,PAFR514,PBFR515,PBER515,PAFR515,PAER515,PBFR516,PBER516,PAFR516,PAER516,PAER517,PBMR607,PBAR607,PAMR607,PAAR607,PBMR608,PBAR608,PAMR608,PAAR608,R670,R671,R674,R677,R717,R722,R723,R724,R726,R728,R744,R745,R747,R750,R754,R757,R760,R761,R768,R785,R798,R802,R810,R812,R813,R824,R826,R895,R896,R899,R900,R909,R911,R918,R919,R921,R923,R924,R926,R928,R930,R931,R941,R946,R947,R951,R952,R973,R974,R979,R987,R1004,R1005,R1073,R1082,R1086,R1099,R1100,R1116,R1117,R1130,R1131,R1132,R1133,R1134,R1143,R1145,R1146,R1158,R1160,R1166,R1167,R1168,R1170,R1177,R1178,R1179,R1180,R1182,R1187,R1188,R1191,R1192,R1194,R1200,R1201,R1203,R1204,R1207,R1208,R1214,R1215,R1216,R1226,R1228,R1233,R1235,R1236,R1238,R1241,R1242,R1243,R1244,R1245,R1246,R1247,R1248,R1249,R1250,R1259,R1260,R1281,R1282,R1283,R1284,R1285,R1286,R1289,R1290,R1291,R1292,R1293,R1297,R1321,R1322,R1330,R1339,R1344,R1360,R1362,R1369,R1370,R1372,R1373,R1375,R1376,R1406,R1407,R1432,R1433,R1434,R1435,R1436,R1437,R1438,R1439,R1442,R1443,R1445,R1472,R1473,R1478,R1491,R1496,R1497,R1501,R1502,R1503,R1510,R1514,R1522,R1527,R1528,R1531,R1532,R1549,R1552,R1554,R1555,R1556,R1599,R1600,R1720,R1721,R1722,R1724,R1725,R1752,R1753,R1776,R1787,R1788,R1803,R1804,R1805,R1806,R1807,R1808,R1809,R1810,R1812,R1813,R1814,R1815,R1816,R1817,R1818,R1819,R1825,R1826,R1832,R1833,R1835,R1837,R1840,R1841,R1842,R1843,PSPR3001,PIPR3001,PFPR3001,PEPR3001,PSPR3002,PIPR3002,PFPR3002,PEPR3002,PSRR3003,PSPR3003,PIPR3003,PFPR3003,PEPR3003,PSRR3005,PSRR3008 | 719 | 610107A00-017-G | RES,0 Ohm,+/-5%,1/16W,G,SMD0402 | KOA SPEER ELECTRONICS, INC. | RK73Z1ETTP | N | PWA BOM | In Old BOM |
|  |  |  | 610107A00-012-G | RES,0 Ohm,+/-5%,1/16W,G,SMD0402 | WALSIN | WR04X000PTL | G | PWA BOM | In Old BOM |
|  |  |  | 610107A00-011-G | RES,0 Ohm,+/-5%,1/16W,G,SMD0402 | YAGEO | RC0402JR-070RL | G | PWA BOM | In Old BOM |
|  |  |  | 610107A00-044-G | RES,0 Ohm,+/-5%,1/16W,G,SMD0402 | TA-I | RM04JTN0 | G | PWA BOM | In Old BOM |
|  |  |  | 610107A00-024-G | RES,0 Ohm,+/-5%,1/16W,G,SMD0402 | PANASONIC INDUSTRIAL CO.,LTD. | ERJ2GE0R00X | G | PWA BOM | In Old BOM |
|  |  |  | 610107A00-029-G | RES,0 Ohm,+/-5%,1/16W,G,SMD0402 | VISHAY ENTER TECHNO LOGY.INC | CRCW04020000Z0ED | G | PWA BOM | In Old BOM |
| 316 | PBAR26,PAAR26 | 2 | 61100YD00-017-G | RES,9.53KOhm,+/-0.1%,1/16W,G,SMD0402 | KOA SPEER ELECTRONICS, INC. | RN731ETTP9531B25 | G | PWA BOM | In New BOM |
|  |  |  | 61100YD00-024-G | RES,9.53KOhm,+/-0.1%,1/16W,G,SMD0402 | PANASONIC INDUSTRIAL CO.,LTD. | ERA2AEB9531X | G | PWA BOM | In New BOM |
|  | PBAR26,PAAR26 | 2 | 61100YD00-017-G | RES,9.53KOhm,+/-0.1%,1/16W,G,SMD0402 | KOA SPEER ELECTRONICS, INC. | RN731ETTP9531B25 |  | PWA BOM | In Old BOM |
|  |  |  | 61100YD00-024-G | RES,9.53KOhm,+/-0.1%,1/16W,G,SMD0402 | PANASONIC INDUSTRIAL CO.,LTD. | ERA2AEB9531X | G | PWA BOM | In Old BOM |
| 317 | PBMR54,PBFR54,PBER54,PBAR54,PAMR54,PAFR54,PAER54,PAAR54 | 8 | 61011MC02-017-G | Res,374 Ohm,+/-1%,1/16W,G,SMD0402 | KOA SPEER ELECTRONICS, INC. | RK73H1ETTP3740F | G | PWA BOM | In New BOM |
|  |  |  | 61011MC00-024-G | RES,thick film,374Ohm,+/-1%,1/16W,SMD0402,G | PANASONIC INDUSTRIAL CO.,LTD. | ERJ2RKF3740X | G | PWA BOM | In New BOM |
|  |  |  | 61011MC00-029-G | RES,thick film,374Ohm,+/-1%,1/16W,SMD0402,G | VISHAY ENTER TECHNO LOGY.INC | CRCW0402374RFKED | G | PWA BOM | In New BOM |
|  | PBMR54,PBFR54,PBER54,PBAR54,PAMR54,PAFR54,PAER54,PAAR54 | 8 | 61011MC02-017-G | Res,374 Ohm,+/-1%,1/16W,G,SMD0402 | KOA SPEER ELECTRONICS, INC. | RK73H1ETTP3740F | N | PWA BOM | In Old BOM |
|  |  |  | 61011MC00-024-G | RES,thick film,374Ohm,+/-1%,1/16W,SMD0402,G | PANASONIC INDUSTRIAL CO.,LTD. | ERJ2RKF3740X | G | PWA BOM | In Old BOM |
|  |  |  | 61011MC00-029-G | RES,thick film,374Ohm,+/-1%,1/16W,SMD0402,G | VISHAY ENTER TECHNO LOGY.INC | CRCW0402374RFKED | G | PWA BOM | In Old BOM |
| 318 | PBAR61,PAAR61 | 2 | 61100QG00-017-G | RES,649 Ohm,+/-0.1%,1/16W,G,SMD0402 | KOA SPEER ELECTRONICS, INC. | RN731ETTP6490B25 | G | PWA BOM | In New BOM |
|  |  |  | 61100QG00-024-G | RES,649 Ohm,+/-0.1%,1/16W,G,SMD0402 | PANASONIC INDUSTRIAL CO.,LTD. | ERA2AEB6490X | G | PWA BOM | In New BOM |
|  |  |  | 61100QG00-029-G | RES,649 Ohm,+/-0.1%,1/16W,G,SMD0402 | VISHAY ENTER TECHNO LOGY.INC | TNPW0402649RBEED | G | PWA BOM | In New BOM |
|  | PBAR61,PAAR61 | 2 | 61100QG00-017-G | RES,649 Ohm,+/-0.1%,1/16W,G,SMD0402 | KOA SPEER ELECTRONICS, INC. | RN731ETTP6490B25 | Y | PWA BOM | In Old BOM |
|  |  |  | 61100QG00-024-G | RES,649 Ohm,+/-0.1%,1/16W,G,SMD0402 | PANASONIC INDUSTRIAL CO.,LTD. | ERA2AEB6490X | G | PWA BOM | In Old BOM |
|  |  |  | 61100QG00-029-G | RES,649 Ohm,+/-0.1%,1/16W,G,SMD0402 | VISHAY ENTER TECHNO LOGY.INC | TNPW0402649RBEED | G | PWA BOM | In Old BOM |
| 319 | PAAR66,PBAR67,PBAR79,PAAR79 | 4 | 610103D00-017-G | RES,24.3KOhm,+/-1%,1/10W,G,SMD0603 | KOA SPEER ELECTRONICS, INC. | RK73H1JTTD2432F | G | PWA BOM | In New BOM |
|  | PAAR66,PBAR67,PBAR79,PAAR79 | 4 | 610103D00-017-G | RES,24.3KOhm,+/-1%,1/10W,G,SMD0603 | KOA SPEER ELECTRONICS, INC. | RK73H1JTTD2432F | N | PWA BOM | In Old BOM |
| 320 | PBAR80,PAAR80 | 2 | 61010DG00-017-G | RES,4.99KOhm,+/-1%,1/10W,G,SMD0603 | KOA SPEER ELECTRONICS, INC. | RK73H1JTTD4991F | G | PWA BOM | In New BOM |
|  | PBAR80,PAAR80 | 2 | 61010DG00-017-G | RES,4.99KOhm,+/-1%,1/10W,G,SMD0603 | KOA SPEER ELECTRONICS, INC. | RK73H1JTTD4991F | N | PWA BOM | In Old BOM |
| 321 | PSPR6,PIPR6,PFPR6,PEPR6,PALR14,PALR15,PBLR20,PBLR21,PBER68,PBMR82,PAMR82,PBAR85,PAAR85,PAFR87,PAER87,PBFR88,PBMR91,PAMR91,PBAR93,PAAR93,PBMR94,PAMR94,PBAR96,PAAR96,R1484,R1745,R1785 | 27 | 61100LR00-017-G | RES,100 Ohm,+/-1%,1/16W,G,SMD0402 | KOA SPEER ELECTRONICS, INC. | RN731ETTP1000F50 | G | PWA BOM | In New BOM |
|  |  |  | 61100LR00-012-G | RES,100 Ohm,+/-1%,1/16W,G,SMD0402 | WALSIN TECHNOLOGY CORPORATION | WF04T1000FTL | G | PWA BOM | In New BOM |
|  |  |  | 61100LR01-011-G | RES,100 Ohm,+/-1%,1/16W,G,SMD0402 | YAGEO CORPORATION COMPONENT | RT0402FRE07100RL | G | PWA BOM | In New BOM |
|  |  |  | 61100LR00-044-G | RES,100 Ohm,+/-1%,1/16W,G,SMD0402 | TA-I TECHNOLOGY CO., LTD | RB04FTS1000 | G | PWA BOM | In New BOM |
|  | PSPR6,PIPR6,PFPR6,PEPR6,PALR14,PALR15,PBLR20,PBLR21,PBER68,PBMR82,PAMR82,PBAR85,PAAR85,PAFR87,PAER87,PBFR88,PBMR91,PAMR91,PBAR93,PAAR93,PBMR94,PAMR94,PBAR96,PAAR96,R1484,R1745,R1785 | 27 | 61100LR00-017-G | RES,100 Ohm,+/-1%,1/16W,G,SMD0402 | KOA SPEER ELECTRONICS, INC. | RN731ETTP1000F50 |  | PWA BOM | In Old BOM |
|  |  |  | 61100LR00-012-G | RES,100 Ohm,+/-1%,1/16W,G,SMD0402 | WALSIN | WF04T1000FTL | G | PWA BOM | In Old BOM |
|  |  |  | 61100LR01-011-G | RES,100 Ohm,+/-1%,1/16W,G,SMD0402 | YAGEO | RT0402FRE07100RL | G | PWA BOM | In Old BOM |
|  |  |  | 61100LR00-044-G | RES,100 Ohm,+/-1%,1/16W,G,SMD0402 | TA-I | RB04FTS1000 | G | PWA BOM | In Old BOM |
| 322 | PALR19,PALR20,PBLR23,PBLR24 | 4 | 61100LR00-017-G | RES,100 Ohm,+/-1%,1/16W,G,SMD0402 | KOA SPEER ELECTRONICS, INC. | RN731ETTP1000F50 | G | PWA BOM | In New BOM |
|  |  |  | 61100LR00-012-G | RES,100 Ohm,+/-1%,1/16W,G,SMD0402 | WALSIN TECHNOLOGY CORPORATION | WF04T1000FTL | G | PWA BOM | In New BOM |
|  |  |  | 61100LR01-011-G | RES,100 Ohm,+/-1%,1/16W,G,SMD0402 | YAGEO CORPORATION COMPONENT | RT0402FRE07100RL | G | PWA BOM | In New BOM |
|  |  |  | 61100LR00-044-G | RES,100 Ohm,+/-1%,1/16W,G,SMD0402 | TA-I TECHNOLOGY CO., LTD | RB04FTS1000 | G | PWA BOM | In New BOM |
|  | PALR19,PALR20,PBLR23,PBLR24 | 4 | 610113800-017-G | RES,10 Ohm,+/-1%,1/16W,G,SMD0402 | KOA SPEER ELECTRONICS, INC. | RK73H1ETTP10R0F | N | PWA BOM | In Old BOM |
|  |  |  | 610113800-012-G | RES,10 Ohm,+/-1%,1/16W,G,SMD0402 | WALSIN | WR04X10R0FTL | G | PWA BOM | In Old BOM |
|  |  |  | 610113800-011-G | RES,10 Ohm,+/-1%,1/16W,G,SMD0402 | YAGEO | RC0402FR-0710RL | G | PWA BOM | In Old BOM |
|  |  |  | 610113800-044-G | RES,10 Ohm,+/-1%,1/16W,G,SMD0402 | TA-I | RM04FTN10R0 | G | PWA BOM | In Old BOM |
| 323 | PBAR127,PAAR127 | 2 | 61011G600-017-G | RES,133KOhm,+/-1%,1/16W,G,SMD0402 | KOA SPEER ELECTRONICS, INC. | RK73G1ETTP1333F | G | PWA BOM | In New BOM |
|  | PBAR127,PAAR127 | 2 | 61011G600-017-G | RES,133KOhm,+/-1%,1/16W,G,SMD0402 | KOA SPEER ELECTRONICS, INC. | RK73G1ETTP1333F |  | PWA BOM | In Old BOM |
| 324 | PBFR511,PBER511,PAFR511,PAER511,PBMR603,PBAR603,PAMR603,PAAR603,PBMR604,PBAR604,PAMR604,PAAR604,PAFR634,PBFR659,PBER659,PAER684 | 16 | 61010L100-017-G | RES,100KOhm,+/-1%,1/16W,G,SMD0402 | KOA SPEER ELECTRONICS, INC. | RK73H1ETTP1003F | G | PWA BOM | In New BOM |
|  |  |  | 61010L100-012-G | RES,100KOhm,+/-1%,1/16W,G,SMD0402 | WALSIN TECHNOLOGY CORPORATION | WR04X1003FTL | G | PWA BOM | In New BOM |
|  |  |  | 61010L100-011-G | RES,100KOhm,+/-1%,1/16W,G,SMD0402 | YAGEO CORPORATION COMPONENT | RC0402FR-07100KL | G | PWA BOM | In New BOM |
|  |  |  | 61010L100-044-G | RES,100KOhm,+/-1%,1/16W,G,SMD0402 | TA-I TECHNOLOGY CO., LTD | RM04FTN1003 | G | PWA BOM | In New BOM |
|  |  |  | 61010L106-029-G | RES,100KOhm,+/-1%,1/16W,G,SMD0402 | VISHAY ENTER TECHNO LOGY.INC | CRCW0402100KFKEDC | G | PWA BOM | In New BOM |
|  |  |  | 61010L100-024-G | RES,100KOhm,+/-1%,1/16W,G,SMD0402 | PANASONIC INDUSTRIAL CO.,LTD. | ERJ2RKF1003X | G | PWA BOM | In New BOM |
|  | PBFR511,PBER511,PAFR511,PAER511,PBMR603,PBAR603,PAMR603,PAAR603,PBMR604,PBAR604,PAMR604,PAAR604,PAFR634,PBFR659,PBER659,PAER684 | 16 | 61010L100-017-G | RES,100KOhm,+/-1%,1/16W,G,SMD0402 | KOA SPEER ELECTRONICS, INC. | RK73H1ETTP1003F | N | PWA BOM | In Old BOM |
|  |  |  | 61010L100-012-G | RES,100KOhm,+/-1%,1/16W,G,SMD0402 | WALSIN | WR04X1003FTL | G | PWA BOM | In Old BOM |
|  |  |  | 61010L100-011-G | RES,100KOhm,+/-1%,1/16W,G,SMD0402 | YAGEO | RC0402FR-07100KL | G | PWA BOM | In Old BOM |
|  |  |  | 61010L100-044-G | RES,100KOhm,+/-1%,1/16W,G,SMD0402 | TA-I | RM04FTN1003 | G | PWA BOM | In Old BOM |
|  |  |  | 61010L106-029-G | RES,100KOhm,+/-1%,1/16W,G,SMD0402 | VISHAY ENTER TECHNO LOGY.INC | CRCW0402100KFKEDC | G | PWA BOM | In Old BOM |
|  |  |  | 61010L100-024-G | RES,100KOhm,+/-1%,1/16W,G,SMD0402 | PANASONIC INDUSTRIAL CO.,LTD. | ERJ2RKF1003X | G | PWA BOM | In Old BOM |
| 325 | PBMU1,PBFU1,PBEU1,PBAU1,PAMU1,PAFU1,PAEU1,PAAU1 | 8 | 320242200-230-G | IC,PWM Controller,ISL68137IRAZ-T,G,QFN-48,SMD | INTERSIL CORPORATION | ISL68137IRAZ-T | G | PWA BOM | In New BOM |
|  | PBMU1,PBFU1,PBEU1,PBAU1,PAMU1,PAFU1,PAEU1,PAAU1 | 8 | 320242200-230-G | IC,PWM Controller,ISL68137IRAZ-T,G,QFN-48,SMD | INTERSIL CORPORATION | ISL68137IRAZ-T |  | PWA BOM | In Old BOM |
| 326 | PBMU2,PBFU2,PBEU2,PBAU2,PAMU2,PAFU2,PAEU2,PAAU2 | 8 | 32040FG00-183-G | IC,Current Sensor,INA193AIDBVR,G,SOT23-5,SMD | TEXAS INSTRUMENTS | INA193AIDBVR | G | PWA BOM | In New BOM |
|  | PBMU2,PBFU2,PBEU2,PBAU2,PAMU2,PAFU2,PAEU2,PAAU2 | 8 | 32040FG00-183-G | IC,Current Sensor,INA193AIDBVR,G,SOT23-5,SMD | TEXAS INSTRUMENTS | INA193AIDBVR | N | PWA BOM | In Old BOM |
| 327 | PBAU4,PAAU4,PBAU6,PAAU6 | 4 | 880302200-53N-G | Converter,input 0V~60V,185W,G,VTM48MP012T130AA0 | Vicor Corporation | VTM48MP012T130AA0 | G | PWA BOM | In New BOM |
|  | PBAU4,PAAU4,PBAU6,PAAU6 | 4 | 880302200-53N-G | Converter,input 0V~60V,185W,G,VTM48MP012T130AA0 | Vicor Corporation | VTM48MP012T130AA0 |  | PWA BOM | In Old BOM |
| 328 | PBMU5,PBFU5,PBEU5,PAMU5,PAFU5,PAEU5,PBAU7,PAAU7 | 8 | 32031MS00-183-G | IC,Operation Amplifier,OPA2365AIDR,G,SOIC-8,SMD | TEXAS INSTRUMENTS | OPA2365AIDR | G | PWA BOM | In New BOM |
|  | PBMU5,PBFU5,PBEU5,PAMU5,PAFU5,PAEU5,PBAU7,PAAU7 | 8 | 32031MS00-183-G | IC,Operation Amplifier,OPA2365AIDR,G,SOIC-8,SMD | TEXAS INSTRUMENTS | OPA2365AIDR |  | PWA BOM | In Old BOM |
| 329 | PBFC4,PBEC4,PAFC4,PAEC4 | 4 | 620108600-015-G | CAP,180pF,+/-5%,NPO(C0G),50V,G,SMD0402 | MURATA ELEC. NORTH AMERICA | GRM1555C1H181J | G | PWA BOM | In New BOM |
|  | PBFC4,PBEC4,PAFC4,PAEC4 | 4 | 620108600-015-G | CAP,180pF,+/-5%,NPO(C0G),50V,G,SMD0402 | MURATA ELEC. NORTH AMERICA | GRM1555C1H181J | N | PWA BOM | In Old BOM |
| 330 | PBFFS1,PBEFS1,PAMFS1,PAFFS1,PAEFS1,PAMFS2 | 6 | 730100L00-086-G | Fuse,Very fast acting,125V,5A,G,SMD | LITTELFUSE FAR EAST PTE LTD | 0451005.MRL | G | PWA BOM | In New BOM |
|  |  |  | 730107B01-088-G | Fuse,Fast acting,125V,5A,SMD,G | COOPER BUSSMANN, INC. | CB61F5A-TR2 | G | PWA BOM | In New BOM |
|  | PBFFS1,PBEFS1,PAMFS1,PAFFS1,PAEFS1,PAMFS2 | 6 | 730100L00-086-G | Fuse,Very fast acting,125V,5A,G,SMD | LITTELFUSE FAR EAST PTE LTD | 0451005.MRL | N | PWA BOM | In Old BOM |
|  |  |  | 730107B01-088-G | Fuse,Fast acting,125V,5A,SMD,G | COOPER BUSSMANN, INC. | CB61F5A-TR2 | G | PWA BOM | In Old BOM |
| 331 | PBFR34,PBER34,PAFR34,PAER34 | 4 | 61100YT00-017-G | RES,487 Ohm,+/-0.1%,1/16W,G,SMD0402 | KOA SPEER ELECTRONICS, INC. | RN731ETTP4870B25 | G | PWA BOM | In New BOM |
|  | PBFR34,PBER34,PAFR34,PAER34 | 4 | 61100YT00-017-G | RES,487 Ohm,+/-0.1%,1/16W,G,SMD0402 | KOA SPEER ELECTRONICS, INC. | RN731ETTP4870B25 | N | PWA BOM | In Old BOM |
| 332 | PBFR57,PBER57,PAFR57,PAER57 | 4 | 610127L00-017-G | RES,215 Ohm,+/-1%,1/16W,G,SMD0402 | KOA SPEER ELECTRONICS, INC. | RK73H1ETTP2150F | G | PWA BOM | In New BOM |
|  | PBFR57,PBER57,PAFR57,PAER57 | 4 | 610127L00-017-G | RES,215 Ohm,+/-1%,1/16W,G,SMD0402 | KOA SPEER ELECTRONICS, INC. | RK73H1ETTP2150F |  | PWA BOM | In Old BOM |
| 333 | PBER84,PAFR84,PAER84,PBFR85 | 4 | 610107K00-017-G | RES,24.9KOhm,+/-1%,1/10W,G,SMD0603 | KOA SPEER ELECTRONICS, INC. | RK73H1JTTD2492F | G | PWA BOM | In New BOM |
|  | PBER84,PAFR84,PAER84,PBFR85 | 4 | 610107K00-017-G | RES,24.9KOhm,+/-1%,1/10W,G,SMD0603 | KOA SPEER ELECTRONICS, INC. | RK73H1JTTD2492F | N | PWA BOM | In Old BOM |
| 334 | PBMU3,PBFU3,PBEU3,PAMU3,PAFU3,PAEU3 | 6 | 32014CE00-53N-G | IC,Regulator,PI3755-02-LGIZ,ADJ,4A,G,LGA-71,SMD | Vicor Corporation | PI3755-02-LGIZ | G | PWA BOM | In New BOM |
|  | PBMU3,PBFU3,PBEU3,PAMU3,PAFU3,PAEU3 | 6 | 32014CE00-53N-G | IC,Regulator,PI3755-02-LGIZ,ADJ,4A,G,LGA-71,SMD | Vicor Corporation | PI3755-02-LGIZ |  | PWA BOM | In Old BOM |
| 335 | PBFU4,PBEU4,PAFU4,PAEU4 | 4 | 880302600-53N-G | Converter,input 0V~52V,120W,G,VTM48RP015C076AG0 | Vicor Corporation | VTM48RP015C076AG0 | G | PWA BOM | In New BOM |
|  | PBFU4,PBEU4,PAFU4,PAEU4 | 4 | 880302600-53N-G | Converter,input 0V~52V,120W,G,VTM48RP015C076AG0 | Vicor Corporation | VTM48RP015C076AG0 |  | PWA BOM | In Old BOM |
| 336 | PHAC1,PANC1,PBNC2,PHAC7,PALC37,PBLC62 | 6 | 620131D00-015-G | CAP,1uF,+/-10%,X6S,16V,G,SMD0402 | MURATA ELEC. NORTH AMERICA | GRM155C81C105KE11J | G | PWA BOM | In New BOM |
|  |  |  | 620131D00-023-G | CAP,1uF,+/-10%,X6S,16V,G,SMD0402 | TAIYO ELECTRIC IND.CO.LTD | EMK105C6105KV-F | G | PWA BOM | In New BOM |
|  | PHAC1,PANC1,PBNC2,PHAC7,PALC37,PBLC62 | 6 | 620131D00-015-G | CAP,1uF,+/-10%,X6S,16V,G,SMD0402 | MURATA ELEC. NORTH AMERICA | GRM155C81C105KE11J |  | PWA BOM | In Old BOM |
|  |  |  | 620131D00-023-G | CAP,1uF,+/-10%,X6S,16V,G,SMD0402 | TAIYO ELECTRIC IND.CO.LTD | EMK105C6105KV-F | G | PWA BOM | In Old BOM |
| 337 | PSTL1,PSLL1,PSFL1,PSEL1,PSDL1,PQPL1,PFRL1,PEEL1,PEDL1,PBLL1,PALL1,PUAL2,PSIL2,PSAL2,PRAL2,PQAL2,PPAL2,PIAL2,PFAL2,PERL2,PEAL2,PQPL3 | 22 | 72010RE00-015-G | FB,26 Ohm@100MHz,+/-25%,6A,7mOhm,G,SMD0603 | MURATA ELEC. NORTH AMERICA | BLM18KG260TN1D | G | PWA BOM | In New BOM |
|  |  |  | 72010SJ00-059-G | FB,26 Ohm@100MHz,+/-25%,6A,10mOhm,G,SMD0603 | TAI-TECH ADVANCED ELECTRONICS CO., LTD. | HCB1608KF-260T60 | G | PWA BOM | In New BOM |
|  | PSTL1,PSLL1,PSFL1,PSEL1,PSDL1,PQPL1,PFRL1,PEEL1,PEDL1,PBLL1,PALL1,PUAL2,PSIL2,PSAL2,PRAL2,PQAL2,PPAL2,PIAL2,PFAL2,PERL2,PEAL2,PQPL3 | 22 | 72010RE00-015-G | FB,26 Ohm@100MHz,+/-25%,6A,7mOhm,G,SMD0603 | MURATA ELEC. NORTH AMERICA | BLM18KG260TN1D | N | PWA BOM | In Old BOM |
|  |  |  | 72010SJ00-059-G | FB,26 Ohm@100MHz,+/-25%,6A,10mOhm,G,SMD0603 | TAI-TECH ADVANCED ELECTRONICS CO., LTD. | HCB1608KF-260T60 | G | PWA BOM | In Old BOM |
| 338 | PALU1,PBLU3 | 2 | 320244200-230-G | IC,PWM Controller,ISL99227FRZ-T,G,QFN-32,SMD | INTERSIL CORPORATION | ISL99227FRZ-T | G | PWA BOM | In New BOM |
|  | PALU1,PBLU3 | 2 | 320244200-230-G | IC,PWM Controller,ISL99227FRZ-T,G,QFN-32,SMD | INTERSIL CORPORATION | ISL99227FRZ-T |  | PWA BOM | In Old BOM |
| 339 | PBMC4,PAMC4 | 2 | 62010BH00-015-G | CAP,220pF,+/-5%,NPO(C0G),50V,G,SMD0402 | MURATA ELEC. NORTH AMERICA | GRM1555C1H221J | G | PWA BOM | In New BOM |
|  |  |  | 62010BH02-012-G | CAP,220pF,+/-5%,NPO(C0G),50V,G,SMD0402 | WALSIN TECHNOLOGY CORPORATION | 0402N221J500CT | G | PWA BOM | In New BOM |
|  |  |  | 62010BH00-011-G | CAP,220pF,+/-5%,NPO(C0G),50V,G,SMD0402 | YAGEO CORPORATION COMPONENT | CC0402JRNPO9BN221 | G | PWA BOM | In New BOM |
|  |  |  | 62010BH00-026-G | CAP,220pF,+/-5%,NPO(C0G),50V,G,SMD0402 | SAMSUNG SEMICONDUCTOR | CL05C221JB5NNNC | G | PWA BOM | In New BOM |
|  |  |  | 62010BH03-023-G | CAP,220pF,+/-5%,NPO(C0G),50V,G,SMD0402 | TAIYO ELECTRIC IND.CO.LTD | UMK105CG221JV-F | G | PWA BOM | In New BOM |
|  | PBMC4,PAMC4 | 2 | 62010BH00-015-G | CAP,220pF,+/-5%,NPO(C0G),50V,G,SMD0402 | MURATA ELEC. NORTH AMERICA | GRM1555C1H221J | N | PWA BOM | In Old BOM |
|  |  |  | 62010BH02-012-G | CAP,220pF,+/-5%,NPO(C0G),50V,G,SMD0402 | WALSIN TECHNOLOGY CORPORATION | 0402N221J500CT | G | PWA BOM | In Old BOM |
|  |  |  | 62010BH00-011-G | CAP,220pF,+/-5%,NPO(C0G),50V,G,SMD0402 | YAGEO CORPORATION COMPONENT | CC0402JRNPO9BN221 | G | PWA BOM | In Old BOM |
|  |  |  | 62010BH00-026-G | CAP,220pF,+/-5%,NPO(C0G),50V,G,SMD0402 | SAMSUNG SEMICONDUCTOR | CL05C221JB5NNNC | G | PWA BOM | In Old BOM |
|  |  |  | 62010BH03-023-G | CAP,220pF,+/-5%,NPO(C0G),50V,G,SMD0402 | TAIYO ELECTRIC IND.CO.LTD | UMK105CG221JV-F | G | PWA BOM | In Old BOM |
| 340 | PBMR57,PAMR57 | 2 | 610119U00-017-G | RES,133 Ohm,+/-1%,1/16W,G,SMD0402 | KOA SPEER ELECTRONICS, INC. | RK73H1ETTP1330F | G | PWA BOM | In New BOM |
|  | PBMR57,PAMR57 | 2 | 610123T00-017-G | RES,232 Ohm,+/-1%,1/16W,G,SMD0402 | KOA SPEER ELECTRONICS, INC. | RK73H1ETTP2320F | N | PWA BOM | In Old BOM |
| 341 | PBMR77,PAMR77 | 2 | 61010A700-017-G | RES,30.9KOhm,+/-1%,1/10W,G,SMD0603 | KOA SPEER ELECTRONICS, INC. | RK73H1JTTD3092F | G | PWA BOM | In New BOM |
|  | PBMR77,PAMR77 | 2 | 61010A700-017-G | RES,30.9KOhm,+/-1%,1/10W,G,SMD0603 | KOA SPEER ELECTRONICS, INC. | RK73H1JTTD3092F | N | PWA BOM | In Old BOM |
| 342 | PBMR121,PAMR121 | 2 | 61011FU00-017-G | RES,115KOhm,+/-1%,1/16W,G,SMD0402 | KOA SPEER ELECTRONICS, INC. | RK73H1ETTP1153F | G | PWA BOM | In New BOM |
|  | PBMR121,PAMR121 | 2 | 61011FU00-017-G | RES,115KOhm,+/-1%,1/16W,G,SMD0402 | KOA SPEER ELECTRONICS, INC. | RK73H1ETTP1153F | N | PWA BOM | In Old BOM |
| 343 | PBMU4,PAMU4 | 2 | 880302800-53N-G | Converter,input 0V~60V,131W,G,VTM48MP010C105AG0 | Vicor Corporation | VTM48MP010C105AG0 | G | PWA BOM | In New BOM |
|  | PBMU4,PAMU4 | 2 | 880302800-53N-G | Converter,input 0V~60V,131W,G,VTM48MP010C105AG0 | Vicor Corporation | VTM48MP010C105AG0 |  | PWA BOM | In Old BOM |
| 344 | PUAC8,PSIC8,PSAC8,PRAC8,PQAC8,PPAC8,PIAC8,PFAC8,PETC8,PERC8,PEAC8,PBNC10,PANC10 | 13 | 62010HR00-015-G | CAP,100nF,+/-10%,X7R,50V,G,SMD0603 | MURATA ELEC. NORTH AMERICA | GRM188R71H104K | G | PWA BOM | In New BOM |
|  |  |  | 62010HR00-026-G | CAP,100nF,+/-10%,X7R,50V,G,SMD0603 | SAMSUNG SEMICONDUCTOR | CL10B104KB8NNNC | G | PWA BOM | In New BOM |
|  | PUAC8,PSIC8,PSAC8,PRAC8,PQAC8,PPAC8,PIAC8,PFAC8,PETC8,PERC8,PEAC8,PBNC10,PANC10 | 13 | 62010HR00-015-G | CAP,100nF,+/-10%,X7R,50V,G,SMD0603 | MURATA ELEC. NORTH AMERICA | GRM188R71H104K | N | PWA BOM | In Old BOM |
|  |  |  | 62010HR00-026-G | CAP,100nF,+/-10%,X7R,50V,G,SMD0603 | SAMSUNG SEMICONDUCTOR | CL10B104KB8NNNC | G | PWA BOM | In Old BOM |
| 345 | PBNL1,PANL1 | 2 | 630330G00-088-G | IND,300nH@100KHz,+/-10%,32.5A,304.5uOhm,SHLD,G,SMD | COOPER BUSSMANN, INC. | FP0906R1-R30-R | G | PWA BOM | In New BOM |
|  |  |  | 630332A01-051-G | Coil Ind,Shielded(SHLD),300nH@100KHz,+/-10%,33A,304.5uOhm,SMD,9.2*6.2*7.8,G | PULSE ELECTRONICS (SINGAPORE) | PA3288.301HLT | G | PWA BOM | In New BOM |
|  |  |  | MSI-900608-R30K-E | IND,MSI-900608-R30K-E | MAG.LAYERS, SCIENTIFIC-TECHNICS (KUNSHAN) CO., LTD. | MSI-900608-R30K-E | G | PWA BOM | In New BOM |
|  | PBNL1,PANL1 | 2 | 630330G00-088-G | IND,300nH@100KHz,+/-10%,32.5A,304.5uOhm,SHLD,G,SMD | COOPER BUSSMANN, INC. | FP0906R1-R30-R |  | PWA BOM | In Old BOM |
|  |  |  | 630332A01-051-G | Coil Ind,Shielded(SHLD),300nH@100KHz,+/-10%,33A,304.5uOhm,SMD,9.2*6.2*7.8,G | PULSE ELECTRONICS (SINGAPORE) | PA3288.301HLT | G | PWA BOM | In Old BOM |
|  |  |  | MSI-900608-R30K-E | IND,MSI-900608-R30K-E | MAG.LAYERS, SCIENTIFIC-TECHNICS (KUNSHAN) CO., LTD. | MSI-900608-R30K-E | G | PWA BOM | In Old BOM |
| 346 | PSRR20,PBNR23,PANR23,PHAR28,PHAR29,PHAR30,R668,R669,R683,R762,R763,R764,R765,R766,R767,R769,R770,R772,R773,R774,R775,R776,R777,R778,R779,R780,R783,R784,R786,R787,R788,R791,R795,R800,R801,R804,R805,R806,R807,R808,R809,R811,R814,R817,R820,R822,R823,R825,R827,R828,R830,R893,R894,R901,R902,R922,R942,R943,R944,R945,R949,R950,R955,R956,R957,R958,R959,R1017,R1023,R1129,R1135,R1138,R1148,R1149,R1150,R1151,R1152,R1156,R1159,R1162,R1164,R1165,R1172,R1174,R1175,R1176,R1184,R1185,R1186,R1190,R1195,R1197,R1198,R1199,R1210,R1211,R1212,R1213,R1218,R1219,R1220,R1221,R1222,R1223,R1224,R1240,R1256,R1257,R1295,R1296,R1461,R1463,R1464,R1465,R1467,R1469,R1470,R1471,R1474,R1475,R1476,R1477,R1495,R1504,R1507,R1508,R1509,R1511,R1512,R1515,R1520,R1521,R1550,R1551,R1589,R1590,R1592,R1593,R1603,R1604,R1605,R1606,R1779,R1780,R1781,R1782,R1786,R1789,R1801,R1820,R1821,R1834 | 152 | 61010LA00-017-G | RES,4.7KOhm,+/-1%,1/16W,G,SMD0402 | KOA SPEER ELECTRONICS, INC. | RK73H1ETTP4701F | G | PWA BOM | In New BOM |
|  |  |  | 61010LA00-012-G | RES,4.7KOhm,+/-1%,1/16W,G,SMD0402 | WALSIN TECHNOLOGY CORPORATION | WR04X4701FTL | G | PWA BOM | In New BOM |
|  |  |  | 61010LA00-011-G | RES,4.7KOhm,+/-1%,1/16W,G,SMD0402 | YAGEO CORPORATION COMPONENT | RC0402FR-074K7L | G | PWA BOM | In New BOM |
|  |  |  | 61010LA00-044-G | RES,4.7KOhm,+/-1%,1/16W,G,SMD0402 | TA-I TECHNOLOGY CO., LTD | RM04FTN4701 | G | PWA BOM | In New BOM |
|  | PSRR20,PBNR23,PANR23,PHAR28,PHAR29,PHAR30,R668,R669,R683,R762,R763,R764,R765,R766,R767,R769,R770,R772,R773,R774,R775,R776,R777,R778,R779,R780,R783,R784,R786,R787,R788,R791,R795,R800,R801,R804,R805,R806,R807,R808,R809,R811,R814,R817,R820,R822,R823,R825,R827,R828,R830,R893,R894,R901,R902,R922,R942,R943,R944,R945,R949,R950,R955,R956,R957,R958,R959,R1017,R1023,R1129,R1135,R1138,R1148,R1149,R1150,R1151,R1152,R1156,R1159,R1162,R1164,R1165,R1172,R1174,R1175,R1176,R1184,R1185,R1186,R1190,R1195,R1197,R1198,R1199,R1210,R1211,R1212,R1213,R1218,R1219,R1220,R1221,R1222,R1223,R1224,R1240,R1256,R1257,R1295,R1296,R1461,R1463,R1464,R1465,R1467,R1469,R1470,R1471,R1474,R1475,R1476,R1477,R1495,R1504,R1507,R1508,R1509,R1511,R1512,R1515,R1520,R1521,R1550,R1551,R1589,R1590,R1592,R1593,R1603,R1604,R1605,R1606,R1779,R1780,R1781,R1782,R1786,R1789,R1801,R1820,R1821,R1834 | 152 | 61010LA00-017-G | RES,4.7KOhm,+/-1%,1/16W,G,SMD0402 | KOA SPEER ELECTRONICS, INC. | RK73H1ETTP4701F | N | PWA BOM | In Old BOM |
|  |  |  | 61010LA00-012-G | RES,4.7KOhm,+/-1%,1/16W,G,SMD0402 | WALSIN | WR04X4701FTL | G | PWA BOM | In Old BOM |
|  |  |  | 61010LA00-011-G | RES,4.7KOhm,+/-1%,1/16W,G,SMD0402 | YAGEO | RC0402FR-074K7L | G | PWA BOM | In Old BOM |
|  |  |  | 61010LA00-044-G | RES,4.7KOhm,+/-1%,1/16W,G,SMD0402 | TA-I | RM04FTN4701 | G | PWA BOM | In Old BOM |
| 347 | PBNU1,PANU1 | 2 | 320147Q00-238-G | IC,Regulator,IR38064MTRPBF,ADJ,35A,G,QFN-26,SMD | INTERNATIONAL RECTIFIER | IR38064MTRPBF | G | PWA BOM | In New BOM |
|  | PBNU1,PANU1 | 2 | 320147Q00-238-G | IC,Regulator,IR38064MTRPBF,ADJ,35A,G,QFN-26,SMD | INTERNATIONAL RECTIFIER | IR38064MTRPBF |  | PWA BOM | In Old BOM |
| 348 | PUAC1,PSIC1,PSAC1,PRAC1,PQAC1,PPAC1,PIAC1,PFAC1,PETC1,PERC1,PEAC1,PSUC4 | 12 | 62011F100-015-G | CAP,1uF,+/-10%,X7R,25V,G,SMD0603 | MURATA ELEC. NORTH AMERICA | GRM188R71E105K | G | PWA BOM | In New BOM |
|  |  |  | 62011F100-023-G | CAP,1uF,+/-10%,X7R,25V,G,SMD0603 | TAIYO ELECTRIC IND.CO.LTD | TMK107B7105KA-T | G | PWA BOM | In New BOM |
|  |  |  | 62011F100-026-G | CAP,1uF,+/-10%,X7R,25V,G,SMD0603 | SAMSUNG SEMICONDUCTOR | CL10B105KA8NNNC | G | PWA BOM | In New BOM |
|  | PUAC1,PSIC1,PSAC1,PRAC1,PQAC1,PPAC1,PIAC1,PFAC1,PETC1,PERC1,PEAC1,PSUC4 | 12 | 62011F100-015-G | CAP,1uF,+/-10%,X7R,25V,G,SMD0603 | MURATA ELEC. NORTH AMERICA | GRM188R71E105K | N | PWA BOM | In Old BOM |
|  |  |  | 62011F100-023-G | CAP,1uF,+/-10%,X7R,25V,G,SMD0603 | TAIYO ELECTRIC IND.CO.LTD | TMK107B7105KA-T | G | PWA BOM | In Old BOM |
|  |  |  | 62011F100-026-G | CAP,1uF,+/-10%,X7R,25V,G,SMD0603 | SAMSUNG SEMICONDUCTOR | CL10B105KA8NNNC | G | PWA BOM | In Old BOM |
| 349 | PUAC4,PSAC4,PRAC4,PQAC4,PPAC4,PIAC4,PFAC4,PEAC4,PUAC5,PSAC5,PRAC5,PQAC5,PPAC5,PIAC5,PFAC5,PEAC5,PUAC6,PSAC6,PRAC6,PQAC6,PPAC6,PIAC6,PFAC6,PEAC6 | 24 | 62011DD00-015-G | CAP,22uF,+/-10%,X6S,6.3V,G,SMD1206 | MURATA ELEC. NORTH AMERICA | GRM31CC80J226K | G | PWA BOM | In New BOM |
|  | PUAC4,PSAC4,PRAC4,PQAC4,PPAC4,PIAC4,PFAC4,PEAC4,PUAC5,PSAC5,PRAC5,PQAC5,PPAC5,PIAC5,PFAC5,PEAC5,PUAC6,PSAC6,PRAC6,PQAC6,PPAC6,PIAC6,PFAC6,PEAC6 | 24 | 62011DD00-015-G | CAP,22uF,+/-10%,X6S,6.3V,G,SMD1206 | MURATA ELEC. NORTH AMERICA | GRM31CC80J226K | Y | PWA BOM | In Old BOM |
| 350 | PSLC7,PSFC7,PSEC7,PSDC7,PEEC7,PEDC7,PSLC8,PSFC8,PSEC8,PSDC8,PEEC8,PEDC8,PUAC11,PSLC11,PSIC11,PSFC11,PSEC11,PSDC11,PSAC11,PRAC11,PQAC11,PPAC11,PIAC11,PFAC11,PEEC11,PEDC11,PEAC11,PUAC12,PSLC12,PSIC12,PSFC12,PSEC12,PSDC12,PSAC12,PRAC12,PQAC12,PPAC12,PIAC12,PFAC12,PEEC12,PEDC12,PEAC12,PUAC13,PSIC13,PSAC13,PRAC13,PQAC13,PPAC13,PIAC13,PFAC13,PEAC13,PUAC14,PSIC14,PSAC14,PRAC14,PQAC14,PPAC14,PIAC14,PFAC14,PEAC14,PUAC15,PSLC15,PSIC15,PSFC15,PSEC15,PSDC15,PSAC15,PRAC15,PQAC15,PPAC15,PIAC15,PFAC15,PEEC15,PEDC15,PEAC15,PUAC16,PSIC16,PSAC16,PRAC16,PQAC16,PPAC16,PIAC16,PFAC16,PEAC16 | 84 | 620119R04-015-G | CAP,22uF,+/-20%,X6S,4V,G,SMD0805 | MURATA ELEC. NORTH AMERICA | GRM21BC80G226M | G | PWA BOM | In New BOM |
|  |  |  | 620119R01-015-G | CAP,22uF,+/-20%,X6S,4V,G,SMD0805 | MURATA ELEC. NORTH AMERICA | GRM21BC80G226ME39K | G | PWA BOM | In New BOM |
|  |  |  | 620119R00-023-G | CAP,22uF,+/-20%,X6S,4V,G,SMD0805 | TAIYO ELECTRIC IND.CO.LTD | AMK212C6226MG-T | G | PWA BOM | In New BOM |
|  |  |  | 620119R00-026-G | CAP,22uF,+/-20%,X6S,4V,G,SMD0805 | SAMSUNG SEMICONDUCTOR | CL21X226MRQNNNE | G | PWA BOM | In New BOM |
|  | PSLC7,PSFC7,PSEC7,PSDC7,PEEC7,PEDC7,PSLC8,PSFC8,PSEC8,PSDC8,PEEC8,PEDC8,PUAC11,PSLC11,PSIC11,PSFC11,PSEC11,PSDC11,PSAC11,PRAC11,PQAC11,PPAC11,PIAC11,PFAC11,PEEC11,PEDC11,PEAC11,PUAC12,PSLC12,PSIC12,PSFC12,PSEC12,PSDC12,PSAC12,PRAC12,PQAC12,PPAC12,PIAC12,PFAC12,PEEC12,PEDC12,PEAC12,PUAC13,PSIC13,PSAC13,PRAC13,PQAC13,PPAC13,PIAC13,PFAC13,PEAC13,PUAC14,PSIC14,PSAC14,PRAC14,PQAC14,PPAC14,PIAC14,PFAC14,PEAC14,PUAC15,PSLC15,PSIC15,PSFC15,PSEC15,PSDC15,PSAC15,PRAC15,PQAC15,PPAC15,PIAC15,PFAC15,PEEC15,PEDC15,PEAC15,PUAC16,PSIC16,PSAC16,PRAC16,PQAC16,PPAC16,PIAC16,PFAC16,PEAC16 | 84 | 620119R04-015-G | CAP,22uF,+/-20%,X6S,4V,G,SMD0805 | MURATA ELEC. NORTH AMERICA | GRM21BC80G226M |  | PWA BOM | In Old BOM |
|  |  |  | 620119R01-015-G | CAP,22uF,+/-20%,X6S,4V,G,SMD0805 | MURATA ELEC. NORTH AMERICA | GRM21BC80G226ME39K | G | PWA BOM | In Old BOM |
|  |  |  | 620119R00-023-G | CAP,22uF,+/-20%,X6S,4V,G,SMD0805 | TAIYO ELECTRIC IND.CO.LTD | AMK212C6226MG-T | G | PWA BOM | In Old BOM |
|  |  |  | 620119R00-026-G | CAP,22uF,+/-20%,X6S,4V,G,SMD0805 | SAMSUNG SEMICONDUCTOR | CL21X226MRQNNNE | G | PWA BOM | In Old BOM |
| 351 | PUAU1,PSIU1,PSAU1,PRAU1,PQAU1,PPAU1,PIAU1,PFAU1,PETU1,PERU1,PEAU1 | 11 | 32012NN00-238-G | IC,Regulator,IR3898MTRPBF,6A,1.5MHZ,G,QFN-17,SMD | INTERNATIONAL RECTIFIER | IR3898MTRPBF | G | PWA BOM | In New BOM |
|  | PUAU1,PSIU1,PSAU1,PRAU1,PQAU1,PPAU1,PIAU1,PFAU1,PETU1,PERU1,PEAU1 | 11 | 32012NN00-238-G | IC,Regulator,IR3898MTRPBF,6A,1.5MHZ,G,QFN-17,SMD | INTERNATIONAL RECTIFIER | IR3898MTRPBF |  | PWA BOM | In Old BOM |
| 352 | PSLC16,PSFC16,PSEC16,PSDC16,PEEC16,PEDC16 | 6 | 62012CM01-015-G | CAP,10uF,+/-20%,X6S,4V,G,SMD0603 | MURATA ELEC. NORTH AMERICA | GRM188C80G106M | G | PWA BOM | In New BOM |
|  |  |  | 62012CM00-023-G | CAP,10uF,+/-20%,X6S,4V,G,SMD0603 | TAIYO ELECTRIC IND.CO.LTD | AMK107AC6106MA-T | G | PWA BOM | In New BOM |
|  |  |  | 62012CM00-026-G | CAP,10uF,+/-20%,X6S,4V,G,SMD0603 | SAMSUNG SEMICONDUCTOR | CL10X106MR8NNNC | G | PWA BOM | In New BOM |
|  | PSLC16,PSFC16,PSEC16,PSDC16,PEEC16,PEDC16 | 6 | 62012CM01-015-G | CAP,10uF,+/-20%,X6S,4V,G,SMD0603 | MURATA ELEC. NORTH AMERICA | GRM188C80G106M |  | PWA BOM | In Old BOM |
|  |  |  | 62012CM00-023-G | CAP,10uF,+/-20%,X6S,4V,G,SMD0603 | TAIYO ELECTRIC IND.CO.LTD | AMK107AC6106MA-T | G | PWA BOM | In Old BOM |
|  |  |  | 62012CM00-026-G | CAP,10uF,+/-20%,X6S,4V,G,SMD0603 | SAMSUNG SEMICONDUCTOR | CL10X106MR8NNNC | G | PWA BOM | In Old BOM |
| 353 | PSLR17,PSFR17,PSER17,PSDR17,PQPR17,PFRR17,PEER17,PEDR17,PEDR19 | 9 | 611004M00-017-G | RES,16.5KOhm,+/-0.1%,1/16W,G,SMD0402 | KOA SPEER ELECTRONICS, INC. | RN731ETTP1652B25 | G | PWA BOM | In New BOM |
|  |  |  | 611004M00-024-G | RES,16.5KOhm,+/-0.1%,1/16W,G,SMD0402 | PANASONIC | ERA2AEB1652X | G | PWA BOM | In New BOM |
|  | PSLR17,PSFR17,PSER17,PSDR17,PQPR17,PFRR17,PEER17,PEDR17,PEDR19 | 9 | 611004M00-017-G | RES,16.5KOhm,+/-0.1%,1/16W,G,SMD0402 | KOA SPEER ELECTRONICS, INC. | RN731ETTP1652B25 |  | PWA BOM | In Old BOM |
|  |  |  | 611004M00-024-G | RES,16.5KOhm,+/-0.1%,1/16W,G,SMD0402 | PANASONIC | ERA2AEB1652X | G | PWA BOM | In Old BOM |
| 354 | PSTU1,PSLU1,PSFU1,PSEU1,PSDU1,PQPU1,PFRU1,PEEU1,PEDU1 | 9 | 32013PD00-238-G | IC,Regulator,IR3883MTRPbF,ADJ,3A,G,QFN-16,SMD | INTERNATIONAL RECTIFIER | IR3883MTRPBF | G | PWA BOM | In New BOM |
|  | PSTU1,PSLU1,PSFU1,PSEU1,PSDU1,PQPU1,PFRU1,PEEU1,PEDU1 | 9 | 32013PD00-238-G | IC,Regulator,IR3883MTRPbF,ADJ,3A,G,QFN-16,SMD | INTERNATIONAL RECTIFIER | IR3883MTRPBF |  | PWA BOM | In Old BOM |
| 355 | PSPCE1,PIPCE1,PFPCE1,PEPCE1,PSUCE4 | 5 | 62120HJ00-022-G | ECAP,SPEA,270uF,+/-20%,16V,105C,G,SMD6.3X9.9,ESR<=8mOhm | SANYO ELECTRIC CO., LTD. | 16SVPG270M | G | PWA BOM | In New BOM |
|  |  |  | 62120LS00-021-G | ECAP,Solid Polymer Electrolytic Aluminium Capacitor (SPEA),Low ESR(LESR),270uF,+/-20%,16V,105_x0003_,10mOhm,SMD,6.3*7.7,G | NIPPON CHEMI-CON CORPORATION | APXJ160ARA271MF80J | G | PWA BOM | In New BOM |
|  | PSPCE1,PIPCE1,PFPCE1,PEPCE1,PSUCE4 | 5 | 62120HJ00-022-G | ECAP,SPEA,270uF,+/-20%,16V,105C,G,SMD6.3X9.9,ESR<=8mOhm | SANYO ELECTRIC CO., LTD. | 16SVPG270M |  | PWA BOM | In Old BOM |
|  |  |  | 62120LS00-021-G | ECAP,Solid Polymer Electrolytic Aluminium Capacitor (SPEA),Low ESR(LESR),270uF,+/-20%,16V,105_x0003_,10mOhm,SMD,6.3*7.7,G | NIPPON CHEMI-CON CORPORATION | APXJ160ARA271MF80J | G | PWA BOM | In Old BOM |
| 356 | PSPR10,PIPR10,PFPR10,PEPR10 | 4 | 61100QQ00-017-G | RES,9.76KOhm,+/-0.1%,1/16W,G,SMD0402 | KOA SPEER ELECTRONICS, INC. | RN731ETTP9761B25 | G | PWA BOM | In New BOM |
|  |  |  | 61100QQ00-024-G | RES,9.76KOhm,+/-0.1%,1/16W,G,SMD0402 | PANASONIC INDUSTRIAL CO.,LTD. | ERA2AEB9761X | G | PWA BOM | In New BOM |
|  |  |  | 61100QQ00-029-G | RES,9.76KOhm,+/-0.1%,1/16W,G,SMD0402 | VISHAY ENTER TECHNO LOGY.INC | TNPW04029K76BEED | G | PWA BOM | In New BOM |
|  | PSPR10,PIPR10,PFPR10,PEPR10 | 4 | 61100QQ00-017-G | RES,9.76KOhm,+/-0.1%,1/16W,G,SMD0402 | KOA SPEER ELECTRONICS, INC. | RN731ETTP9761B25 | Y | PWA BOM | In Old BOM |
|  |  |  | 61100QQ00-024-G | RES,9.76KOhm,+/-0.1%,1/16W,G,SMD0402 | PANASONIC INDUSTRIAL CO.,LTD. | ERA2AEB9761X | G | PWA BOM | In Old BOM |
|  |  |  | 61100QQ00-029-G | RES,9.76KOhm,+/-0.1%,1/16W,G,SMD0402 | VISHAY ENTER TECHNO LOGY.INC | TNPW04029K76BEED | G | PWA BOM | In Old BOM |
| 357 | PSPU1,PIPU1,PFPU1,PEPU1 | 4 | 32013HH00-238-G | IC,Regulator,IR3447MTRPBF,ADJ,25A,G,PQFN-33 | INTERNATIONAL RECTIFIER | IR3447MTRPBF | G | PWA BOM | In New BOM |
|  | PSPU1,PIPU1,PFPU1,PEPU1 | 4 | 32013HH00-238-G | IC,Regulator,IR3447MTRPBF,ADJ,25A,G,PQFN-33 | INTERNATIONAL RECTIFIER | IR3447MTRPBF |  | PWA BOM | In Old BOM |
| 358 | PSRC3,PERC3 | 2 | 62011M802-015-G | CAP,62pF,+/-5%,NPO(C0G),50V,G,SMD0402 | MURATA ELEC. NORTH AMERICA | GRM1555C1H620JA01D | G | PWA BOM | In New BOM |
|  | PSRC3,PERC3 | 2 | 62011M802-015-G | CAP,62pF,+/-5%,NPO(C0G),50V,G,SMD0402 | MURATA ELEC. NORTH AMERICA | GRM1555C1H620JA01D |  | PWA BOM | In Old BOM |
| 359 | PSIC4,PETC4,PERC4,PSIC5,PETC5,PERC5,PSIC6,PETC6,PERC6,PETC22 | 10 | 62013BP00-015-G | CAP,22uF,+/-20%,X6S,25V,G,SMD1206 | MURATA ELEC. NORTH AMERICA | GRM31CC81E226ME11L | G | PWA BOM | In New BOM |
|  | PSIC4,PETC4,PERC4,PSIC5,PETC5,PERC5,PSIC6,PETC6,PERC6,PETC22 | 10 | 62013BP00-015-G | CAP,22uF,+/-20%,X6S,25V,G,SMD1206 | MURATA ELEC. NORTH AMERICA | GRM31CC81E226ME11L |  | PWA BOM | In Old BOM |
| 360 | PSTC7,PQPC7,PFRC7,PSTC8,PQPC8,PFRC8,PSRC10,PSTC11,PSRC11,PQPC11,PFRC11,PETC11,PERC11,PSTC12,PSRC12,PQPC12,PFRC12,PETC12,PERC12,PSRC13,PETC13,PERC13,PETC14,PERC14,PSTC15,PQPC15,PFRC15,PETC15,PERC15,PETC16,PERC16,PSRC3012,PSRC3013,PSRC3014,PSRC3015 | 35 | 62012PT00-015-G | CAP,22uF,+/-20%,X6S,16V,G,SMD0805 | MURATA ELEC. NORTH AMERICA | GRM21BC81C226M | G | PWA BOM | In New BOM |
|  |  |  | 62012PT00-023-G | CAP,22uF,+/-20%,X6S,16V,G,SMD0805 | TAIYO ELECTRIC IND.CO.LTD | EDK212BC6226MG-T | G | PWA BOM | In New BOM |
|  | PSTC7,PQPC7,PFRC7,PSTC8,PQPC8,PFRC8,PSRC10,PSTC11,PSRC11,PQPC11,PFRC11,PETC11,PERC11,PSTC12,PSRC12,PQPC12,PFRC12,PETC12,PERC12,PSRC13,PETC13,PERC13,PETC14,PERC14,PSTC15,PQPC15,PFRC15,PETC15,PERC15,PETC16,PERC16,PSRC3012,PSRC3013,PSRC3014,PSRC3015 | 35 | 62012PT00-015-G | CAP,22uF,+/-20%,X6S,16V,G,SMD0805 | MURATA ELEC. NORTH AMERICA | GRM21BC81C226M |  | PWA BOM | In Old BOM |
|  |  |  | 62012PT00-023-G | CAP,22uF,+/-20%,X6S,16V,G,SMD0805 | TAIYO ELECTRIC IND.CO.LTD | EDK212BC6226MG-T | G | PWA BOM | In Old BOM |
| 361 | PSIR10,PETR10,PERR10,R938 | 4 | 61015JF00-017-G | RES,63.4 Ohm,+/-1%,1/10W,G,SMD0402 | KOA SPEER ELECTRONICS, INC. | RK73H1ETTP63R4F | G | PWA BOM | In New BOM |
|  | PSIR10,PETR10,PERR10,R938 | 4 | 61015JF00-017-G | RES,63.4 Ohm,+/-1%,1/10W,G,SMD0402 | KOA SPEER ELECTRONICS, INC. | RK73H1ETTP63R4F | N | PWA BOM | In Old BOM |
| 362 | PERR13,PERR15 | 2 | 61100PW00-017-G | RES,1.54KOhm,+/-0.1%,1/16W,G,SMD0402 | KOA SPEER ELECTRONICS, INC. | RN731ETTP1541B25 | G | PWA BOM | In New BOM |
|  |  |  | 61100PW00-024-G | RES,1.54KOhm,+/-0.1%,1/16W,G,SMD0402 | PANASONIC INDUSTRIAL CO.,LTD. | ERA2AEB1541X | G | PWA BOM | In New BOM |
|  |  |  | 61100PW00-029-G | RES,1.54KOhm,+/-0.1%,1/16W,G,SMD0402 | VISHAY ENTER TECHNO LOGY.INC | TNPW04021K54BEED | G | PWA BOM | In New BOM |
|  | PERR13,PERR15 | 2 | 61100PW00-017-G | RES,1.54KOhm,+/-0.1%,1/16W,G,SMD0402 | KOA SPEER ELECTRONICS, INC. | RN731ETTP1541B25 | Y | PWA BOM | In Old BOM |
|  |  |  | 61100PW00-024-G | RES,1.54KOhm,+/-0.1%,1/16W,G,SMD0402 | PANASONIC INDUSTRIAL CO.,LTD. | ERA2AEB1541X | G | PWA BOM | In Old BOM |
|  |  |  | 61100PW00-029-G | RES,1.54KOhm,+/-0.1%,1/16W,G,SMD0402 | VISHAY ENTER TECHNO LOGY.INC | TNPW04021K54BEED | G | PWA BOM | In Old BOM |
| 363 | PETC3 | 1 | 62011LT01-015-G | CAP,130pF,+/-5%,NPO(C0G),50V,G,SMD0402 | MURATA ELEC. NORTH AMERICA | GRM1555C1H131JA01D | G | PWA BOM | In New BOM |
|  | PETC3 | 1 | 62011LT01-015-G | CAP,130pF,+/-5%,NPO(C0G),50V,G,SMD0402 | MURATA ELEC. NORTH AMERICA | GRM1555C1H131JA01D |  | PWA BOM | In Old BOM |
| 364 | PETR13,PETR15 | 2 | 61100AW00-017-G | RES,909 Ohm,+/-0.1%,1/16W,G,SMD0402 | KOA SPEER ELECTRONICS, INC. | RN731ETTP9090B25 | G | PWA BOM | In New BOM |
|  |  |  | 61100AW00-024-G | RES,909 Ohm,+/-0.1%,1/16W,G,SMD0402 | PANASONIC INDUSTRIAL CO.,LTD. | ERA2AEB9090X | G | PWA BOM | In New BOM |
|  |  |  | 61100AW00-029-G | RES,909 Ohm,+/-0.1%,1/16W,G,SMD0402 | VISHAY ENTER TECHNO LOGY.INC | TNPW0402909RBEED | G | PWA BOM | In New BOM |
|  | PETR13,PETR15 | 2 | 61100AW00-017-G | RES,909 Ohm,+/-0.1%,1/16W,G,SMD0402 | KOA SPEER ELECTRONICS, INC. | RN731ETTP9090B25 | Y | PWA BOM | In Old BOM |
|  |  |  | 61100AW00-024-G | RES,909 Ohm,+/-0.1%,1/16W,G,SMD0402 | PANASONIC INDUSTRIAL CO.,LTD. | ERA2AEB9090X | G | PWA BOM | In Old BOM |
|  |  |  | 61100AW00-029-G | RES,909 Ohm,+/-0.1%,1/16W,G,SMD0402 | VISHAY ENTER TECHNO LOGY.INC | TNPW0402909RBEED | G | PWA BOM | In Old BOM |
| 365 | PQPL2,PFRL2 | 2 | 63032PP00-088-G | IND,4.7uH@100KHz,+/-20%,5.5A,40mOhm,SHLD,G,SMD | COOPER BUSSMANN, INC. | HCM0703-4R7-R | G | PWA BOM | In New BOM |
|  |  |  | 63030PW00-034-G | Coil Ind,Shielded(SHLD),4.7uH@100KHz,+/-20%,5.5A,40mOhm,SMD,7.3*6.6*3.0,G | CYNTEC CO. LTD | PCMC063T-4R7MN | G | PWA BOM | In New BOM |
|  |  |  | SPS-06CZ-4R7M-V1 | IND,SPS-06CZ-4R7M-V1 | MAG.LAYERS, SCIENTIFIC-TECHNICS (KUNSHAN) CO., LTD. | SPS-06CZ-4R7M-V1 | G | PWA BOM | In New BOM |
|  | PQPL2,PFRL2 | 2 | 63032PP00-088-G | IND,4.7uH@100KHz,+/-20%,5.5A,40mOhm,SHLD,G,SMD | COOPER BUSSMANN, INC. | HCM0703-4R7-R |  | PWA BOM | In Old BOM |
|  |  |  | 63030PW00-034-G | Coil Ind,Shielded(SHLD),4.7uH@100KHz,+/-20%,5.5A,40mOhm,SMD,7.3*6.6*3.0,G | CYNTEC CO. LTD | PCMC063T-4R7MN | G | PWA BOM | In Old BOM |
|  |  |  | SPS-06CZ-4R7M-V1 | IND,SPS-06CZ-4R7M-V1 | MAG.LAYERS, SCIENTIFIC-TECHNICS (KUNSHAN) CO., LTD. | SPS-06CZ-4R7M-V1 | G | PWA BOM | In Old BOM |
| 366 | PFRR19 | 1 | 61100YB00-017-G | RES,2.94KOhm,+/-0.1%,1/16W,G,SMD0402 | KOA SPEER ELECTRONICS, INC. | RN731ETTP2941B25 | G | PWA BOM | In New BOM |
|  | PFRR19 | 1 | 61100YB00-017-G | RES,2.94KOhm,+/-0.1%,1/16W,G,SMD0402 | KOA SPEER ELECTRONICS, INC. | RN731ETTP2941B25 |  | PWA BOM | In Old BOM |
| 367 | PHAD1 | 1 | 52170KE00-086-G | TVS Diode,SMCJ64A,G,DO-214AB-2,SMD | LITTELFUSE FAR EAST PTE LTD | SMCJ64A | G | PWA BOM | In New BOM |
|  |  |  | 52170ER00-237-G | TVS Diode,SMCJ64A-13-F,SMC/DO-214AB,2P,G | DIODES INCORPORATION | SMCJ64A-13-F | G | PWA BOM | In New BOM |
|  | PHAD1 | 1 | 52170KE00-086-G | TVS Diode,SMCJ64A,G,DO-214AB-2,SMD | LITTELFUSE FAR EAST PTE LTD | SMCJ64A |  | PWA BOM | In Old BOM |
|  |  |  | 52170ER00-237-G | TVS Diode,SMCJ64A-13-F,SMC/DO-214AB,2P,G | DIODES INCORPORATION | SMCJ64A-13-F | G | PWA BOM | In Old BOM |
| 368 | PHAD2 | 1 | 52030YE00-223-G | DIODE,Schottky,MBR5H100MFST1G,100V,5A,G,SO8FL-8,SMD | ON SEMICONDUCTOR CORP | MBR5H100MFST1G | G | PWA BOM | In New BOM |
|  | PHAD2 | 1 | 52030YE00-223-G | DIODE,Schottky,MBR5H100MFST1G,100V,5A,G,SO8FL-8,SMD | ON SEMICONDUCTOR CORP | MBR5H100MFST1G |  | PWA BOM | In Old BOM |
| 369 | PHAR1 | 1 | 610601801-32D-G | RES,0.5mOhm,+/-1%,2W,G,SMD1225 | Thin Film Technology Corporation | CPA1225R0M50FW-T5 | G | PWA BOM | In New BOM |
|  | PHAR1 | 1 | 610601801-32D-G | RES,0.5mOhm,+/-1%,2W,G,SMD1225 | Thin Film Technology Corporation | CPA1225R0M50FW-T5 |  | PWA BOM | In Old BOM |
| 370 | PHAU1 | 1 | 32023RR00-183-G | IC,Power Controller,LM5066IPMHX/NOPB,G,HTSSOP-28,SMD | TEXAS INSTRUMENTS | LM5066IPMHX/NOPB | G | PWA BOM | In New BOM |
|  | PHAU1 | 1 | 32023RR00-183-G | IC,Power Controller,LM5066IPMHX/NOPB,G,HTSSOP-28,SMD | TEXAS INSTRUMENTS | LM5066IPMHX/NOPB |  | PWA BOM | In Old BOM |
| 371 | PSIR13,PSIR15,PQPR19 | 3 | 611006C00-017-G | RES,4.12KOhm,+/-0.1%,1/16W,G,SMD0402 | KOA SPEER ELECTRONICS, INC. | RN731ETTP4121B25 | G | PWA BOM | In New BOM |
|  |  |  | 611006C00-024-G | RES,4.12KOhm,+/-0.1%,1/16W,G,SMD0402 | PANASONIC INDUSTRIAL CO.,LTD. | ERA2AEB4121X | G | PWA BOM | In New BOM |
|  |  |  | 611006C00-029-G | RES,4.12KOhm,+/-0.1%,1/16W,G,SMD0402 | VISHAY ENTER TECHNO LOGY.INC | TNPW04024K12BEED | G | PWA BOM | In New BOM |
|  | PSIR13,PSIR15,PQPR19 | 3 | 611006C00-017-G | RES,4.12KOhm,+/-0.1%,1/16W,G,SMD0402 | KOA SPEER ELECTRONICS, INC. | RN731ETTP4121B25 | Y | PWA BOM | In Old BOM |
|  |  |  | 611006C00-024-G | RES,4.12KOhm,+/-0.1%,1/16W,G,SMD0402 | PANASONIC INDUSTRIAL CO.,LTD. | ERA2AEB4121X | G | PWA BOM | In Old BOM |
|  |  |  | 611006C00-029-G | RES,4.12KOhm,+/-0.1%,1/16W,G,SMD0402 | VISHAY ENTER TECHNO LOGY.INC | TNPW04024K12BEED | G | PWA BOM | In Old BOM |
| 372 | PSTL2,PSLL2,PSDL2 | 3 | 630328U00-088-G | IND,3.3uH@100KHz,+/-20%,6A,30mOhm,SHLD,G,SMD | COOPER BUSSMANN, INC. | HCM0703-3R3-R | G | PWA BOM | In New BOM |
|  |  |  | 63034QP00-034-G | IND,3.3uH@100KHz,+/-20%,6.5A,21mOhm,SHLD,G,SMD | CYNTEC CO. LTD | PCME063T-3R3MS | G | PWA BOM | In New BOM |
|  | PSTL2,PSLL2,PSDL2 | 3 | 630328U00-088-G | IND,3.3uH@100KHz,+/-20%,6A,30mOhm,SHLD,G,SMD | COOPER BUSSMANN, INC. | HCM0703-3R3-R |  | PWA BOM | In Old BOM |
|  |  |  | 63034QP00-034-G | IND,3.3uH@100KHz,+/-20%,6.5A,21mOhm,SHLD,G,SMD | CYNTEC CO. LTD | PCME063T-3R3MS | G | PWA BOM | In Old BOM |
| 373 | PSIL1,PSEL2 | 2 | 63032A900-088-G | IND,1.5uH@100KHz,+/-20%,9A,15mOhm,SHLD,G,SMD | COOPER BUSSMANN, INC. | HCM0703-1R5-R | G | PWA BOM | In New BOM |
|  |  |  | 63032BW00-034-G | IND,1.5uH@100KHz,+/-20%,9A,15mOhm,SHLD,G,SMD | CYNTEC CO. LTD | PCMC063T-1R5MN | G | PWA BOM | In New BOM |
|  |  |  | 63030HW00-051-G | IND,1.5uH@100KHz,+/-20%,9A,11.8mOhm,SHLD,G,SMD | PULSE ELECTRONICS (SINGAPORE) | PG0426.152NLT | G | PWA BOM | In New BOM |
|  | PSIL1,PSEL2 | 2 | 63032A900-088-G | IND,1.5uH@100KHz,+/-20%,9A,15mOhm,SHLD,G,SMD | COOPER BUSSMANN, INC. | HCM0703-1R5-R | N | PWA BOM | In Old BOM |
|  |  |  | 63032BW00-034-G | IND,1.5uH@100KHz,+/-20%,9A,15mOhm,SHLD,G,SMD | CYNTEC CO. LTD | PCMC063T-1R5MN | G | PWA BOM | In Old BOM |
|  |  |  | 63030HW00-051-G | IND,1.5uH@100KHz,+/-20%,9A,11.8mOhm,SHLD,G,SMD | PULSE ELECTRONICS (SINGAPORE) | PG0426.152NLT | G | PWA BOM | In Old BOM |
| 374 | PSER19 | 1 | 61100V400-017-G | RES,13.7KOhm,+/-0.1%,1/16W,G,SMD0402 | KOA SPEER ELECTRONICS, INC. | RN731ETTP1372B25 | G | PWA BOM | In New BOM |
|  |  |  | 61100V400-024-G | RES,13.7KOhm,+/-0.1%,1/16W,G,SMD0402 | PANASONIC INDUSTRIAL CO.,LTD. | ERA2AEB1372X | G | PWA BOM | In New BOM |
|  |  |  | 61100V400-029-G | RES,13.7KOhm,+/-0.1%,1/16W,G,SMD0402 | VISHAY ENTER TECHNO LOGY.INC | TNPW040213K7BEED | G | PWA BOM | In New BOM |
|  | PSER19 | 1 | 61100V400-017-G | RES,13.7KOhm,+/-0.1%,1/16W,G,SMD0402 | KOA SPEER ELECTRONICS, INC. | RN731ETTP1372B25 |  | PWA BOM | In Old BOM |
|  |  |  | 61100V400-024-G | RES,13.7KOhm,+/-0.1%,1/16W,G,SMD0402 | PANASONIC INDUSTRIAL CO.,LTD. | ERA2AEB1372X | G | PWA BOM | In Old BOM |
|  |  |  | 61100V400-029-G | RES,13.7KOhm,+/-0.1%,1/16W,G,SMD0402 | VISHAY ENTER TECHNO LOGY.INC | TNPW040213K7BEED | G | PWA BOM | In Old BOM |
| 375 | PSFR19 | 1 | 61100Y900-017-G | RES,11.8KOhm,+/-0.1%,1/16W,G,SMD0402 | KOA SPEER ELECTRONICS, INC. | RN731ETTP1182B25 | G | PWA BOM | In New BOM |
|  |  |  | 61100Y900-024-G | RES,11.8KOhm,+/-0.1%,1/16W,G,SMD0402 | PANASONIC INDUSTRIAL CO.,LTD. | ERA2AEB1182X | G | PWA BOM | In New BOM |
|  |  |  | 61100Y900-029-G | RES,11.8KOhm,+/-0.1%,1/16W,G,SMD0402 | VISHAY ENTER TECHNO LOGY.INC | TNPW040211K8BEED | G | PWA BOM | In New BOM |
|  | PSFR19 | 1 | 61100Y900-017-G | RES,11.8KOhm,+/-0.1%,1/16W,G,SMD0402 | KOA SPEER ELECTRONICS, INC. | RN731ETTP1182B25 |  | PWA BOM | In Old BOM |
|  |  |  | 61100Y900-024-G | RES,11.8KOhm,+/-0.1%,1/16W,G,SMD0402 | PANASONIC INDUSTRIAL CO.,LTD. | ERA2AEB1182X | G | PWA BOM | In Old BOM |
|  |  |  | 61100Y900-029-G | RES,11.8KOhm,+/-0.1%,1/16W,G,SMD0402 | VISHAY ENTER TECHNO LOGY.INC | TNPW040211K8BEED | G | PWA BOM | In Old BOM |
| 376 | PSIC3 | 1 | 62011LY01-015-G | CAP,160pF,+/-5%,NPO(C0G),50V,G,SMD0402 | MURATA ELEC. NORTH AMERICA | GRM1555C1H161JA01D | G | PWA BOM | In New BOM |
|  | PSIC3 | 1 | 62011LY01-015-G | CAP,160pF,+/-5%,NPO(C0G),50V,G,SMD0402 | MURATA ELEC. NORTH AMERICA | GRM1555C1H161JA01D |  | PWA BOM | In Old BOM |
| 377 | PSPC10 | 1 | 62013BS00-015-G | CAP,3nF,+/-10%,X7R,50V,G,SMD0402 | MURATA ELEC. NORTH AMERICA | GRM155R71H302KA01D | G | PWA BOM | In New BOM |
|  | PSPC10 | 1 | 62013BS00-015-G | CAP,3nF,+/-10%,X7R,50V,G,SMD0402 | MURATA ELEC. NORTH AMERICA | GRM155R71H302KA01D |  | PWA BOM | In Old BOM |
| 378 | PSRCE1 | 1 | 62120BA00-022-G | SPEA,CAP,180uF,+/-20%,16V,105C,G,SMD6.3*5.9,ESR<=22mOhm | SANYO ELECTRIC CO., LTD. | 16SVPF180M | G | PWA BOM | In New BOM |
|  |  |  | 62120D701-021-G | SPEA CAP,180uF,+/-20%,16V,105_x0003_,G,SMD6.3*5.8,ESR<=22mOhm | NIPPON CHEMI-CON CORPORATION | APXG160ARA181MF61G | G | PWA BOM | In New BOM |
|  | PSRCE1 | 1 | 62120BA00-022-G | SPEA,CAP,180uF,+/-20%,16V,105C,G,SMD6.3*5.9,ESR<=22mOhm | SANYO ELECTRIC CO., LTD. | 16SVPF180M | N | PWA BOM | In Old BOM |
|  |  |  | 62120D701-021-G | SPEA CAP,180uF,+/-20%,16V,105_x0003_,G,SMD6.3*5.8,ESR<=22mOhm | NIPPON CHEMI-CON CORPORATION | APXG160ARA181MF61G | G | PWA BOM | In Old BOM |
| 379 | PSRC4,PSUC5,PSRC5,PSUC6,PSRC6,PSUC7,PSUC8,PSUC9,PSUC10,PSRC3001,PSRC3002,PSRC3005 | 12 | 62012T500-015-G | CAP,22uF,+/-20%,X7S,25V,G,SMD1206 | MURATA ELEC. NORTH AMERICA | GRM31CC71E226ME11L | G | PWA BOM | In New BOM |
|  | PSRC4,PSUC5,PSRC5,PSUC6,PSRC6,PSUC7,PSUC8,PSUC9,PSUC10,PSRC3001,PSRC3002,PSRC3005 | 12 | 62012T500-015-G | CAP,22uF,+/-20%,X7S,25V,G,SMD1206 | MURATA ELEC. NORTH AMERICA | GRM31CC71E226ME11L |  | PWA BOM | In Old BOM |
| 380 | PSRC7 | 1 | 62013BQ00-015-G | CAP,3.6nF,+/-10%,X7R,50V,G,SMD0402 | MURATA ELEC. NORTH AMERICA | GRM155R71H362KA01D | G | PWA BOM | In New BOM |
|  | PSRC7 | 1 | 62013BQ00-015-G | CAP,3.6nF,+/-10%,X7R,50V,G,SMD0402 | MURATA ELEC. NORTH AMERICA | GRM155R71H362KA01D |  | PWA BOM | In Old BOM |
| 381 | PSRR12 | 1 | 61100P800-017-G | RES,8.45KOhm,+/-0.1%,1/16W,G,SMD0402 | KOA SPEER ELECTRONICS, INC. | RN731ETTP8451B25 | G | PWA BOM | In New BOM |
|  |  |  | 61100P800-024-G | RES,8.45KOhm,+/-0.1%,1/16W,G,SMD0402 | PANASONIC INDUSTRIAL CO.,LTD. | ERA2AEB8451X | G | PWA BOM | In New BOM |
|  |  |  | 61100P800-029-G | RES,8.45KOhm,+/-0.1%,1/16W,G,SMD0402 | VISHAY ENTER TECHNO LOGY.INC | TNPW04028K45BEED | G | PWA BOM | In New BOM |
|  | PSRR12 | 1 | 61100P800-017-G | RES,8.45KOhm,+/-0.1%,1/16W,G,SMD0402 | KOA SPEER ELECTRONICS, INC. | RN731ETTP8451B25 | Y | PWA BOM | In Old BOM |
|  |  |  | 61100P800-024-G | RES,8.45KOhm,+/-0.1%,1/16W,G,SMD0402 | PANASONIC INDUSTRIAL CO.,LTD. | ERA2AEB8451X | G | PWA BOM | In Old BOM |
|  |  |  | 61100P800-029-G | RES,8.45KOhm,+/-0.1%,1/16W,G,SMD0402 | VISHAY ENTER TECHNO LOGY.INC | TNPW04028K45BEED | G | PWA BOM | In Old BOM |
| 382 | PSRU1 | 1 | 32013FK00-238-G | IC,Regulator,IR3846MTRPBF,ADJ,35A,G,PQFN-26,SMD | INTERNATIONAL RECTIFIER | IR3846MTRPBF | G | PWA BOM | In New BOM |
|  | PSRU1 | 1 | 32013FK00-238-G | IC,Regulator,IR3846MTRPBF,ADJ,35A,G,PQFN-26,SMD | INTERNATIONAL RECTIFIER | IR3846MTRPBF |  | PWA BOM | In Old BOM |
| 383 | PSTR19 | 1 | 61100J401-017-G | RES,1.78KOhm,+/-0.1%,1/16W,G,SMD0402 | KOA SPEER ELECTRONICS, INC. | RN73H1ETTP1781B25 | G | PWA BOM | In New BOM |
|  |  |  | 61100J400-024-G | RES,1.78KOhm,+/-0.1%,1/16W,G,SMD0402 | PANASONIC INDUSTRIAL CO.,LTD. | ERA2AEB1781X | G | PWA BOM | In New BOM |
|  |  |  | MCS0402MD1781BE000 | RES,1.78KOhm,+/-0.1%,1/16W,G,SMD0402 | VISHAY ENTER TECHNO LOGY.INC | MCS0402MD1781BE000 | G | PWA BOM | In New BOM |
|  | PSTR19 | 1 | 61100J401-017-G | RES,1.78KOhm,+/-0.1%,1/16W,G,SMD0402 | KOA SPEER ELECTRONICS, INC. | RN73H1ETTP1781B25 |  | PWA BOM | In Old BOM |
|  |  |  | 61100J400-024-G | RES,1.78KOhm,+/-0.1%,1/16W,G,SMD0402 | PANASONIC INDUSTRIAL CO.,LTD. | ERA2AEB1781X | G | PWA BOM | In Old BOM |
|  |  |  | MCS0402MD1781BE000 | RES,1.78KOhm,+/-0.1%,1/16W,G,SMD0402 | VISHAY ENTER TECHNO LOGY.INC | MCS0402MD1781BE000 | G | PWA BOM | In Old BOM |
| 384 | PSUR1,PSUR4 | 2 | 610119C00-017-G | RES,130KOhm,+/-1%,1/16W,G,SMD0402 | KOA SPEER ELECTRONICS, INC. | RK73H1ETTP1303F | G | PWA BOM | In New BOM |
|  |  |  | 610119C00-011-G | RES,130KOhm,+/-1%,1/16W,G,SMD0402 | YAGEO CORPORATION COMPONENT | RC0402FR-07130KL | G | PWA BOM | In New BOM |
|  |  |  | 610119C00-012-G | RES,130KOhm,+/-1%,1/16W,G,SMD0402 | WALSIN TECHNOLOGY CORPORATION | WR04X1303FTL | G | PWA BOM | In New BOM |
|  |  |  | 610119C00-044-G | RES,130KOhm,+/-1%,1/16W,G,SMD0402 | TA-I TECHNOLOGY CO., LTD | RM04FTN1303 | G | PWA BOM | In New BOM |
|  | PSUR1,PSUR4 | 2 | 610119C00-017-G | RES,130KOhm,+/-1%,1/16W,G,SMD0402 | KOA SPEER ELECTRONICS, INC. | RK73H1ETTP1303F | N | PWA BOM | In Old BOM |
|  |  |  | 610119C00-011-G | RES,130KOhm,+/-1%,1/16W,G,SMD0402 | YAGEO CORPORATION COMPONENT | RC0402FR-07130KL | G | PWA BOM | In Old BOM |
|  |  |  | 610119C00-012-G | RES,130KOhm,+/-1%,1/16W,G,SMD0402 | WALSIN TECHNOLOGY CORPORATION | WR04X1303FTL | G | PWA BOM | In Old BOM |
|  |  |  | 610119C00-044-G | RES,130KOhm,+/-1%,1/16W,G,SMD0402 | TA-I TECHNOLOGY CO., LTD | RM04FTN1303 | G | PWA BOM | In Old BOM |
| 385 | PSUR2,PSUR5 | 2 | 610116G00-017-G | RES,150KOhm,+/-1%,1/16W,G,SMD0402 | KOA SPEER ELECTRONICS, INC. | RK73H1ETTP1503F | G | PWA BOM | In New BOM |
|  |  |  | 610116G00-011-G | RES,150KOhm,+/-1%,1/16W,G,SMD0402 | YAGEO CORPORATION COMPONENT | RC0402FR-07150KL | G | PWA BOM | In New BOM |
|  |  |  | 610116G00-012-G | RES,150KOhm,+/-1%,1/16W,G,SMD0402 | WALSIN TECHNOLOGY CORPORATION | WR04X1503FTL | G | PWA BOM | In New BOM |
|  |  |  | 610116G00-044-G | RES,150KOhm,+/-1%,1/16W,G,SMD0402 | TA-I TECHNOLOGY CO., LTD | RM04FTN1503 | G | PWA BOM | In New BOM |
|  | PSUR2,PSUR5 | 2 | 610116G00-017-G | RES,150KOhm,+/-1%,1/16W,G,SMD0402 | KOA SPEER ELECTRONICS, INC. | RK73H1ETTP1503F | N | PWA BOM | In Old BOM |
|  |  |  | 610116G00-011-G | RES,150KOhm,+/-1%,1/16W,G,SMD0402 | YAGEO CORPORATION COMPONENT | RC0402FR-07150KL | G | PWA BOM | In Old BOM |
|  |  |  | 610116G00-012-G | RES,150KOhm,+/-1%,1/16W,G,SMD0402 | WALSIN TECHNOLOGY CORPORATION | WR04X1503FTL | G | PWA BOM | In Old BOM |
|  |  |  | 610116G00-044-G | RES,150KOhm,+/-1%,1/16W,G,SMD0402 | TA-I TECHNOLOGY CO., LTD | RM04FTN1503 | G | PWA BOM | In Old BOM |
| 386 | Q1,Q9,Q10,Q11,Q13,Q14,Q24,Q25,Q26,Q27,Q28,Q29,Q30,Q31,Q32,Q33,Q34,Q35,Q36,Q37,Q38,Q39,Q40,Q41,Q42,Q43,Q44,Q45,Q46,Q47,Q48,Q49,Q50,Q51,Q52,Q53,Q54,Q55,Q56,Q57,Q58,Q59,Q60,Q93 | 44 | 51030QP00-237-G | MOS N,BSS138W-7-F,50V,0.2A,3.5ohm@10V,G,SOT323-3,SMD | DIODES INEORPORATION | BSS138W-7-F | G | PWA BOM | In New BOM |
|  |  |  | 51031KA00-031-G | MOS N,BSS138PW,60V,320mA, 2ohm@5V,G,SC70-3,SMD | NXP SEMICONDUCTORS | BSS138PW | G | PWA BOM | In New BOM |
|  |  |  | 51031WU00-221-G | MOS N,BSS138W H6327,60V,280mA,3.5m@10V,G,SOT323-3,SMD | INFINEON TECHNOLOGIES CORP. | BSS138W H6327 | G | PWA BOM | In New BOM |
|  | Q1,Q9,Q10,Q11,Q13,Q14,Q24,Q25,Q26,Q27,Q28,Q29,Q30,Q31,Q32,Q33,Q34,Q35,Q36,Q37,Q38,Q39,Q40,Q41,Q42,Q43,Q44,Q45,Q46,Q47,Q48,Q49,Q50,Q51,Q52,Q53,Q54,Q55,Q56,Q57,Q58,Q59,Q60,Q93 | 44 | 51030QP00-237-G | MOS N,BSS138W-7-F,50V,0.2A,3.5ohm@10V,G,SOT323-3,SMD | DIODES INEORPORATION | BSS138W-7-F | N | PWA BOM | In Old BOM |
|  |  |  | 51031KA00-031-G | MOS N,BSS138PW,60V,320mA, 2ohm@5V,G,SC70-3,SMD | NXP SEMICONDUCTORS | BSS138PW | G | PWA BOM | In Old BOM |
|  |  |  | 51031WU00-221-G | MOS N,BSS138W H6327,60V,280mA,3.5m@10V,G,SOT323-3,SMD | INFINEON TECHNOLOGIES CORP. | BSS138W H6327 | G | PWA BOM | In Old BOM |
| 387 | Q2,Q3,Q4,Q6 | 4 | 510301N00-223-G | MOS N,2N7002LT1G,60V,0.115A,7.5ohm@5V,G,SOT23-3,SMD | ON SEMICONDUCTOR CORP | 2N7002LT1G | G | PWA BOM | In New BOM |
|  |  |  | 51030CQ00-185-G | MOS N,2N7002,60V,115mA,7.5ohm@5V,G,SOT23-3,SMD | FAIRCHILD SEMICONDUCTOR CORP | 2N7002 |  | PWA BOM | In New BOM |
|  | Q2,Q3,Q4,Q6 | 4 | 510301N00-223-G | MOS N,2N7002LT1G,60V,0.115A,7.5ohm@5V,G,SOT23-3,SMD | ON SEMICONDUCTOR CORP | 2N7002LT1G | N | PWA BOM | In Old BOM |
| 388 | PSUQ1 | 1 | 510301N00-223-G | MOS N,2N7002LT1G,60V,0.115A,7.5ohm@5V,G,SOT23-3,SMD | ON SEMICONDUCTOR CORP | 2N7002LT1G | G | PWA BOM | In New BOM |
|  |  |  | 51030CQ00-185-G | MOS N,2N7002,60V,115mA,7.5ohm@5V,G,SOT23-3,SMD | FAIRCHILD SEMICONDUCTOR CORP | 2N7002 |  | PWA BOM | In New BOM |
|  | PSUQ1 | 1 | 51030CQ00-185-G | MOS N,2N7002,60V,115mA,7.5ohm@5V,G,SOT23-3,SMD | FAIRCHILD SEMICONDUCTOR CORP | 2N7002 | N | PWA BOM | In Old BOM |
|  |  |  | 510301N00-223-G_1 | MOS N,2N7002LT1G,60V,0.115A,7.5ohm@5V,G,SOT23-3,SMD | ON SEMICONDUCTOR CORP | 2N7002LT1G | G | PWA BOM | In Old BOM |
| 389 | R11,R12,R13,R373,R374,R375 | 6 | 61100Y400-017-G | RES,169 Ohm,+/-0.1%,1/16W,G,SMD0402 | KOA SPEER ELECTRONICS, INC. | RN731ETTP1690B25 | G | PWA BOM | In New BOM |
|  | R11,R12,R13,R373,R374,R375 | 6 | 61100Y400-017-G | RES,169 Ohm,+/-0.1%,1/16W,G,SMD0402 | KOA SPEER ELECTRONICS, INC. | RN731ETTP1690B25 |  | PWA BOM | In Old BOM |
| 390 | R751 | 1 | 61100H601-017-G | RES,2KOhm,+/-0.5%,1/16W,G,SMD0402 | KOA SPEER ELECTRONICS, INC. | RN731ETTP2001D25 | G | PWA BOM | In New BOM |
|  | R751 | 1 | 61100H601-017-G | RES,2KOhm,+/-0.5%,1/16W,G,SMD0402 | KOA SPEER ELECTRONICS, INC. | RN731ETTP2001D25 | Y | PWA BOM | In Old BOM |
| 391 | R839,R840,R841,R842,R843,R844,R845,R846,R847,R848,R849,R850,R851,R852,R853,R854,R855,R856,R857,R858,R859,R860,R861,R862,R867,R868,R869,R870,R871,R872,R873,R874,R875,R876,R877,R878,R879,R880,R881,R882,R883,R884,R885,R887,R888,R889,R890,R891 | 48 | 61011U901-017-G | RES,120Ohm,+/-1%,1/20W,G,SMD0201 | KOA SPEER ELECTRONICS, INC. | RK73H1HTTC1200F | G | PWA BOM | In New BOM |
|  | R839,R840,R841,R842,R843,R844,R845,R846,R847,R848,R849,R850,R851,R852,R853,R854,R855,R856,R857,R858,R859,R860,R861,R862,R867,R868,R869,R870,R871,R872,R873,R874,R875,R876,R877,R878,R879,R880,R881,R882,R883,R884,R885,R887,R888,R889,R890,R891 | 48 | 61011U901-017-G | RES,120Ohm,+/-1%,1/20W,G,SMD0201 | KOA SPEER ELECTRONICS, INC. | RK73H1HTTC1200F |  | PWA BOM | In Old BOM |
| 392 | R1483 | 1 | 61100QT01-017-G | RES,10 Ohm,+/-0.5%,1/16W,G,SMD0402 | KOA SPEER ELECTRONICS, INC. | RN731ETTP10R0D25 | G | PWA BOM | In New BOM |
|  | R1483 | 1 | 61100QT01-017-G | RES,10 Ohm,+/-0.5%,1/16W,G,SMD0402 | KOA SPEER ELECTRONICS, INC. | RN731ETTP10R0D25 |  | PWA BOM | In Old BOM |
| 393 | R1492 | 1 | 610118800-017-G | RES,499KOhm,+/-1%,1/8W,G,SMD0805 | KOA SPEER ELECTRONICS, INC. | RK73H2ATTD4993F | G | PWA BOM | In New BOM |
|  |  |  | 610118800-024-G | RES,499KOhm,+/-1%,1/8W,G,SMD0805 | PANASONIC INDUSTRIAL CO.,LTD. | ERJ6ENF4993V | G | PWA BOM | In New BOM |
|  | R1492 | 1 | 610118800-017-G | RES,499KOhm,+/-1%,1/8W,G,SMD0805 | KOA SPEER ELECTRONICS, INC. | RK73H2ATTD4993F | N | PWA BOM | In Old BOM |
|  |  |  | 610118800-024-G | RES,499KOhm,+/-1%,1/8W,G,SMD0805 | PANASONIC INDUSTRIAL CO.,LTD. | ERJ6ENF4993V | G | PWA BOM | In Old BOM |
| 394 | R1769,R1770 | 2 | 610130300-017-G | RES,60.4 Ohm,+/-1%,1/20W,G,SMD0201 | KOA SPEER ELECTRONICS, INC. | RK73H1HTTC60R4F | G | PWA BOM | In New BOM |
|  |  |  | CRCW020160R4FKED | RES,60.4 Ohm,+/-1%,1/20W,G,SMD0201 | VISHAY ENTER TECHNO LOGY.INC | CRCW020160R4FKED | G | PWA BOM | In New BOM |
|  |  |  | 610130300-024-G | RES,60.4 Ohm,+/-1%,1/20W,G,SMD0201 | PANASONIC INDUSTRIAL CO.,LTD. | ERJ1GNF60R4C | G | PWA BOM | In New BOM |
|  | R1769,R1770 | 2 | 610130300-017-G | RES,60.4 Ohm,+/-1%,1/20W,G,SMD0201 | KOA SPEER ELECTRONICS, INC. | RK73H1HTTC60R4F |  | PWA BOM | In Old BOM |
|  |  |  | CRCW020160R4FKED | RES,60.4 Ohm,+/-1%,1/20W,G,SMD0201 | VISHAY ENTER TECHNO LOGY.INC | CRCW020160R4FKED | G | PWA BOM | In Old BOM |
|  |  |  | 610130300-024-G | RES,60.4 Ohm,+/-1%,1/20W,G,SMD0201 | PANASONIC INDUSTRIAL CO.,LTD. | ERJ1GNF60R4C | G | PWA BOM | In Old BOM |
| 395 | U_LOM1_ROM1 | 1 | 41050W700-46Y-G | Flash,AT45DB081E-SHNHC-T,1.65~3.6V,8M,SPI,G,SOIC-8,SMD | Adesto Technologies Corporation | AT45DB081E-SHNHC-T | G | PWA BOM | In New BOM |
|  | U_LOM1_ROM1 | 1 | 41050W700-46Y-G | Flash,AT45DB081E-SHNHC-T,1.65~3.6V,8M,SPI,G,SOIC-8,SMD | Adesto Technologies Corporation | AT45DB081E-SHNHC-T |  | PWA BOM | In Old BOM |
| 396 | U3,U4 | 2 | 320242G00-183-G | IC,Power Controller,LM3880MFX-1AA/NOPB,G,SOT-23-6,SMD | TEXAS INSTRUMENTS | LM3880MFX-1AA/NOPB | G | PWA BOM | In New BOM |
|  | U3,U4 | 2 | 320242G00-183-G | IC,Power Controller,LM3880MFX-1AA/NOPB,G,SOT-23-6,SMD | TEXAS INSTRUMENTS | LM3880MFX-1AA/NOPB |  | PWA BOM | In Old BOM |
| 397 | U5 | 1 | 320241C00-183-G | IC,Power Controller,UCD90160RGCR,G,VQFN-64,SMD | TEXAS INSTRUMENTS | UCD90160RGCR | G | PWA BOM | In New BOM |
|  | U5 | 1 | 320241C00-183-G | IC,Power Controller,UCD90160RGCR,G,VQFN-64,SMD | TEXAS INSTRUMENTS | UCD90160RGCR |  | PWA BOM | In Old BOM |
| 398 | U6,U7,U8,U9,U53,U54,U56,U57,U58,U59,U64,U65,U67,U69,U70,U71,U72,U85,U88,U103,U111,U113,U114,U115,U117,U169 | 26 | 310502800-031-G | IC,Buffer,74LVC1G07GW,1.65~5.5V,G,SOT353-5,SMD | NXP SEMICONDUCTORS | 74LVC1G07GW | G | PWA BOM | In New BOM |
|  |  |  | 31050CU00-131-G | IC,Buffer,TC7SZ07FU,1.65~5.5V,G,SSOP-5,SMD | TOSHIBA ELECTRONICS ASIA LTD | TC7SZ07FU | G | PWA BOM | In New BOM |
|  |  |  | 310502C00-223-G | IC,Buffer,NL17SZ07DFT2G,1.65~5.50V,G,SC-88A/SOT-353-5,SMD | ON SEMICONDUCTOR CORP | NL17SZ07DFT2G | G | PWA BOM | In New BOM |
|  | U6,U7,U8,U9,U53,U54,U56,U57,U58,U59,U64,U65,U67,U69,U70,U71,U72,U85,U88,U103,U111,U113,U114,U115,U117,U169 | 26 | 310502800-031-G | IC,Buffer,74LVC1G07GW,1.65~5.5V,G,SOT353-5,SMD | NXP SEMICONDUCTORS | 74LVC1G07GW | N | PWA BOM | In Old BOM |
|  |  |  | 31050CU00-131-G | IC,Buffer,TC7SZ07FU,1.65~5.5V,G,SSOP-5,SMD | TOSHIBA ELECTRONICS ASIA LTD | TC7SZ07FU | G | PWA BOM | In Old BOM |
|  |  |  | 310502C00-223-G | IC,Buffer,NL17SZ07DFT2G,1.65~5.50V,G,SC-88A/SOT-353-5,SMD | ON SEMICONDUCTOR CORP | NL17SZ07DFT2G | G | PWA BOM | In Old BOM |
| 399 | U12 | 1 | 310406Q00-031-G | IC,Multiplexer,CBTL01023GM,3V~3.6V,G,XQFN-10,SMD | NXP SEMICONDUCTORS | CBTL01023GM | G | PWA BOM | In New BOM |
|  | U12 | 1 | 310406Q00-031-G | IC,Multiplexer,CBTL01023GM,3V~3.6V,G,XQFN-10,SMD | NXP SEMICONDUCTORS | CBTL01023GM |  | PWA BOM | In Old BOM |
| 400 | U13 | 1 | 21040M500-283-G | IC,BROADCOM,BCM54612EB1KMLG,B1,G,MLP-48,SMD | BROADCOM SINGAPORE PTE LTD. | BCM54612EB1KMLG | G | PWA BOM | In New BOM |
|  | U13 | 1 | 21040M500-283-G | IC,BROADCOM,BCM54612EB1KMLG,B1,G,MLP-48,SMD | BROADCOM SINGAPORE PTE LTD. | BCM54612EB1KMLG |  | PWA BOM | In Old BOM |
| 401 | U14 | 1 | 21012NJ00-687-G | IC,ASPEED,AST2500A2-GP,A2,G,TFBGA-456,SMD | ASPEED TECHNOLOGY INC | AST2500A2-GP | G | PWA BOM | In New BOM |
|  | U14 | 1 | 21012NJ00-687-G | IC,ASPEED,AST2500A2-GP,A2,G,TFBGA-456,SMD | ASPEED TECHNOLOGY INC | AST2500A2-GP |  | PWA BOM | In Old BOM |
| 402 | U15,U16 | 2 | 31030CA00-031-G | IC,Switch,PCA9546APW,2.3~5.5V,G,TSSOP-16,SMD | NXP SEMICONDUCTORS | PCA9546APW | G | PWA BOM | In New BOM |
|  |  |  | 31030YF00-252-G | Logic IC,Switch,PI4MSD5V9546ALEX,1.65V~5.5V,0.3ns,TSSOP,16P,G | PERICOM SEMICONDUCTOR CORP | PI4MSD5V9546ALEX | G | PWA BOM | In New BOM |
|  | U15,U16 | 2 | 31030CA00-031-G | IC,Switch,PCA9546APW,2.3~5.5V,G,TSSOP-16,SMD | NXP SEMICONDUCTORS | PCA9546APW | N | PWA BOM | In Old BOM |
|  |  |  | 31030YF00-252-G | Logic IC,Switch,PI4MSD5V9546ALEX,1.65V~5.5V,0.3ns,TSSOP,16P,G | PERICOM SEMICONDUCTOR CORP | PI4MSD5V9546ALEX | G | PWA BOM | In Old BOM |
| 403 | U18,U19 | 2 | 310311G00-183-G | IC,Switch,TS3L110RGYR,3V~3.6V,G,VQFN-16,SMD | TEXAS INSTRUMENTS | TS3L110RGYR | G | PWA BOM | In New BOM |
|  | U18,U19 | 2 | 310311G00-183-G | IC,Switch,TS3L110RGYR,3V~3.6V,G,VQFN-16,SMD | TEXAS INSTRUMENTS | TS3L110RGYR |  | PWA BOM | In Old BOM |
| 404 | U25,U179 | 2 | 310312S00-217-G | IC,Switch,74CBTLV3125QG8,2.3V~3.6V,G,QSOP-16,SMD | INTEGRATED DEVICE TECHNOLOGY | 74CBTLV3125QG8 | G | PWA BOM | In New BOM |
|  |  |  | 310305U00-252-G | Logic IC,Switch,PI3B3125QEX,3.0V~3.6V,0.25ns,QSOP,16P,G | PERICOM SEMICONDUCTOR CORP | PI3B3125QEX | G | PWA BOM | In New BOM |
|  | U25,U179 | 2 | 310312S00-217-G | IC,Switch,74CBTLV3125QG8,2.3V~3.6V,G,QSOP-16,SMD | INTEGRATED DEVICE TECHNOLOGY | 74CBTLV3125QG8 |  | PWA BOM | In Old BOM |
|  |  |  | 310305U00-252-G | Logic IC,Switch,PI3B3125QEX,3.0V~3.6V,0.25ns,QSOP,16P,G | PERICOM SEMICONDUCTOR CORP | PI3B3125QEX | G | PWA BOM | In Old BOM |
| 405 | U27 | 1 | 310408900-217-G | IC,Switch,74CBTLV3257PGG8,2.3~3.6V,G,TSSOP-16,SMD | INTEGRATED DEVICE TECHNOLOGY | 74CBTLV3257PGG8 | G | PWA BOM | In New BOM |
|  |  |  | 310405F00-252-G | Logic IC,Multiplexer,PI3B3257LEX,2.97V~3.63V,0.25ns,TSSOP,16P,G | PERICOM SEMICONDUCTOR CORP | PI3B3257LEX | G | PWA BOM | In New BOM |
|  | U27 | 1 | 310408900-217-G | IC,Switch,74CBTLV3257PGG8,2.3~3.6V,G,TSSOP-16,SMD | INTEGRATED DEVICE TECHNOLOGY | 74CBTLV3257PGG8 | N | PWA BOM | In Old BOM |
|  |  |  | 310405F00-252-G | Logic IC,Multiplexer,PI3B3257LEX,2.97V~3.63V,0.25ns,TSSOP,16P,G | PERICOM SEMICONDUCTOR CORP | PI3B3257LEX | G | PWA BOM | In Old BOM |
| 406 | U30 | 1 | 41040BT00-191-G | EEPROM,AT24C64D-SSHM-T,1.7~5.5V,64K,I2C,G,SOIC-8,SMD | ATMEL CORPORATION | AT24C64D-SSHM-T | G | PWA BOM | In New BOM |
|  |  |  | 410405H00-214-G | EEPROM,M24C64-RMN6TP,1.8~5.5V,64K,I2C,G,SO-8,SMD | ST MICRO ELECTRONICS,INC | M24C64-RMN6TP | G | PWA BOM | In New BOM |
|  |  |  | 410409E00-223-G | EEPROM,CAT24C64WI-GT3,1.8~5.5V,64K,I2C,G,SOIC-8,SMD | ON SEMICONDUCTOR CORP | CAT24C64WI-GT3 | G | PWA BOM | In New BOM |
|  | U30 | 1 | 41040BT00-191-G | EEPROM,AT24C64D-SSHM-T,1.7~5.5V,64K,I2C,G,SOIC-8,SMD | ATMEL CORPORATION | AT24C64D-SSHM-T | N | PWA BOM | In Old BOM |
|  |  |  | 410405H00-214-G | EEPROM,M24C64-RMN6TP,1.8~5.5V,64K,I2C,G,SO-8,SMD | ST MICRO ELECTRONICS,INC | M24C64-RMN6TP | G | PWA BOM | In Old BOM |
|  |  |  | 410409E00-223-G | EEPROM,CAT24C64WI-GT3,1.8~5.5V,64K,I2C,G,SOIC-8,SMD | ON SEMICONDUCTOR CORP | CAT24C64WI-GT3 | G | PWA BOM | In Old BOM |
| 407 | U31 | 1 | 310504D00-031-G | IC,Buffer,74LVC2G125DP,1.65~5.5V,G,TSSOP-8,SMD | NXP SEMICONDUCTORS | 74LVC2G125DP | G | PWA BOM | In New BOM |
|  | U31 | 1 | 310504D00-031-G | IC,Buffer,74LVC2G125DP,1.65~5.5V,G,TSSOP-8,SMD | NXP SEMICONDUCTORS | 74LVC2G125DP | N | PWA BOM | In Old BOM |
| 408 | U32 | 1 | 320501P00-173-G | IC,Driver/Receiver,MAX3243CAI+T,G,SSOP-28,SMD | MAXIM INTEGRATED PRODUCTS, INC. | MAX3243CAI+T | G | PWA BOM | In New BOM |
|  |  |  | 320503B00-214-G | IC,Driver/Receiver,ST3243ECTR-E,G,TSSOP-28,SMD | ST MICRO ELECTRONICS,INC | ST3243ECTR-E | G | PWA BOM | In New BOM |
|  | U32 | 1 | 320501P00-173-G | IC,Driver/Receiver,MAX3243CAI+T,G,SSOP-28,SMD | MAXIM INTEGRATED PRODUCTS, INC. | MAX3243CAI+T | N | PWA BOM | In Old BOM |
|  |  |  | 320503B00-214-G | IC,Driver/Receiver,ST3243ECTR-E,G,TSSOP-28,SMD | ST MICRO ELECTRONICS,INC | ST3243ECTR-E | G | PWA BOM | In Old BOM |
| 409 | U33,U35,U177 | 3 | 32022AL00-223-G | IC,Power Controller,NCP380HSNAJAAT1G,G,TSOP-6,SMD | ON SEMICONDUCTOR CORP | NCP380HSNAJAAT1G | G | PWA BOM | In New BOM |
|  | U33,U35,U177 | 3 | 32022AL00-223-G | IC,Power Controller,NCP380HSNAJAAT1G,G,TSOP-6,SMD | ON SEMICONDUCTOR CORP | NCP380HSNAJAAT1G |  | PWA BOM | In Old BOM |
| 410 | U36 | 1 | 21081AQ00-426-G | IC,RENESAS,uPD720201K8-701-BAC-A,G,QFN-68,SMD | RENESAS TECHNOLOGY AMERICA INC | uPD720201K8-701-BAC-A | G | PWA BOM | In New BOM |
|  | U36 | 1 | 21081AQ00-426-G | IC,RENESAS,uPD720201K8-701-BAC-A,G,QFN-68,SMD | RENESAS TECHNOLOGY AMERICA INC | uPD720201K8-701-BAC-A |  | PWA BOM | In Old BOM |
| 411 | U37 | 1 | 41050J100-233-G | Flash,MX25L5121EMC-20G,2.7~3.6V,512K,SPI,G,SOP-8,SMD | MACRONIX INTERNATIONAL CO.,LTD. | MX25L5121EMC-20G | G | PWA BOM | In New BOM |
|  |  |  | 41050YB00-36F-G | NOR Flash,GD25D05BTIG,2.7V,N/A,3.6V,512K,SPI,-40_x0003_~85_x0003_,SOP,8P,G | GIGADEVICE | GD25D05BTIG | G | PWA BOM | In New BOM |
|  | U37 | 1 | 41050J100-233-G | Flash,MX25L5121EMC-20G,2.7~3.6V,512K,SPI,G,SOP-8,SMD | MACRONIX INTERNATIONAL CO.,LTD. | MX25L5121EMC-20G | N | PWA BOM | In Old BOM |
|  |  |  | 41050YB00-36F-G | NOR Flash,GD25D05BTIG,2.7V,N/A,3.6V,512K,SPI,-40_x0003_~85_x0003_,SOP,8P,G | GIGADEVICE | GD25D05BTIG | G | PWA BOM | In Old BOM |
| 412 | U38 | 1 | 210826400-183-G | IC,TI,TUSB2077APTR,G,LQFP-48,SMD | TEXAS INSTRUMENTS | TUSB2077APTR | G | PWA BOM | In New BOM |
|  | U38 | 1 | 210826400-183-G | IC,TI,TUSB2077APTR,G,LQFP-48,SMD | TEXAS INSTRUMENTS | TUSB2077APTR |  | PWA BOM | In Old BOM |
| 413 | U45 | 1 | 21081N000-348-G | IC,MARVELL,88SE9235A1-NAA2C000,A1,G,QFN-76,SMD | MARVELL SEMICONDUCTOR, INC | 88SE9235A1-NAA2C000[VER.A1] | G | PWA BOM | In New BOM |
|  | U45 | 1 | 21081N000-348-G | IC,MARVELL,88SE9235A1-NAA2C000,A1,G,QFN-76,SMD | MARVELL SEMICONDUCTOR, INC | 88SE9235A1-NAA2C000[VER.A1] |  | PWA BOM | In Old BOM |
| 414 | U46 | 1 | 41050K700-233-G | Flash,MX25L4006EM2I-12G,2.7V~3.6V,4M,SPI,G,SOP-8,SMD | MACRONIX INTERNATIONAL CO.,LTD. | MX25L4006EM2I-12G | G | PWA BOM | In New BOM |
|  |  |  | 41050RL00-205-G | NOR Flash,W25X40CLSSIG,2.3V,N/A,3.6V,4M,SPI,-40_x0003_~85_x0003_,SOIC,8P,G | WINBOND | W25X40CLSSIG | G | PWA BOM | In New BOM |
|  | U46 | 1 | 41050K700-233-G | Flash,MX25L4006EM2I-12G,2.7V~3.6V,4M,SPI,G,SOP-8,SMD | MACRONIX INTERNATIONAL CO.,LTD. | MX25L4006EM2I-12G |  | PWA BOM | In Old BOM |
|  |  |  | 41050RL00-205-G | NOR Flash,W25X40CLSSIG,2.3V,N/A,3.6V,4M,SPI,-40_x0003_~85_x0003_,SOIC,8P,G | WINBOND | W25X40CLSSIG | G | PWA BOM | In Old BOM |
| 415 | U55,U168 | 2 | 310203000-031-G | IC,Trigger,74LVC74APW,1.2~3.6V,G,TSSOP-14,SMD | NXP SEMICONDUCTORS | 74LVC74APW | G | PWA BOM | In New BOM |
|  |  |  | 310202400-223-G | IC,Trigger,MC74LCX74DTR2G,2.3~3.6V,G,TSSOP-14,SMD | ON SEMICONDUCTOR CORP | MC74LCX74DTR2G | G | PWA BOM | In New BOM |
|  |  |  | 310208S00-131-G | IC,Trigger,74LCX74FT,1.65V~3.6V,G,TSSOP-14,SMD | TOSHIBA ELECTRONICS ASIA LTD | 74LCX74FT | G | PWA BOM | In New BOM |
|  | U55,U168 | 2 | 310203000-031-G | IC,Trigger,74LVC74APW,1.2~3.6V,G,TSSOP-14,SMD | NXP SEMICONDUCTORS | 74LVC74APW | N | PWA BOM | In Old BOM |
|  |  |  | 310202400-223-G | IC,Trigger,MC74LCX74DTR2G,2.3~3.6V,G,TSSOP-14,SMD | ON SEMICONDUCTOR CORP | MC74LCX74DTR2G | G | PWA BOM | In Old BOM |
|  |  |  | 310208S00-131-G | IC,Trigger,74LCX74FT,1.65V~3.6V,G,TSSOP-14,SMD | TOSHIBA ELECTRONICS ASIA LTD | 74LCX74FT | G | PWA BOM | In Old BOM |
| 416 | U60 | 1 | 21050P200-031-G | IC,NXP,PCF8523TK,G,HVSON-8,SMD | NXP SEMICONDUCTORS | PCF8523TK | G | PWA BOM | In New BOM |
|  | U60 | 1 | 21050P200-031-G | IC,NXP,PCF8523TK,G,HVSON-8,SMD | NXP SEMICONDUCTORS | PCF8523TK |  | PWA BOM | In Old BOM |
| 417 | U61 | 1 | 21050Q600-217-G | IC,IDT,5PB1102PGGI8,G,TSSOP-8,SMD | INTEGRATED DEVICE TECHNOLOGY | 5PB1102PGGI8 | G | PWA BOM | In New BOM |
|  |  |  | 31050JY00-223-G | Logic IC,Buffer,NB3V1102CDTR2G,1.8V/2.5V/3.3V,3.5ns,TSSOP,8P,G | ON | NB3V1102CDTR2G | G | PWA BOM | In New BOM |
|  | U61 | 1 | 21050Q600-217-G | IC,IDT,5PB1102PGGI8,G,TSSOP-8,SMD | INTEGRATED DEVICE TECHNOLOGY | 5PB1102PGGI8 |  | PWA BOM | In Old BOM |
|  |  |  | 31050JY00-223-G | Logic IC,Buffer,NB3V1102CDTR2G,1.8V/2.5V/3.3V,3.5ns,TSSOP,8P,G | ON | NB3V1102CDTR2G | G | PWA BOM | In Old BOM |
| 418 | U62 | 1 | 21050R500-298-G | IC,SILABS,Si5338C-B06799-GMR,G,QFN-24,SMD | Silicon Laboratories Inc. | SI5338C-B06799-GMR | G | PWA BOM | In New BOM |
|  | U62 | 1 | 21050R500-298-G | IC,SILABS,Si5338C-B06799-GMR,G,QFN-24,SMD | Silicon Laboratories Inc. | SI5338C-B06799-GMR |  | PWA BOM | In Old BOM |
| 419 | U63 | 1 | 21050P100-217-G | IC,IDT,9DBL0452BKILFT,G,VFQFPN-32,SMD | INTEGRATED DEVICE TECHNOLOGY | 9DBL0452BKILFT | G | PWA BOM | In New BOM |
|  | U63 | 1 | 21050P100-217-G | IC,IDT,9DBL0452BKILFT,G,VFQFPN-32,SMD | INTEGRATED DEVICE TECHNOLOGY | 9DBL0452BKILFT |  | PWA BOM | In Old BOM |
| 420 | U66,U73,U74,U75,U76,U77,U78,U79,U80,U81,U82,U161,U178 | 13 | 310101400-031-G | IC,Gate&Inverter,74LVC1G08GW,1.65~5.5V,G,SOT353-5,SMD | NXP SEMICONDUCTORS | 74LVC1G08GW | G | PWA BOM | In New BOM |
|  |  |  | 310103J00-223-G | IC,Gate&Inverter,NL17SZ08DFT2G,1.65~5.5V,G,SOT353-5,SMD | ON SEMICONDUCTOR CORP | NL17SZ08DFT2G | G | PWA BOM | In New BOM |
|  |  |  | 31010J400-131-G | IC,Gate&Inverter,TC7SZ08FU,1.8~5.5V,G,SSOP-5,SMD | TOSHIBA ELECTRONICS ASIA LTD | TC7SZ08FU | G | PWA BOM | In New BOM |
|  | U66,U73,U74,U75,U76,U77,U78,U79,U80,U81,U82,U161,U178 | 13 | 310101400-031-G | IC,Gate&Inverter,74LVC1G08GW,1.65~5.5V,G,SOT353-5,SMD | NXP SEMICONDUCTORS | 74LVC1G08GW | N | PWA BOM | In Old BOM |
|  |  |  | 310103J00-223-G | IC,Gate&Inverter,NL17SZ08DFT2G,1.65~5.5V,G,SOT353-5,SMD | ON SEMICONDUCTOR CORP | NL17SZ08DFT2G | G | PWA BOM | In Old BOM |
|  |  |  | 31010J400-131-G | IC,Gate&Inverter,TC7SZ08FU,1.8~5.5V,G,SSOP-5,SMD | TOSHIBA ELECTRONICS ASIA LTD | TC7SZ08FU | G | PWA BOM | In Old BOM |
| 421 | U68,U86,U89 | 3 | 310504B00-031-G | IC,Buffer,74LVC1G17GW,1.65~5.5V,G,SOT353-5,SMD | NXP SEMICONDUCTORS | 74LVC1G17GW | G | PWA BOM | In New BOM |
|  |  |  | 310507Q00-223-G | Logic IC,Buffer,NL17SZ17DFT2G,1.65V~5.5V,15ns,SC-88A/SOT-353,5P,G | ON SEMICONDUCTOR CORP | NL17SZ17DFT2G | G | PWA BOM | In New BOM |
|  |  |  | 31050BH00-131-G | IC,Buffer,TC7SZ17FU,1.65~5.5V,G,SSOP-5,SMD | TOSHIBA ELECTRONICS ASIA LTD | TC7SZ17FU | G | PWA BOM | In New BOM |
|  | U68,U86,U89 | 3 | 310504B00-031-G | IC,Buffer,74LVC1G17GW,1.65~5.5V,G,SOT353-5,SMD | NXP SEMICONDUCTORS | 74LVC1G17GW | N | PWA BOM | In Old BOM |
|  |  |  | 310507Q00-223-G | Logic IC,Buffer,NL17SZ17DFT2G,1.65V~5.5V,15ns,SC-88A/SOT-353,5P,G | ON SEMICONDUCTOR CORP | NL17SZ17DFT2G | G | PWA BOM | In Old BOM |
|  |  |  | 31050BH00-131-G | IC,Buffer,TC7SZ17FU,1.65~5.5V,G,SSOP-5,SMD | TOSHIBA ELECTRONICS ASIA LTD | TC7SZ17FU | G | PWA BOM | In Old BOM |
| 422 | U84 | 1 | 320231500-183-G | IC,Voltage Sensor,TPS3897ADRYR,G,SON-6,SMD | TEXAS INSTRUMENTS | TPS3897ADRYR | G | PWA BOM | In New BOM |
|  | U84 | 1 | 320231500-183-G | IC,Voltage Sensor,TPS3897ADRYR,G,SON-6,SMD | TEXAS INSTRUMENTS | TPS3897ADRYR |  | PWA BOM | In Old BOM |
| 423 | U87 | 1 | 32020LS00-183-G | IC,Power Controller,TPS3801K33DCKR,G,SC-70-5,SMD | TEXAS INSTRUMENTS | TPS3801K33DCKR | G | PWA BOM | In New BOM |
|  | U87 | 1 | 32020LS00-183-G | IC,Power Controller,TPS3801K33DCKR,G,SC-70-5,SMD | TEXAS INSTRUMENTS | TPS3801K33DCKR | N | PWA BOM | In Old BOM |
| 424 | U92,U93,U94,U95 | 4 | 31050J800-031-G | IC,Buffer,PCA9516APW,2.3V~3.6V,G,TSSOP-16,SMD | NXP SEMICONDUCTORS | PCA9516APW | G | PWA BOM | In New BOM |
|  | U92,U93,U94,U95 | 4 | 31050J800-031-G | IC,Buffer,PCA9516APW,2.3V~3.6V,G,TSSOP-16,SMD | NXP SEMICONDUCTORS | PCA9516APW |  | PWA BOM | In Old BOM |
| 425 | U96,U108 | 2 | 32021R100-252-G | IC,Power Controller,PI3USB102ZLEX,G,TQFN-10P,SMD | PERICOM SEMICONDUCTOR CORP | PI3USB102ZLEX | G | PWA BOM | In New BOM |
|  | U96,U108 | 2 | 32021R100-252-G | IC,Power Controller,PI3USB102ZLEX,G,TQFN-10P,SMD | PERICOM SEMICONDUCTOR CORP | PI3USB102ZLEX |  | PWA BOM | In Old BOM |
| 426 | U97 | 1 | 31090C800-031-G | IC,Transceiver,74AVC4TD245GU,0.8V~3.6V,G,XQFN-16,SMD | NXP SEMICONDUCTORS | 74AVC4TD245GU | G | PWA BOM | In New BOM |
|  | U97 | 1 | 31090C800-031-G | IC,Transceiver,74AVC4TD245GU,0.8V~3.6V,G,XQFN-16,SMD | NXP SEMICONDUCTORS | 74AVC4TD245GU |  | PWA BOM | In Old BOM |
| 427 | U99,U100 | 2 | 210203M00-031-G | IC,NXP,PCA9554PW,G,TSSOP-16,SMD | NXP SEMICONDUCTORS | PCA9554PW | G | PWA BOM | In New BOM |
|  | U99,U100 | 2 | 210203M00-031-G | IC,NXP,PCA9554PW,G,TSSOP-16,SMD | NXP SEMICONDUCTORS | PCA9554PW | N | PWA BOM | In Old BOM |
| 428 | U104,U105,U106,U107 | 4 | 311004800-031-G | IC,Translator,PCA9617ADPJ,0.8~5.5V,2.2~5.5V,G,TSSOP-8,SMD | NXP SEMICONDUCTORS | PCA9617ADPJ | G | PWA BOM | In New BOM |
|  |  |  | 311004V00-223-G | Logic IC,Translator,PCA9617ADMR2G,Vcca=0.8V~5.5V,Vccb=2.2V~5.5V,102ns,Micro8,8P,G | ON SEMICONDUCTOR CORP | PCA9617ADMR2G | G | PWA BOM | In New BOM |
|  | U104,U105,U106,U107 | 4 | 311004800-031-G | IC,Translator,PCA9617ADPJ,0.8~5.5V,2.2~5.5V,G,TSSOP-8,SMD | NXP SEMICONDUCTORS | PCA9617ADPJ |  | PWA BOM | In Old BOM |
|  |  |  | 311004V00-223-G | Logic IC,Translator,PCA9617ADMR2G,Vcca=0.8V~5.5V,Vccb=2.2V~5.5V,102ns,Micro8,8P,G | ON SEMICONDUCTOR CORP | PCA9617ADMR2G | G | PWA BOM | In Old BOM |
| 429 | U109 | 1 | 310307T00-031-G | IC,Switch,74CBTLV1G125GV,2.3~3.6V,G,SOT753-5,SMD | NXP SEMICONDUCTORS | 74CBTLV1G125GV | G | PWA BOM | In New BOM |
|  |  |  | 310300D00-183-G | IC,Switch,SN74CBTLV1G125DBVR,2.3~3.6V,G,SOT23-5,SMD | TEXAS INSTRUMENTS | SN74CBTLV1G125DBVR | G | PWA BOM | In New BOM |
|  | U109 | 1 | 310307T00-031-G | IC,Switch,74CBTLV1G125GV,2.3~3.6V,G,SOT753-5,SMD | NXP SEMICONDUCTORS | 74CBTLV1G125GV |  | PWA BOM | In Old BOM |
|  |  |  | 310300D00-183-G | IC,Switch,SN74CBTLV1G125DBVR,2.3~3.6V,G,SOT23-5,SMD | TEXAS INSTRUMENTS | SN74CBTLV1G125DBVR | G | PWA BOM | In Old BOM |
| 430 | U110 | 1 | 330103N00-426-G | IC,Optocoupler,PS2811-1-F3-A,G,SSOP-4,SMD | RENESAS TECHNOLOGY AMERICA INC | PS2811-1-F3-A | G | PWA BOM | In New BOM |
|  |  |  | 330102900-289-G | OPTO-IC,ISOL,LTV-217-G,SSOP,4P,G | LITE-ON TECHNOLOGY CORPORATION | LTV-217-G | G | PWA BOM | In New BOM |
|  |  |  | VOS618A-3T | OPTO-IC,VOS618A-3T | VISHAY ENTER TECHNO LOGY.INC | VOS618A-3T | G | PWA BOM | In New BOM |
|  | U110 | 1 | 330103N00-426-G | IC,Optocoupler,PS2811-1-F3-A,G,SSOP-4,SMD | RENESAS TECHNOLOGY AMERICA INC | PS2811-1-F3-A |  | PWA BOM | In Old BOM |
|  |  |  | 330102900-289-G | OPTO-IC,ISOL,LTV-217-G,SSOP,4P,G | LITE-ON TECHNOLOGY CORPORATION | LTV-217-G | G | PWA BOM | In Old BOM |
|  |  |  | VOS618A-3T | OPTO-IC,VOS618A-3T | VISHAY ENTER TECHNO LOGY.INC | VOS618A-3T | G | PWA BOM | In Old BOM |
| 431 | U116 | 1 | 21081WR00-031-G | IC,NXP,PCA9541APW/01,G,TSSOP-16,SMD | NXP SEMICONDUCTORS | PCA9541APW/01 | G | PWA BOM | In New BOM |
|  | U116 | 1 | 21081WR00-031-G | IC,NXP,PCA9541APW/01,G,TSSOP-16,SMD | NXP SEMICONDUCTORS | PCA9541APW/01 |  | PWA BOM | In Old BOM |
| 432 | U164 | 1 | 311006F00-031-G | IC,Translator,PCA9508D,0.9V~5.5V/2.7V~5.5V,G,SO-8,SMD | NXP SEMICONDUCTORS | PCA9508D | G | PWA BOM | In New BOM |
|  | U164 | 1 | 311006F00-031-G | IC,Translator,PCA9508D,0.9V~5.5V/2.7V~5.5V,G,SO-8,SMD | NXP SEMICONDUCTORS | PCA9508D |  | PWA BOM | In Old BOM |
| 433 | U165 | 1 | 320242H00-226-G | IC,Power Controller,LTC2955CDDB-2#TRMPBF,G,DFN-10,SMD | LINEAR TECHNOLOGY CORPORATION | LTC2955CDDB-2#TRMPBF | G | PWA BOM | In New BOM |
|  | U165 | 1 | 320242H00-226-G | IC,Power Controller,LTC2955CDDB-2#TRMPBF,G,DFN-10,SMD | LINEAR TECHNOLOGY CORPORATION | LTC2955CDDB-2#TRMPBF |  | PWA BOM | In Old BOM |
| 434 | U166,U172 | 2 | 32050Q900-031-G | IC,LED Driver,PCA9551PW,G,TSSOP-16,SMD | NXP SEMICONDUCTORS | PCA9551PW | G | PWA BOM | In New BOM |
|  | U166,U172 | 2 | 32050Q900-031-G | IC,LED Driver,PCA9551PW,G,TSSOP-16,SMD | NXP SEMICONDUCTORS | PCA9551PW |  | PWA BOM | In Old BOM |
| 435 | U167,U173 | 2 | 310203U00-223-G | IC,Trigger,NL17SZ14DFT2G,1.65~5.5V,G,SOT353-5,SMD | ON SEMICONDUCTOR CORP | NL17SZ14DFT2G | G | PWA BOM | In New BOM |
|  |  |  | 310200900-185-G | IC,Trigger,NC7SZ14P5X,1.65-5.5V,G,SC70-5P,SMD | FAIRCHILD SEMICONDUCTOR CORP | NC7SZ14P5X | G | PWA BOM | In New BOM |
|  |  |  | 310107000-031-G | Logic IC,Gate&Inverter,74LVC1G14GW,1.65V~5.5V,14ns,TSSOP,5P,G | NXP SEMICONDUCTORS | 74LVC1G14GW | G | PWA BOM | In New BOM |
|  | U167,U173 | 2 | 310203U00-223-G | IC,Trigger,NL17SZ14DFT2G,1.65~5.5V,G,SOT353-5,SMD | ON SEMICONDUCTOR CORP | NL17SZ14DFT2G | N | PWA BOM | In Old BOM |
|  |  |  | 310200900-185-G | IC,Trigger,NC7SZ14P5X,1.65-5.5V,G,SC70-5P,SMD | FAIRCHILD SEMICONDUCTOR CORP | NC7SZ14P5X | G | PWA BOM | In Old BOM |
|  |  |  | 310107000-031-G | Logic IC,Gate&Inverter,74LVC1G14GW,1.65V~5.5V,14ns,TSSOP,5P,G | NXP SEMICONDUCTORS | 74LVC1G14GW | G | PWA BOM | In Old BOM |
| 436 | U170,U174,U180 | 3 | 310109D00-031-G | IC,Gate&Inverter,74LVC1G32GW,1.65~5.5V,G,TSSOP-5,SMD | NXP SEMICONDUCTORS | 74LVC1G32GW | G | PWA BOM | In New BOM |
|  |  |  | 310109E00-223-G | IC,Gate&Inverter,NL17SZ32DFT2G,1.65~5.5V,G,SOT-353-5,SMD | ON SEMICONDUCTOR CORP | NL17SZ32DFT2G | G | PWA BOM | In New BOM |
|  |  |  | 310108600-131-G | IC,Gate&Inverter,TC7SZ32FU,1.65~5.5V,G,SSOP-5,SMD | TOSHIBA ELECTRONICS ASIA LTD | TC7SZ32FU | G | PWA BOM | In New BOM |
|  | U170,U174,U180 | 3 | 310109D00-031-G | IC,Gate&Inverter,74LVC1G32GW,1.65~5.5V,G,TSSOP-5,SMD | NXP SEMICONDUCTORS | 74LVC1G32GW | N | PWA BOM | In Old BOM |
|  |  |  | 310109E00-223-G | IC,Gate&Inverter,NL17SZ32DFT2G,1.65~5.5V,G,SOT-353-5,SMD | ON SEMICONDUCTOR CORP | NL17SZ32DFT2G | G | PWA BOM | In Old BOM |
|  |  |  | 310108600-131-G | IC,Gate&Inverter,TC7SZ32FU,1.65~5.5V,G,SSOP-5,SMD | TOSHIBA ELECTRONICS ASIA LTD | TC7SZ32FU | G | PWA BOM | In Old BOM |
| 437 | U171 | 1 | 31050KL00-031-G | IC,Buffer,74HC75PW,2.0V~6.0V,G,TSSOP-16,SMD | NXP SEMICONDUCTORS | 74HC75PW | G | PWA BOM | In New BOM |
|  |  |  | CD74HC75PWRG4 | IC,Buffer,CD74HC75PWRG4 | Texas Instruments | CD74HC75PWRG4 | G | PWA BOM | In New BOM |
|  | U171 | 1 | 31050KL00-031-G | IC,Buffer,74HC75PW,2.0V~6.0V,G,TSSOP-16,SMD | NXP SEMICONDUCTORS | 74HC75PW |  | PWA BOM | In Old BOM |
|  |  |  | CD74HC75PWRG4 | IC,Buffer,CD74HC75PWRG4 | Texas Instruments | CD74HC75PWRG4 | G | PWA BOM | In Old BOM |
| 438 | U175 | 1 | 31010SB00-183-G | Logic IC,Gate,ISO1540DR,3V~5.5V,G,SOIC-8,SMD | TEXAS INSTRUMENTS | ISO1540DR | G | PWA BOM | In New BOM |
|  | U175 | 1 | 31010SB00-183-G | Logic IC,Gate,ISO1540DR,3V~5.5V,G,SOIC-8,SMD | TEXAS INSTRUMENTS | ISO1540DR |  | PWA BOM | In Old BOM |
| 439 | X4 | 1 | 71012EC00-162-G | XTAL,6MHz,+/-30ppm,20pF,G,SMD | EPSON ELECTRONICS AMERICA,INC. | Q22MA4061164200 | G | PWA BOM | In New BOM |
|  | X4 | 1 | 71012EC00-162-G | XTAL,6MHz,+/-30ppm,20pF,G,SMD | EPSON ELECTRONICS AMERICA,INC. | Q22MA4061164200 |  | PWA BOM | In Old BOM |
| 440 | Y3 | 1 | 710213J00-16G-G | OSC,25MHz,+/-1.5ppm,3.3V,15pF,G,SMD | SiTime Corporation | SIT5000AC-3B-33N0-25.000000T | G | PWA BOM | In New BOM |
|  | Y3 | 1 | 710213J00-16G-G | OSC,25MHz,+/-1.5ppm,3.3V,15pF,G,SMD | SiTime Corporation | SIT5000AC-3B-33N0-25.000000T |  | PWA BOM | In Old BOM |
| 441 | B1 | 1 | 340660600-GRS-G | CONN,Header,Battery Holder,Bla,21.3mm,G/F,G,SMD-2 | LOTES CO LTD | AAA-BAT-063-P02_A | G | PWA BOM | In New BOM |
|  | B1 | 1 | 340660600-GRS-G | CONN,Header,Battery Holder,Bla,21.3mm,G/F,G,SMD-2 | LOTES CO LTD | AAA-BAT-063-P02_A |  | PWA BOM | In Old BOM |
| 442 | CLIP1,CLIP2,CLIP3,CLIP4 | 4 | 2T714BY00-086-G | Fuse Clips,10.67mm*7.11mm*7.87mm,G,LITTELFUSE,01220088Z | LITTELFUSE FAR EAST PTE LTD | 01220088Z | G | PWA BOM | In New BOM |
|  | CLIP1,CLIP2,CLIP3,CLIP4 | 4 | 2T714BY00-086-G | Fuse Clips,10.67mm*7.11mm*7.87mm,G,LITTELFUSE,01220088Z | LITTELFUSE FAR EAST PTE LTD | 01220088Z |  | PWA BOM | In Old BOM |
| 443 | JP1(2-3),JP4(2-3),JP5(2-3),JP6(1-2) | 4 | 340612R00-309-G | CONN,Jumper,Bla,2.54mm,G,DIP-2 | SAMTEC INC. | SNT-100-BK-G | G | PWA BOM | In New BOM |
|  |  |  | 34065L900-GRT-G | CONN,jumper,Bla,2.54mm,30u,G,DIP-2 | PINREX TECHNOLOGY CORP. | 201-71-01DB00 | G | PWA BOM | In New BOM |
|  |  |  | 34066N500-600-G | Header&Socket Connector,SJ0520F-A0,Jumper,2,DIP,PBT,2.54mm,3u",Black,G | FOXCONN TECHNOLOGY CO.,LTD. | SJ0520F-A0 | G | PWA BOM | In New BOM |
|  | JP1(2-3),JP4(2-3),JP5(2-3),JP6(1-2) | 4 | 340612R00-309-G | CONN,Jumper,Bla,2.54mm,G,DIP-2 | SAMTEC INC. | SNT-100-BK-G |  | PWA BOM | In Old BOM |
|  |  |  | 34065L900-GRT-G | CONN,jumper,Bla,2.54mm,30u,G,DIP-2 | PINREX TECHNOLOGY CORP. | 201-71-01DB00 | G | PWA BOM | In Old BOM |
|  |  |  | 34066N500-600-G | Header&Socket Connector,SJ0520F-A0,Jumper,2,DIP,PBT,2.54mm,3u",Black,G | FOXCONN TECHNOLOGY CO.,LTD. | SJ0520F-A0 | G | PWA BOM | In Old BOM |
| 444 | J2,J6 | 2 | 340692800-309-G | CONN,Header,Socket,2X30,V/T,Bla,0.5mm,G/F,G,SMD-60 | SAMTEC INC. | QSH-030-01-F-D-A-K-TR | G | PWA BOM | In New BOM |
|  | J2,J6 | 2 | 340692800-309-G | CONN,Header,Socket,2X30,V/T,Bla,0.5mm,G/F,G,SMD-60 | SAMTEC INC. | QSH-030-01-F-D-A-K-TR |  | PWA BOM | In Old BOM |
| 445 | J8 | 1 | 340459T00-GRS-G | CONN,I/O,HDMI,V/T,Bla,0.5mm,1u,G,SMD-19 | LOTES CO LTD | AHDM0001-P004A | G | PWA BOM | In New BOM |
|  | J8 | 1 | 340459T00-GRS-G | CONN,I/O,HDMI,V/T,Bla,0.5mm,1u,G,SMD-19 | LOTES CO LTD | AHDM0001-P004A |  | PWA BOM | In Old BOM |
| 446 | J9 | 1 | 3406A2A00-309-G | CONN,Header,Shrouded,2X4,V/T,1.27mm,15u,G,SMD-8 | SAMTEC INC. | TFM-104-02-L-D-K-TR | G | PWA BOM | In New BOM |
|  | J9 | 1 | 3406A2A00-309-G | CONN,Header,Shrouded,2X4,V/T,1.27mm,15u,G,SMD-8 | SAMTEC INC. | TFM-104-02-L-D-K-TR |  | PWA BOM | In Old BOM |
| 447 | J10 | 1 | 3406B5J00-317-G | CONN,Header,Socket,V/T,Bla,2mm,15u,G,DIP-18 | MOLEX INCORPORATED | 79107-7008 | G | PWA BOM | In New BOM |
|  | J10 | 1 | 3406B5J00-317-G | CONN,Header,Socket,V/T,Bla,2mm,15u,G,DIP-18 | MOLEX INCORPORATED | 79107-7008 |  | PWA BOM | In Old BOM |
| 448 | J11 | 1 | 3406AEU00-245-G | CONN,Header,Shrouded,2X4,R/A,Bla,2.54mm,G/F,G,DIP-8 | AMPHENOL SHANGHAI CORP. | G821EU208AGN00Y | G | PWA BOM | In New BOM |
|  |  |  | 3406AYC00-GRT-G | Header&Socket Connector,511-90-08GB00,Shrouded Header,8,DIP,NY9T,2.54mm,3u",Black,G | PINREX TECHNOLOGY CORP. | 511-90-08GB00 | G | PWA BOM | In New BOM |
|  |  |  | 3406AYD00-971-G | Header&Socket Connector,C18359-10839-Y,Shrouded Header,8,DIP,LCP,2.54mm,999.9999u",Black,G | ALLTOP TECHNOLOGY CO.,LTD | C18359-10839-Y | G | PWA BOM | In New BOM |
|  |  |  | 3406AYE00-637-G | Header&Socket Connector,3112110800-0231,Shrouded Header,8,DIP,NY6T,2.54mm,3u",Black,G | LONG SHOUNG CO.,LTD. | 3112110800-0231 | G | PWA BOM | In New BOM |
|  | J11 | 1 | 3406AEU00-245-G | CONN,Header,Shrouded,2X4,R/A,Bla,2.54mm,G/F,G,DIP-8 | AMPHENOL SHANGHAI CORP. | G821EU208AGN00Y |  | PWA BOM | In Old BOM |
|  |  |  | 3406AYC00-GRT-G | Header&Socket Connector,511-90-08GB00,Shrouded Header,8,DIP,NY9T,2.54mm,3u",Black,G | PINREX TECHNOLOGY CORP. | 511-90-08GB00 | G | PWA BOM | In Old BOM |
|  |  |  | 3406AYD00-971-G | Header&Socket Connector,C18359-10839-Y,Shrouded Header,8,DIP,LCP,2.54mm,999.9999u",Black,G | ALLTOP TECHNOLOGY CO.,LTD | C18359-10839-Y | G | PWA BOM | In Old BOM |
|  |  |  | 3406AYE00-637-G | Header&Socket Connector,3112110800-0231,Shrouded Header,8,DIP,NY6T,2.54mm,3u",Black,G | LONG SHOUNG CO.,LTD. | 3112110800-0231 | G | PWA BOM | In Old BOM |
| 449 | J12 | 1 | 3406AGV00-317-G | CONN,Header,WTB,2X8,V/T,Whi,1.25mm,G,SMD-16 | MOLEX INCORPORATED | 5054331671 | G | PWA BOM | In New BOM |
|  | J12 | 1 | 3406AGV00-317-G | CONN,Header,WTB,2X8,V/T,Whi,1.25mm,G,SMD-16 | MOLEX INCORPORATED | 5054331671 |  | PWA BOM | In Old BOM |
| 450 | J13 | 1 | 34064J800-317-G | CONN,Header,Socket,2X2,V/T,Bla,2mm,15u,G,DIP-4 | MOLEX INCORPORATED | 79107-7001 | G | PWA BOM | In New BOM |
|  | J13 | 1 | 34064J800-317-G | CONN,Header,Socket,2X2,V/T,Bla,2mm,15u,G,DIP-4 | MOLEX INCORPORATED | 79107-7001 |  | PWA BOM | In Old BOM |
| 451 | J14 | 1 | 34071AW00-245-G | CONN,SATA,V/T,Bla,1.27mm,15u,G,DIP-22 | AMPHENOL SHANGHAI CORP. | G16CE41210W3EU | G | PWA BOM | In New BOM |
|  | J14 | 1 | 34071AW00-245-G | CONN,SATA,V/T,Bla,1.27mm,15u,G,DIP-22 | AMPHENOL SHANGHAI CORP. | G16CE41210W3EU |  | PWA BOM | In Old BOM |
| 452 | J16 | 1 | 34131WS00-G78-G | CONN,BTB,Bla,0.8mm,7.87u,G,SMD-120 | FCI CONNECTORS HONGKONG LTD. | 10139781-122402LF | G | PWA BOM | In New BOM |
|  | J16 | 1 | 34131WS00-G78-G | CONN,BTB,Bla,0.8mm,7.87u,G,SMD-120 | FCI CONNECTORS HONGKONG LTD. | 10139781-122402LF |  | PWA BOM | In Old BOM |
| 453 | J17,J18 | 2 | 34131WT00-G78-G | CONN,BTB,Bla,0.8mm,7.87u,G,SMD-80 | FCI CONNECTORS HONGKONG LTD. | 10139781-082402LF | G | PWA BOM | In New BOM |
|  | J17,J18 | 2 | 34131WT00-G78-G | CONN,BTB,Bla,0.8mm,7.87u,G,SMD-80 | FCI CONNECTORS HONGKONG LTD. | 10139781-082402LF |  | PWA BOM | In Old BOM |
| 454 | J27 | 1 | 3406AMV00-317-G | CONN,Header,MINFIT,2X4,V/T,Bla,10mm,30u,G,DIP-8 | MOLEX INCORPORATED | 42819-4233 | G | PWA BOM | In New BOM |
|  |  |  | 3406AYH00-971-G | Header&Socket Connector,C23709-10433-Y,Power Connector,4,DIP,LCP,10mm,30u",Black,G | ALLTOP TECHNOLOGY CO.,LTD | C23709-10433-Y | G | PWA BOM | In New BOM |
|  | J27 | 1 | 3406AMV00-317-G | CONN,Header,MINFIT,2X4,V/T,Bla,10mm,30u,G,DIP-8 | MOLEX INCORPORATED | 42819-4233 |  | PWA BOM | In Old BOM |
|  |  |  | 3406AYH00-971-G | Header&Socket Connector,C23709-10433-Y,Power Connector,4,DIP,LCP,10mm,30u",Black,G | ALLTOP TECHNOLOGY CO.,LTD | C23709-10433-Y | G | PWA BOM | In Old BOM |
| 455 | J28,J31 | 2 | 34071BR00-245-G | CONN,SAS,V/T,0.6mm,30u,G,SMD-74 | AMPHENOL SHANGHAI CORP. | U10-K074-260T | G | PWA BOM | In New BOM |
|  | J28,J31 | 2 | 34071BR00-245-G | CONN,SAS,V/T,0.6mm,30u,G,SMD-74 | AMPHENOL SHANGHAI CORP. | U10-K074-260T |  | PWA BOM | In Old BOM |
| 456 | J30,J33 | 2 | 34071BS00-245-G | CONN,SAS,V/T,0.6mm,30u,G,SMD-74 | AMPHENOL SHANGHAI CORP. | U10-K074-26BT | G | PWA BOM | In New BOM |
|  | J30,J33 | 2 | 34071BS00-245-G | CONN,SAS,V/T,0.6mm,30u,G,SMD-74 | AMPHENOL SHANGHAI CORP. | U10-K074-26BT |  | PWA BOM | In Old BOM |
| 457 | J34 | 1 | 3406A9H00-309-G | CONN,Header,Socket,V/T,Bla,2.54mm,30u,G,SMD-12 | SAMTEC INC. | SSM-106-S-DV-P-TR | G | PWA BOM | In New BOM |
|  | J34 | 1 | 3406A9H00-309-G | CONN,Header,Socket,V/T,Bla,2.54mm,30u,G,SMD-12 | SAMTEC INC. | SSM-106-S-DV-P-TR |  | PWA BOM | In Old BOM |
| 458 | J99 | 1 | 34051FE00-GRS-G | CONN,Modular Jack,USBX2_RJ45,R/A,Bla/Blu,2mm,30u,G,DIP-23 | LOTES CO LTD | AUSBS002-K001C05 | G | PWA BOM | In New BOM |
|  | J99 | 1 | 34051FE00-GRS-G | CONN,Modular Jack,USBX2_RJ45,R/A,Bla/Blu,2mm,30u,G,DIP-23 | LOTES CO LTD | AUSBS002-K001C05 |  | PWA BOM | In Old BOM |
| 459 | J100 | 1 | 3406ARP00-317-G | CONN,Header,Power,2X8,V/T,Whi,4.2mm,G,DIP-16 | MOLEX INCORPORATED | 46015-1602 | G | PWA BOM | In New BOM |
|  | J100 | 1 | 3406ARP00-317-G | CONN,Header,Power,2X8,V/T,Whi,4.2mm,G,DIP-16 | MOLEX INCORPORATED | 46015-1602 |  | PWA BOM | In Old BOM |
| 460 | J102 | 1 | 340653G00-317-G | CONN,Header,Shrouded,2X11,V/T,Bla,2mm,30u,G,SMD-22 | MOLEX INCORPORATED | 87832-6023 | G | PWA BOM | In New BOM |
|  | J102 | 1 | 340653G00-317-G | CONN,Header,Shrouded,2X11,V/T,Bla,2mm,30u,G,SMD-22 | MOLEX INCORPORATED | 87832-6023 |  | PWA BOM | In Old BOM |
| 461 | J103 | 1 | 3406ALY00-317-G | CONN,Header,Shrouded,2X6,V/T,Bla,2mm,30u,G,SMD-12 | MOLEX INCORPORATED | 87832-5523 | G | PWA BOM | In New BOM |
|  | J103 | 1 | 3406ALY00-317-G | CONN,Header,Shrouded,2X6,V/T,Bla,2mm,30u,G,SMD-12 | MOLEX INCORPORATED | 87832-5523 |  | PWA BOM | In Old BOM |
| 462 | J148 | 1 | 340672300-317-G | CONN,Pin Header,1X4,V/T,Bla,2.54mm,30u,G,SMD-4 | MOLEX INCORPORATED | 87898-0455 | G | PWA BOM | In New BOM |
|  |  |  | 34068VT00-GRT-G | CONN,Header,Pin Header,1X4,V/T,Bla,2.54mm,30u,G,SMD-4 | PINREX TECHNOLOGY CORP. | 212-91-04SBEJ | G | PWA BOM | In New BOM |
|  |  |  | 340692T00-245-G | CONN,Header,Pin Header,1X4,V/T,Bla,2.54mm,30u,G,SMD-4 | AMPHENOL SHANGHAI CORP. | G800MR304010HR | G | PWA BOM | In New BOM |
|  | J148 | 1 | 340672300-317-G | CONN,Pin Header,1X4,V/T,Bla,2.54mm,30u,G,SMD-4 | MOLEX INCORPORATED | 87898-0455 |  | PWA BOM | In Old BOM |
|  |  |  | 34068VT00-GRT-G | CONN,Header,Pin Header,1X4,V/T,Bla,2.54mm,30u,G,SMD-4 | PINREX TECHNOLOGY CORP. | 212-91-04SBEJ | G | PWA BOM | In Old BOM |
|  |  |  | 340692T00-245-G | CONN,Header,Pin Header,1X4,V/T,Bla,2.54mm,30u,G,SMD-4 | AMPHENOL SHANGHAI CORP. | G800MR304010HR | G | PWA BOM | In Old BOM |
| 463 | PBMJ1,PBEJ1,PBAJ1,PAMJ1,PAEJ1,PAAJ1 | 6 | 340634U00-600-G | CONN,Pin Header,2X3,V/T,Bla,2.54mm,30u,G,SMD-6 | FOXCONN TECHNOLOGY CO.,LTD. | HS1103H-RN | G | PWA BOM | In New BOM |
|  |  |  | 34065EA00-317-G | CONN,Header,Pin Header,2X3,V/T,Bla,2.54mm,30u,G,SMD-6 | MOLEX INCORPORATED | 015-91-3060 | G | PWA BOM | In New BOM |
|  |  |  | 3406AY700-637-G | Header&Socket Connector,11006A5807,Pin Header,6,SMD,NY6T,2.54mm,30u",Black,G | LONG SHOUNG CO.,LTD. | 11006A5807 | G | PWA BOM | In New BOM |
|  |  |  | 34068GJ00-GRT-G | CONN,Header,Pin Header,2X3,V/T,Bla,2.54mm,30u,SMD-6 | PINREX TECHNOLOGY CORP. | 212-92-03SBEL | G | PWA BOM | In New BOM |
|  | PBMJ1,PBEJ1,PBAJ1,PAMJ1,PAEJ1,PAAJ1 | 6 | 340634U00-600-G | CONN,Pin Header,2X3,V/T,Bla,2.54mm,30u,G,SMD-6 | FOXCONN TECHNOLOGY CO.,LTD. | HS1103H-RN |  | PWA BOM | In Old BOM |
|  |  |  | 34065EA00-317-G | CONN,Header,Pin Header,2X3,V/T,Bla,2.54mm,30u,G,SMD-6 | MOLEX INCORPORATED | 015-91-3060 | G | PWA BOM | In Old BOM |
|  |  |  | 3406AY700-637-G | Header&Socket Connector,11006A5807,Pin Header,6,SMD,NY6T,2.54mm,30u",Black,G | LONG SHOUNG CO.,LTD. | 11006A5807 | G | PWA BOM | In Old BOM |
|  |  |  | 34068GJ00-GRT-G | CONN,Header,Pin Header,2X3,V/T,Bla,2.54mm,30u,SMD-6 | PINREX TECHNOLOGY CORP. | 212-92-03SBEL | G | PWA BOM | In Old BOM |
| 464 | PBAU3,PAAU3 | 2 | PI3753-00-LGIZ | IC,Regulator,PI3753-00,ADJ,4A,G,LGA-71,SMD | Vicor Corporation | PI3753-00-LGIZ | G | PWA BOM | In New BOM |
|  | PBAU3,PAAU3 | 2 | PI3753-00-LGIZ | IC,Regulator,PI3753-00,ADJ,4A,G,LGA-71,SMD | Vicor Corporation | PI3753-00-LGIZ |  | PWA BOM | In Old BOM |
| 465 | PBMR34,PAMR34 | 2 | RN731ETTP3160B25 | RES,316 Ohm,+/-0.1%,1/16W,G,SMD0402 | KOA SPEER ELECTRONICS, INC. | RN731ETTP3160B25 | G | PWA BOM | In New BOM |
|  | PBMR34,PAMR34 | 2 | 61100RF00-017-G | RES,402 Ohm,+/-0.1%,1/16W,G,SMD0402 | KOA SPEER ELECTRONICS, INC. | RN731ETTP4020B25 | N | PWA BOM | In Old BOM |
| 466 | PSUSW1 | 1 | 34080F500-653-G | CONN,Switch,slide,25mA,24V,G,SMD-8 | DIPTRONICS MANUFACTURING INC. | DHN-04F-T-V-T/R | G | PWA BOM | In New BOM |
|  | PSUSW1 | 1 | 34080F500-653-G | CONN,Switch,slide,25mA,24V,G,SMD-8 | DIPTRONICS MANUFACTURING INC. | DHN-04F-T-V-T/R |  | PWA BOM | In Old BOM |
| 467 | SW1,SW2 | 2 | 340805A00-638-G | CONN,Switch,tact,50mA,12V,G,SMD-2 | E-SWITCH | TL1015AF160QG | G | PWA BOM | In New BOM |
|  |  |  | 340812T00-653-G | CONN,Switch,tact,50mA,12V,Bla,G,SMD-2 | DIPTRONICS MANUFACTURING INC. | MPTLP2-V-T/R | G | PWA BOM | In New BOM |
|  | SW1,SW2 | 2 | 340805A00-638-G | CONN,Switch,tact,50mA,12V,G,SMD-2 | E-SWITCH | TL1015AF160QG |  | PWA BOM | In Old BOM |
|  |  |  | 340812T00-653-G | CONN,Switch,tact,50mA,12V,Bla,G,SMD-2 | DIPTRONICS MANUFACTURING INC. | MPTLP2-V-T/R | G | PWA BOM | In Old BOM |
| 468 | SW3,SW4 | 2 | 34081GH00-653-G | CONN,Switch,tact,Brown,50mA,12V,G,DIP-4 | DIPTRONICS MANUFACTURING INC. | DTSA-644N-Q | G | PWA BOM | In New BOM |
|  | SW3,SW4 | 2 | 34081GH00-653-G | CONN,Switch,tact,Brown,50mA,12V,G,DIP-4 | DIPTRONICS MANUFACTURING INC. | DTSA-644N-Q |  | PWA BOM | In Old BOM |
| 469 | U1,U10 | 2 | 340108S00-600-G | POWER9 CPU Socket for LGA3899-HYBRID | FOXCONN TECHNOLOGY CO.,LTD. | PE38993-51BC0-1H | G | PWA BOM | In New BOM |
|  | U1,U10 | 2 | 340108S00-600-G | POWER9 CPU Socket for LGA3899-HYBRID | FOXCONN TECHNOLOGY CO.,LTD. | PE38993-51BC0-1H |  | PWA BOM | In Old BOM |
| 470 | U22,U23 | 2 | 34061E400-GRS-G | CONN,Socket,SPI Flash,V/T,Bla,1.27mm,G/F,G,SMD-16 | LOTES CO LTD | ACA-SPI-006-F01 | G | PWA BOM | In New BOM |
|  | U22,U23 | 2 | 34061E400-GRS-G | CONN,Socket,SPI Flash,V/T,Bla,1.27mm,G/F,G,SMD-16 | LOTES CO LTD | ACA-SPI-006-F01 | Y | PWA BOM | In Old BOM |
| ##### Change Revision |  |  |  |  |  |  |  |  |  |
| Sheet | REV OF BOM | CUSTOMER | CUSTOMER P/N | PWA PN | PWA DESCRIPTION | PWA REV | DATE | Remark |  |
| OOOOOOOOOOOOOOOOOOOOOOOOOOOOOOOOOOOOOOOOOOOOOOOOOOOOOOOOOOOOOOOOOOOOOOOOOOOOOOOOOOOOOOOOOO | OOOOOOOOOOOOOOOOOOOOOOOOOOOOOOOOOOOOOOOOOOOOOOOOOOOOOOOOOOOOOOOOOOOOOOOOOOOOOOOOOOOOOOOOOO | OOOOOOOOOOOOOOOOOOOOOOOOOOOOOOOOOOOOOOOOOOOOOOOOOOOOOOOOOOOOOOOOOOOOOOOOOOOOOOOOOOOOOOOOOO | OOOOOOOOOOOOOOOOOOOOOOOOOOOOOOOOOOOOOOOOOOOOOOOOOOOOOOOOOOOOOOOOOOOOOOOOOOOOOOOOOOOOOOOOOO | OOOOOOOOOOOOOOOOOOOOOOOOOOOOOOOOOOOOOOOOOOOOOOOOOOOOOOOOOOOOOOOOOOOOOOOOOOOOOOOOOOOOOOOOOO | OOOOOOOOOOOOOOOOOOOOOOOOOOOOOOOOOOOOOOOOOOOOOOOOOOOOOOOOOOOOOOOOOOOOOOOOOOOOOOOOOOOOOOOOOO | OOOOOOOOOOOOOOOOOOOOOOOOOOOOOOOOOOOOOOOOOOOOOOOOOOOOOOOOOOOOOOOOOOOOOOOOOOOOOOOOOOOOOOOOOO | OOOOOOOOOOOOOOOOOOOOOOOOOOOOOOOOOOOOOOOOOOOOOOOOOOOOOOOOOOOOOOOOOOOOOOOOOOOOOOOOOOOOOOOOOO | OOOOOOOOOOOOOOOOOOOOOOOOOOOOOOOOOOOOOOOOOOOOOOOOOOOOOOOOOOOOOOOOOOOOOOOOOOOOOOOOOOOOOOOOOO | OOOOOOOOOOOOOOOOOOOOOOOOOOOOOOOOOOOOOOOOOOOOOOOOOOOOOOOOOOOOOOOOOOOOOOOOOOOOOOOOOOOOOOOOOO |
| Second Source Change |  |  |  |  |  |  |  |  |  |
| Item | Location | Change Type | Foxconn P/N | Part Description | Manufacturer Full Name | Manufacturer P/N | RoHS | Sheet |  |
| 1 | PCB |  | 0101EW800-000-G | PCB,Zaius-MB DVT-X03,OSP,Blu,22L,22.20*13.00,G | GOLD CIRCUIT ELECTRONICS LTD. | 0101EW800-000-G | G | PWA BOM |  |
|  |  | ADD | 0101EW800-000-G | PCB,Zaius-MB DVT-X03,OSP,Blu,22L,22.20*13.00,G | ZHUHAI FOUNDER PRINTED CIRCUIT BOARD（HK） DEVELOPMENT LIMITED | 0101EW800-000-G | G | PWA BOM |  |
| 2 | LED11,LED12 |  | 52113AW00-289-G | LED,Green,LTL-42NGY8DH184P,5V,20mA,G,DIP-2 | LITE-ON TECHNOLOGY CORPORATION | LTL-42NGY8DH184P | G | PWA BOM |  |
|  |  | ADD | SSF-LXH303GD | LED,Green,SSF-LXH303GD,5V,20mA,G,DIP-2 | LUEMX INC,TAIWAN BRANCH | SSF-LXH303GD | G | PWA BOM |  |
|  |  | Delete | SSF-LXH303SUGD | LED,Green,LTL-42NGY8DH184P,5V,20mA,G,DIP-2 | Lumex | SSF-LXH303SUGD | G | PWA BOM |  |
| 3 | LED13 |  | 52113B100-289-G | LED,Blue,LTL42TB6NH184P,5V,30mA,G,DIP-2 | LITE-ON TECHNOLOGY CORPORATION | LTL42TB6NH184P | G | PWA BOM |  |
|  |  | NO | L-7104ADFX010-TW | LED,Blue,LTL42TB6NH184P,5V,30mA,G,DIP-2 | Kingbright | L-7104ADFX010-TW | G | PWA BOM |  |
|  |  | Delete | 52113GJ00-354-G | LED LAMP,LA140B-1/DBK-1-PF,Blue,700mcd@IF=20mA,470nm,5V,30mA,N/A,,DIP,2P,G | Ligitek Electronics Co., Ltd. | LA140B-1/DBK-1-PF | G | PWA BOM |  |
|  |  | Delete | SSF-LXH303USBC | LED,SSF-LXH303USBC | LUMEX | SSF-LXH303USBC | G | PWA BOM |  |
| 4 | L17 |  | 720106E00-015-G | FB,330 Ohm@100MHz,+/-25%,500mA,300mOhm,G,SMD0603 | MURATA ELEC. NORTH AMERICA | BLM18EG331TN1D | G | PWA BOM |  |
|  |  | NO | 72010YW01-129-G | FB,Multilayer,100mOhm,330Ohm@100MHz,+/-25%,2A,,SMD0603,G | MAG.LAYERS, SCIENTIFIC-TECHNICS (KUNSHAN) CO., LTD. | GMLB-160808-0330P-N8 | G | PWA BOM |  |
|  |  | Delete | 72010B000-016-G | FB,Multilayer,300mOhm,300Ohm@100MHz,+/-25%,500mA,,SMD0603,G | TDK | MMZ1608S301AT | G | PWA BOM |  |
| 5 | L22,L23,L24,L25 |  | 720105P00-016-G | FB,80 Ohm@100MHz,+/-25%,500mA,150mOhm,G,SMD0603 | TDK ELECTRONICS EUROPE GMBH | MMZ1608S800AT | G | PWA BOM |  |
|  |  | ADD | 72010WQ00-129-G | FB,80 Ohm@100MHz,+/-25%,3A,0.04Ohm,G,SMD0603 | MAG.LAYERS, SCIENTIFIC-TECHNICS (KUNSHAN) CO., LTD. | GMLB-160808-0080P-N8 | G | PWA BOM |  |
|  |  | Delete | GMLB-160808-0080P-N8 | FB,80 Ohm@100MHz,+/-25%,500mA,150mOhm,G,SMD0603 | MAG.LAYERS, SCIENTIFIC-TECHNICS (KUNSHAN) CO., LTD. | GMLB-160808-0080P-N8 | G | PWA BOM |  |
| 6 | PBMD1,PBFD1,PBED1,PBAD1,PAMD1,PAFD1,PAED1,PAAD1 |  | 520103B00-185-G | Diode,Rectifier&Switching,MMBD1205,100V,200mA,G,SOT-23-3,SMD | FAIRCHILD SEMICONDUCTOR CORP | MMBD1205 | G | PWA BOM |  |
|  |  | ADD | MMBD3004A | Diode,Rectifier&Switching,100V,200mA,G,SOT-23-3,SMD | DIODES INCORPORATION | MMBD3004A |  | PWA BOM |  |
|  |  | Delete | BAW156HM | Diode,Rectifier&Switching,100V,200mA,G,SOT-23-3,SMD | ROHM | BAW156HM |  | PWA BOM |  |
|  |  | Delete | 52010AP00-280-G | Diode,Rectifier&Switching,MMBD3004A,240V,225mA,SOT-23,3P,G | DIODES INC | MMBD3004A |  | PWA BOM |  |
| 7 | PSUFS1,PBAFS1,PAAFS1,PSUFS2 |  | 730100M00-086-G | Fuse,Very fast acting,125V,10A,G,SMD | LITTELFUSE FAR EAST PTE LTD | 0451010.MRL | G | PWA BOM |  |
|  |  | ADD | CB61F10A-TR2 | Fuse,CB61F10A-TR2 | COOPER BUSSMANN, INC. | CB61F10A-TR2 | 2 | PWA BOM |  |
| 8 | PBMQ1,PBFQ1,PBEQ1,PBAQ1,PAMQ1,PAFQ1,PAEQ1,PAAQ1,PBMQ2,PBFQ2,PBEQ2,PBAQ2,PAMQ2,PAFQ2,PAEQ2,PAAQ2 |  | 510201900-185-G | TRANS P,MMBT3906,40V,0.2A,G,SOT23-3,SMD | FAIRCHILD SEMICONDUCTOR CORP | MMBT3906 | G | PWA BOM |  |
|  |  | NO | 510201900-031-G | TRANS P,MMBT3906,40V,0.2A,G,SOT23-3,SMD | NXP SEMICONDUCTORS | MMBT3906 | G | PWA BOM |  |
|  |  | NO | 510200600-237-G | TRANS P,MMBT3906-7-F,40V,0.2A,G,SOT23-3,SMD | DIODES INCORPORATION | MMBT3906-7-F | G | PWA BOM |  |
|  |  | Delete | 510200E00-223-G | TRANS P,MMBT3906LT1G,40V,0.2A,G,SOT23-3,SMD | ON SEMICONDUCTOR CORP | MMBT3906LT1G | G | PWA BOM |  |
| 9 | PALL2,PBLL4 |  | 630351600-034-G | IND,470nH@100KHz,+/-20%,30A,1.68mOhm,SHLD,G,SMD | CYNTEC CO. LTD | PCMB104T-R47MS | G | PWA BOM |  |
|  |  | NO | 63035YA00-051-G | Coil Ind,Shielded(SHLD),470nH@100KHz,+/-20%,28A,1.5mOhm,SMD,11.5*10.3*4.0,,,G | PULSE ELECTRONICS (SINGAPORE) | PA4342.471NLT | G | PWA BOM |  |
|  |  | ADD | 63035Y900-129-G | IND,470nH@100KHz,+/-20%,30A,1.68mOhm,SHLD,G,SMD | MAG.LAYERS, SCIENTIFIC-TECHNICS (KUNSHAN) CO., LTD. | SPS-10DZ-R47M-X2 | G | PWA BOM |  |
|  |  | Delete | SPS-10DZ-R47M-X2 | Coil Ind,SPS-10DZ-R47M-X2 | MAG.LAYERS, SCIENTIFIC-TECHNICS (KUNSHAN) CO., LTD. | SPS-10DZ-R47M-X2 | G | PWA BOM |  |
| 10 | PCIE1,PCIE5 |  | 10061913-102HLF | CONN,PCIE-8X,V/T,Bla,1mm,30u,G,SMD-98 | FCI CONNECTORS HONGKONG LTD. | 10061913-102HLF | G | PWA BOM |  |
|  |  | ADD | 2041366-4 | CONN,PCIE-8X,V/T,Bla,1mm,30u,G,SMD-98 | TYCO ELECTRONICS CORPORATION | 2041366-4 | G | PWA BOM |  |
| 11 | PCIE2,PCIE3,PCIE4 |  | 10061913-103HLF | CONN,PCIE-16X,V/T,Bla,1mm,30u,G,SMD-164 | FCI CONNECTORS HONGKONG LTD. | 10061913-103HLF | G | PWA BOM |  |
|  |  | ADD | 2041366-6 | CONN,PCIE-16X,V/T,Bla,1mm,30u,G,SMD-164 | TYCO ELECTRONICS CORPORATION | 2041366-6 | G | PWA BOM |  |
| 12 | PUAL1,PSAL1,PRAL1,PQAL1,PPAL1,PIAL1,PFAL1,PEAL1 |  | 630335M00-088-G | IND,820nH@100KHz,+/-20%,13A,8mOhm,SHLD,G,SMD | COOPER BUSSMANN, INC. | HCM0703-R82-R | G | PWA BOM |  |
|  |  | NO | 63035Y800-051-G | Coil Ind,Shielded(SHLD),820nH@100KHz,+/-20%,13A,8mOhm,SMD,7.6*6.9*3.0,,,G | PULSE ELECTRONICS (SINGAPORE) | PA4341.821NLT | G | PWA BOM |  |
|  |  | ADD | 63032RP05-129-G | IND,820nH@100KHz,+/-20%,13A,8mOhm,SHLD,G,SMD | MAG.LAYERS, SCIENTIFIC-TECHNICS (KUNSHAN) CO., LTD. | SPS-06CZ-R82M-V1 | G | PWA BOM |  |
|  |  | Delete | SPS-06CZ-R82M-V1 | Ind,SPS-06CZ-R82M-V1 | MAG.LAYERS, SCIENTIFIC-TECHNICS (KUNSHAN) CO., LTD. | SPS-06CZ-R82M-V1 | G | PWA BOM |  |
| 13 | PSTC4,PSLC4,PSFC4,PSEC4,PSDC4,PQPC4,PFRC4,PEEC4,PEDC4,PSPC3003,PIPC3003,PFPC3003,PEPC3003,PSRC3010 |  | 62012T300-015-G | CAP,1uF,+/-10%,X7S,25V,G,SMD0402 | MURATA ELEC. NORTH AMERICA | GRM155C71E105KE11D | G | PWA BOM |  |
|  |  | ADD | 620138700-026-G | CAP,1uF,+/-10%,X6S,25V,G,SMD0402 | SAMSUNG | CL05X105KA5NQNC |  | PWA BOM |  |
|  |  | ADD | GRM155C81E105KE11D | CAP,1uF,+/-10%,X6S,25V,G,SMD0402 | MURATA | GRM155C81E105KE11D |  | PWA BOM |  |
| 14 | PETL1,PERL1,PSFL2,PEEL2,PEDL2 |  | 63032CD00-088-G | IND,2.2uH@100KHz,+/-20%,8A,20mOhm,SHLD,G,SMD | COOPER BUSSMANN, INC. | HCM0703-2R2-R | G | PWA BOM |  |
|  |  | ADD | CMLE063T-2R2MS | IND,CMLE063T-2R2MS | CYNTEC CO. LTD | CMLE063T-2R2MS | G | PWA BOM |  |
|  |  | Delete | 63033JK00-15A-G | IND,2.2uH@100KHz,+/-20%,9A,16.5mOhm,SHLD,G,SMD | The Inter-Technical Group, Inc. | SMHC2511A-2R2MHF | G | PWA BOM |  |
| 15 | PSRCE3000,PSRCE3001,PSPCE3003,PIPCE3003,PFPCE3003,PEPCE3003,PSPCE3004,PIPCE3004,PFPCE3004,PEPCE3004,PSPCE3005,PIPCE3005,PFPCE3005,PEPCE3005 |  | 62120CM00-024-G | SPEA CAP,220uF,+10%~-35%,6.3V,105C,G,SMD2816,ESR<=15mOhm | PANASONIC INDUSTRIAL CO.,LTD. | EEFCX0J221YR | G | PWA BOM |  |
|  |  | Delete | 622203H00-025-G | SPET CAP,220uF,+/-20%,6.3V,105_x0003_,G,SMD2816,ESR<=15mOhm | KEMET ELECTRONICS CORPORATION | T520V227M006ATE015 | G | PWA BOM |  |
|  |  | Delete | 622203H00-028-G | SPET CAP,220uF,+/-20%,6.3V,105C,G,SMD2816,ESR<=15mOhm | NEC | PSKV0J227M015C | G | PWA BOM |  |
| 16 | PSPL1,PIPL1,PFPL1,PEPL1 |  | 63032CC00-088-G | IND,1uH@100KHz,+/-20%,11A,10mOhm,SHLD,G,SMD | COOPER BUSSMANN, INC. | HCM0703-1R0-R | G | PWA BOM |  |
|  |  | ADD | CMMS063T1R0MS | IND,CMMS063T1R0MS | CYNTEC CO. LTD | CMMS063T1R0MS |  | PWA BOM |  |
|  |  | ADD | PA4341.102NLT | IND,PA4341.102NLT | PULSE ELECTRONICS (SINGAPORE) | PA4341.102NLT |  | PWA BOM |  |
|  |  | Delete | 63033LP00-15A-G | IND,1uH@100KHz,+/-20%,12.5A,8mOhm,SHLD,G,SMD | The Inter-Technical Group, Inc. | SMHC2511A-1R0MHF | G | PWA BOM |  |
| 17 | PERC7 |  | 62013BN00-015-G | CAP,4.3nF,+/-10%,X7R,50V,G,SMD0402 | MURATA ELEC. NORTH AMERICA | GRM155R71H432KA01D | G | PWA BOM |  |
|  |  | ADD | 62010LJ00-023-G | CAP,4.7nF,+/-10%,X7R,50V,G,SMD0402 | TAIYO | UMK105B7472KV-F |  | PWA BOM |  |
| 18 | PHAQ4 |  | 51020A000-031-G | TRANS P,PBHV9115T,150V,1A,G,SOT23-3,SMD | NXP SEMICONDUCTORS | PBHV9115T | G | PWA BOM |  |
|  |  | NO | MMBT5401 | TRANS P,150V,1A,G,SOT23-3,SMD | FAIRCHILD SEMICONDUCTOR CORP | MMBT5401 | G | PWA BOM |  |
|  |  | ADD | MMBT5401_1 | TRANS P,150V,1A,G,SOT23-3,SMD | DIODES INCORPORATION | MMBT5401_1 | G | PWA BOM |  |
|  |  | Delete | 51020AF00-280-G | Trans PNP,MMBT5401,-150V,-500mA,SOT-23,3P,G | Fairchild | MMBT5401 | G | PWA BOM |  |
| 19 | PSDR19 |  | 61100KM01-017-G | RES,15KOhm,+/-0.1%,1/16W,G,SMD0402 | KOA SPEER ELECTRONICS, INC. | RN73H1ETTP1502B25 | G | PWA BOM |  |
|  |  | ADD | ERA2AEB153X | RES,15KOhm,+/-0.1%,1/16W,G,SMD0402 | PANASONIC INDUSTRIAL CO.,LTD. | ERA2AEB153X | G | PWA BOM |  |
|  |  | Delete | 61100KM00-024-G | RES,15KOhm,+/-0.1%,1/16W,G,SMD0402 | PANASONIC INDUSTRIAL CO.,LTD. | ERA2AEB1502X | G | PWA BOM |  |
| 20 | PSRL1 |  | 63033PG00-15A-G | IND,22nH@100KHz,+/-15%,22A,249.55uOhm,SHLD,G,SMD | The Inter-Technical Group, Inc. | SLC1615A-R022LHF | G | PWA BOM |  |
|  |  | ADD | 63035Y500-129-G | IND,22nH@100KHz,+/-15%,22A,249.55uOhm,SHLD,G,SMD | MAG.LAYERS, SCIENTIFIC-TECHNICS (KUNSHAN) CO., LTD. | MSI-400404-22NL-I | G | PWA BOM |  |
|  |  | NO | 630352U00-034-G | IND,22nH@100KHz,+/-15%,22A,249.55uOhm,SHLD,G,SMD | CYNTEC CO. LTD | HCB0439-220 | G | PWA BOM |  |
|  |  | Delete | MSI-400404-22NL-I | IND,MSI-400404-22NL-I | MAG.LAYERS, SCIENTIFIC-TECHNICS (KUNSHAN) CO., LTD. | MSI-400404-22NL-I | G | PWA BOM |  |
| 21 | PSTR17 |  | 61100QA00-017-G | RES,16KOhm,+/-0.1%,1/16W,G,SMD0402 | KOA SPEER ELECTRONICS, INC. | RN731ETTP1602B25 | G | PWA BOM |  |
|  |  | ADD | ERA2AEB163X | RES,16KOhm,+/-0.1%,1/16W,G,SMD0402 | PANASONIC INDUSTRIAL CO.,LTD. | ERA2AEB163X | G | PWA BOM |  |
|  |  | NO | 61100QA00-029-G | RES,16KOhm,+/-0.1%,1/16W,G,SMD0402 | VISHAY ENTER TECHNO LOGY.INC | TNPW040216K0BEED | G | PWA BOM |  |
|  |  | Delete | 61100QA00-024-G | RES,16KOhm,+/-0.1%,1/16W,G,SMD0402 | PANASONIC INDUSTRIAL CO.,LTD. | ERA2AEB1602X | G | PWA BOM |  |
| 22 | QN1 |  | 510507500-185-G | MOS N/P,FDC6327C,20V,2.7/1.9A,80m/170m@4.5V,G,SuperSOT-6,SMD | FAIRCHILD SEMICONDUCTOR CORP | FDC6327C | G | PWA BOM |  |
|  |  | ADD | 51050BG00-223-G | MOS N/P,NTGD4167CT1G,30V,2.9/2.2A,90m/170m@4.5V,G,TSOP-6,SMD | ON SEMICONDUCTOR CORP | NTGD4167CT1G | G | PWA BOM |  |
|  |  | ADD | DMC2038LVT | MOS N/P,NTGD4167CT1G,30V,2.9/2.2A,90m/170m@4.5V,G,TSOP-6,SMD | DIODES INCORPORATION | DMC2038LVT | G | PWA BOM |  |
| 23 | Q2,Q3,Q4,Q6,Q15,PSUQ1 |  | 510301N00-223-G | MOS N,2N7002LT1G,60V,0.115A,7.5ohm@5V,G,SOT23-3,SMD | ON SEMICONDUCTOR CORP | 2N7002LT1G | G | PWA BOM |  |
|  |  | ADD | 51030CQ00-185-G | MOS N,2N7002,60V,115mA,7.5ohm@5V,G,SOT23-3,SMD | FAIRCHILD SEMICONDUCTOR CORP | 2N7002 |  | PWA BOM |  |
| 24 | Q5,Q7 |  | 510406000-185-G | MOS P,FDD6685,30V,11A,30m@4.5V,G,TO252-3,SMD | FAIRCHILD SEMICONDUCTOR CORP | FDD6685 | G | PWA BOM |  |
|  |  | ADD | IPD042P03L3 | MOS P,30V,11A,30m@4.5V,G,TO252-3,SMD | INFINEON TECHNOLOGIES CORP. | IPD042P03L3 |  | PWA BOM |  |
|  |  | NO | 51040WQ00-131-G | MOSFET-P,TJ40S04M3L,-40V,-40A,9.1mOhm@Vgs=-10V,13mOhm@Vgs=-6V,SMD,3P,G | TOSHIBA ELECTRONICS ASIA LTD | TJ40S04M3L | G | PWA BOM |  |
| 25 | Q12 |  | 510501900-237-G | MOS N/N,2N7002DW-7-F,60V,0.115A,7.5ohm@5V,G,SOT363-6,SMD | DIODES INEORPORATION | 2N7002DW-7-F | G | PWA BOM |  |
|  |  | ADD | 51050HV00-031-G | FET Dual channel,NX7002BKS,60V,240mA,2.8Ohm@Vgs=10V,3.2Ohm@Vgs=5V,SOT-363,6P,G | NXP SEMICONDUCTORS | NX7002BKS | G | PWA BOM |  |
|  |  | NO | 510507800-131-G | MOS N/N,SSM6N7002BFU,60V,200mA,3.3Ohm@4.5V,G,SC88-6,SMD | TOSHIBA ELECTRONICS ASIA LTD | SSM6N7002BFU | G | PWA BOM |  |
|  |  | Delete | 51050HS00-237-G | MOS N/N,60V,0.115A,7.5ohm@5V,G,SOT363-6,SMD | DIODES | DMN65D8LDW-7 |  | PWA BOM |  |
|  |  | Delete | SSM6N7002KFU | MOS N/N,SSM6N7002KFU,60V,200mA,3.3Ohm@4.5V,G,SC88-6,SMD | TOSHIBA ELECTRONICS ASIA LTD | SSM6N7002KFU |  | PWA BOM |  |
| 26 | R961,R962,R963,R964,R965,R967,R968,R969,R970,R975,R976,R977,R978,R985,R986,R988,R989,R992,R1003 |  | 61100C600-017-G | RES,1KOhm,+/-0.5%,1/16W,G,SMD0402 | KOA SPEER ELECTRONICS, INC. | RN731ETTP1001D25 | G | PWA BOM |  |
|  |  | ADD | ERA2AED102X | RES,1KOhm,+/-0.5%,1/16W,G,SMD0402 | PANASONIC INDUSTRIAL CO.,LTD. | ERA2AED102X | G | PWA BOM |  |
|  |  | NO | 61100C600-029-G | RES,1KOhm,+/-0.5%,1/16W,G,SMD0402 | VISHAY ENTER TECHNO LOGY.INC | MCS04020D1001DE000 | G | PWA BOM |  |
|  |  | Delete | 61100C600-024-G | RES,1KOhm,+/-0.5%,1/16W,G,SMD0402 | PANASONIC INDUSTRIAL CO.,LTD. | ERA2AED1001X | G | PWA BOM |  |
| 27 | U_TMP |  | 320403K00-183-G | IC,Temp Sensor,TMP75AIDR,3°C,G,SOIC-8,SMD | TEXAS INSTRUMENTS | TMP75AIDR | G | PWA BOM |  |
|  |  | ADD | 320404J00-190-G | IC,Temp Sensor,ADT75ARZ-REEL,1°C,G,SOIC-8,SMD | ANALOG DEVICES INC | ADT75ARZ-REEL | G | PWA BOM |  |
|  |  | ADD | 320403Q00-173-G | IC,Temp Sensor,DS75S+T&R,3°C,G,SO-8,SMD | MAXIM INTEGRATED PRODUCTS, INC. | DS75S+T&R | G | PWA BOM |  |
|  |  | ADD | 320405300-214-G | IC,Temp Sensor,STLM75M2F,±0.5°C,G,SO-8,SMD | ST MICRO ELECTRONICS,INC | STLM75M2F | G | PWA BOM |  |
|  |  | ADD | 32040SL00-223-G | IC,Temperature Sensor,NCT75DR2G,G,SOIC-8,SMD | ON SEMICONDUCTOR CORP | NCT75DR2G | G | PWA BOM |  |
|  |  | ADD | 32040FL00-031-G | IC,Temperature Sensor,LM75BD,G,SO-8,SMD | NXP SEMICONDUCTORS | LM75BD | G | PWA BOM |  |
| 28 | U20,U21 |  | 410512F00-233-G | Flash,MX66L51235FMI-10G,2.7V~3.6V,512M,SPI,G,SOP-16,SMD | MACRONIX INTERNATIONAL CO.,LTD. | MX66L51235FMI-10G | G | PWA BOM |  |
|  |  | ADD | 410513L00-216-G | Flash,SOP-16,MT25QL512ABB8ESF-0SIT | MICRON SEMICONDUCTOR ASIA PTE.LTD. | MT25QL512ABB8ESF-0SIT | G | PWA BOM |  |
| 29 | U24 |  | 41050DL00-233-G | Flash,MX25L6445EMI-10G,2.7~3.6V,64M,SPI,G,SOP-16,SMD | MACRONIX INTERNATIONAL CO.,LTD. | MX25L6445EMI-10G | G | PWA BOM |  |
|  |  | NO | 41050DW00-396-G | Flash,S25FL064P0XMFI001,2.7~3.6V,64M,SPI,G,SO-16,SMD | SPANSION INTERNATIONAL LLC | S25FL064P0XMFI001 | G | PWA BOM |  |
|  |  | ADD | W25Q64JVSFIM | Flash,2.7~3.6V,64M,SPI,G,SOP-16,SMD | WINBOND | W25Q64JVSFIM |  | PWA BOM |  |
|  |  | NO | 41050SF00-233-G | Flash,MX25L6435EMI-10G,2.7~3.6V,64M,SPI,G,SOP-16,SMD | MACRONIX INTERNATIONAL CO.,LTD. | MX25L6435EMI-10G | G | PWA BOM |  |
|  |  | Delete | 41050P500-205-G | NOR Flash,W25Q64FVSFIG,2.7V,3V,3.6V,64M,SPI,-40_x0003_~85_x0003_,SOIC,16P,G | WINBOND | W25Q64FVSFIG | G | PWA BOM |  |
| 30 | U83,U101,U102 |  | 310500F00-031-G | IC,Buffer,74LVC07APW,1.65~5.5V,G,TSSOP-14,SMD | NXP SEMICONDUCTORS | 74LVC07APW | G | PWA BOM |  |
|  |  | ADD | 74LVC0AT14-13 | IC,Buffer,74LVC07A,1.65~5.5V,G,TSSOP-14,SMD | DIODES INCORPORATION | 74LVC0AT14-13 | G | PWA BOM |  |
|  |  | Delete | 31050HP00-131-G | IC,Buffer,74LCX07FT,1.65V~5.5V,G,TSSOP-14,SMD | TOSHIBA ELECTRONICS ASIA LTD | 74LCX07FT | G | PWA BOM |  |
|  |  | Delete | 31050BY00-183-G | IC,Buffer,74LVC07A,1.65~5.5V,G,TSSOP-14,SMD | DIODES INC | 74LVC0AT14-13 | G | PWA BOM |  |
| 31 | U90,U91,U112 |  | 310201900-031-G | IC,Gate&Inverter,74LVC2G14GW,1.65~5.5V,G,SOT363-6,SMD | NXP SEMICONDUCTORS | 74LVC2G14GW | G | PWA BOM |  |
|  |  | NO | 310203300-223-G | Logic IC,Trigger,NL27WZ14DFT2G,1.65V~5.5V,7.4ns,SC-70/SOT-323,6P,G | ON SEMICONDUCTOR CORP | NL27WZ14DFT2G | G | PWA BOM |  |
|  |  | Delete | 31010M000-131-G | IC,Gate&Inverter,TC7PZ14FU,1.65~5.5V,G,SSOP-6,SMD | TOSHIBA ELECTRONICS ASIA LTD | TC7PZ14FU | G | PWA BOM |  |
| 32 | X1 |  | 71011RD00-100-G | XTAL,25MHz,+/-25ppm,20pF,G,SMD | TXC CORPORATION | 7V25000016 | G | PWA BOM |  |
|  |  | ADD | 1N225000CC0DT | XTAL,25MHz,+/-25ppm,20pF,G,SMD | KDS | 1N225000CC0DT |  | PWA BOM |  |
|  |  | ADD | 1C225000CC0DT | XTAL,25MHz,+/-25ppm,20pF,G,SMD | KDS | 1C225000CC0DT |  | PWA BOM |  |
| 33 | X3 |  | 710113800-100-G | XTAL,24MHz,+/-30ppm,20pF,G,SMD | TXC CORPORATION | 7B24000038 | G | PWA BOM |  |
|  |  | Delete | 17064-X-144-3 | XTAL,17064-X-144-3 | TAITIEN ELECTRONICS CO.,LTD | 17064-X-144-3 | G | PWA BOM |  |
| 34 | X5 |  | 71011UL00-107-G | XTAL,25MHz,+/-15ppm,16pF,G,SMD | DAISHINKU CORPORATION/DAISHINKU SINGAPORE PTE LTD/KDS | 1ZHY25000BB0A | G | PWA BOM |  |
|  |  | Delete | 17064-X-099-3 | XTAL,17064-X-099-3 | TAITIEN ELECTRONICS CO.,LTD | 17064-X-099-3 | G | PWA BOM |  |
| 35 | X6 |  | 710106900-162-G | XTAL,32.768KHz,+/-20ppm,12.5pF,G,SMD | EPSON ELECTRONICS AMERICA,INC. | Q13FC1350000400 | G | PWA BOM |  |
|  |  | NO | 71011P300-100-G | XTAL,32.768KHz,+/-20ppm,12.5pF,G,SMD | TXC CORPORATION | 9H03200031 | G | PWA BOM |  |
|  |  | ADD | 710123400-061-G | XTAL,32.768KHz,+/-20ppm,12.5pF,-40℃~85℃,SMD,G | TAITIEN | 06172-W-052-3 |  | PWA BOM |  |
| 36 | Y1 |  | 71020SC00-107-G | OSC,24MHz,+/-25ppm,3.3V,15pF,G,SMD | DAISHINKU CORPORATION/DAISHINKU SINGAPORE PTE LTD/KDS | 1XSE024000AR40 | G | PWA BOM |  |
|  |  | Delete | 71020B500-100-G | OSC,24MHz,+/-25ppm,3.3V,15pF,G,SMD | TXC CORPORATION | 7X24000014 | G | PWA BOM |  |
| 37 | Y2 |  | 71020Q600-16G-G | OSC,50MHz,50ppm,3.3V,G,SMD | SiTime Corporation | SIT1602AC-23-33E-50.000000T | G | PWA BOM |  |
|  |  | NO | 71012DA00-100-G | OSC,50MHz,+/-25ppm,15pF,G,SMD | TXC CORPORATION | 7X50000015 | G | PWA BOM |  |
|  |  | ADD | SSW050000I3CHE-ST7R2 | OSC,50MHz,+/-25ppm,15pF,G,SMD | HARMONY | SSW050000I3CHE-ST7R2 |  | PWA BOM |  |
| 38 | Y4 |  | 71020KL00-100-G | OSC,33MHz,+/-50ppm,3.3V,15pF,G,SMD | TXC CORPORATION | 7X33000013 | G | PWA BOM |  |
|  |  | ADD | 710211800-967-G | OSC,33MHz,+/-50ppm,3.3V,15pF,,-40℃~85℃,SMD,G | eCERA | FK3300011 | G | PWA BOM |  |
|  |  | ADD | SSW033000I3CH-SR5 | OSC,33MHz,+/-50ppm,3.3V,15pF,,-40℃~85℃,SMD,G | HARMONY | SSW033000I3CH-SR5 |  | PWA BOM |  |
|  |  | Delete | 710211700-16G-G | OSC,33MHz,+/-25ppm,3.3V,15pF,,-40_x0003_~85_x0003_,SMD,G | SiTime Corporation | SIT1602AI-22-33E-33.000000D | G | PWA BOM |  |
| 39 | DIMM02,DIMM04,DIMM06,DIMM09,DIMM11,DIMM13,DIMM15,DIMM16,DIMM18,DIMM20,DIMM22,DIMM25,DIMM27,DIMM29,DIMM31,DIMM00 |  | 34021BC00-G78-G | CONN,DDR IV,V/T,1.2V,Blu,0.85mm,15u,G,SMD-288 | FCI CONNECTORS HONGKONG LTD. | 10140702-0302K11LF | G | PWA BOM |  |
|  |  | NO | 34021CD00-600-G | Memory Connector,AH58897-T2L31-3F,DDR IV,288,SMD,THERMOPLASTIC,0.85mm,15u",Blue,G | FOXCONN TECHNOLOGY CO.,LTD. | AH58897-T2L31-3F | G | PWA BOM |  |
|  |  | NO | 34021CC00-245-G | Memory Connector,DDR4288S05A1H,DDR IV,288,SMD,NYLON,0.85mm,15u",Blue,G | AMPHENOL SHANGHAI CORP. | DDR4288S05A1H | G | PWA BOM |  |
|  |  | Delete | ADDR0245-K010C | CONN,ADDR0245-K010C | LOTES | ADDR0245-K010C |  | PWA BOM |  |
| 40 | DIMM01,DIMM03,DIMM05,DIMM07,DIMM08,DIMM10,DIMM12,DIMM14,DIMM17,DIMM19,DIMM21,DIMM23,DIMM24,DIMM26,DIMM28,DIMM30 |  | 34021BD00-G78-G | CONN,DDR IV,V/T,1.2V,Bla,0.85mm,15u,G,SMD-288 | FCI CONNECTORS HONGKONG LTD. | 10140702-0301K11LF | G | PWA BOM |  |
|  |  | NO | 34021CF00-600-G | Memory Connector,AH58897-T2B21-3F,DDR IV,288,SMD,THERMOPLASTIC,0.85mm,15u",Black,G | FOXCONN TECHNOLOGY CO.,LTD. | AH58897-T2B21-3F | G | PWA BOM |  |
|  |  | NO | 34021CE00-245-G | Memory Connector,DDR4288S0511H,DDR IV,288,SMD,NYLON,0.85mm,15u",Black,G | AMPHENOL SHANGHAI CORP. | DDR4288S0511H | G | PWA BOM |  |
|  |  | Delete | ADDR0245-P009C | CONN,ADDR0245-P009C | LOTES | ADDR0245-P009C |  | PWA BOM |  |
| 41 | J_BMC_DEBUG1,J1,J3,J4,J5,J36,J41,J43,J48,J147,J149 |  | 34068LN00-317-G | CONN,Header,Pin Header,1X3,V/T,2.54mm,30u,G,SMD-3 | MOLEX INCORPORATED | 87898-0315 | G | PWA BOM |  |
|  |  | NO | 34068HT00-245-G | CONN,Header,Pin Header,1X3,V/T,Bla,2.54mm,30u,SMD-3 | AMPHENOL SHANGHAI CORP. | G800MU305010EU |  | PWA BOM |  |
|  |  | NO | 34068GU00-309-G | CONN,Header,Pin Header,1X3,V/T,Bla,2.54mm,30u,SMD-3 | SAMTEC INC. | TSM-103-01-S-SV-P-TR | 3 | PWA BOM |  |
|  |  | Delete | 34066M800-GRT-G | CONN,Pin Header,1X3,V/T,Bla,2.54mm,30u,G,SMD-3 | PINREX TECHNOLOGY CORP. | 212-91-03SBEJ | G | PWA BOM |  |
|  |  | Delete | 3406AN600-637-G | CONN,Header,Pin Header,1X3,V/T,Bla,2.54mm,30u,G,SMD-3 | LONG SHOUNG CO.,LTD. | 11003A5708 | G | PWA BOM |  |
| 42 | J35,J37,J39,J42,J45 |  | 3406AQH00-317-G | CONN,Header,Pin Header,1X6,V/T,Bla,2.54mm,G,SMD-6 | MOLEX INCORPORATED | 87898-0656 | G | PWA BOM |  |
|  |  | NO | 3406A9F00-GRT-G | Header&Socket Connector,212-91-06GBE2,Pin Header,6,SMD,NY6T,2.54mm,3u",Black,G | PINREX TECHNOLOGY CORP. | 212-91-06GBE2 | G | PWA BOM |  |
|  |  | ADD | G800MR302032HR | Header&Socket Connector,G800MR302032EU,Pin Header,6,DIP,LCP,2.54mm,999.9999u",Black,G | AMPHENOL SHANGHAI CORP. | G800MR302032HR | G | PWA BOM |  |
|  |  | Delete | 3406AYA00-245-G | Header&Socket Connector,G800MR302032EU,Pin Header,6,DIP,LCP,2.54mm,999.9999u",Black,G | AMPHENOL SHANGHAI CORP. | G800MR302032EU | G | PWA BOM |  |
| 43 | J101 |  | 34062MW00-309-G | CONN,Header,WTB,2X5,V/T,Bla,1.27mm,10u,G,SMD-10 | SAMTEC INC. | FTSH-105-01-L-DV-K-P-TR | G | PWA BOM |  |
|  |  | NO | 3406AR700-GRT-G | Header&Socket Connector,232-9B-05SBEC,Pin Header,10,SMD,NY6T,1.27mm,10u",Black,G | PINREX TECHNOLOGY CORP. | 232-9B-05SBEC | G | PWA BOM |  |
|  |  | Delete | 3406ATS00-637-G | CONN,Header,Pin Header,2X5,V/T,Bla,1.27mm,10u,G,SMD-10 | LONG SHOUNG CO.,LTD. | 11210B5805 | G | PWA BOM |  |
| 44 | LAN1 |  | 34050PV00-48U-G | CONN,Modular Jack,RJ45X2,R/A,Bla,1.27mm,50u,G,DIP-28 | TRP CONNECTOR B.V. | 1840855-5 | G | PWA BOM |  |
|  |  | NO | 34051E700-609-G | CONN,Modular Jack,RJ45X2,R/A,Bla,1.27mm,50u,G,DIP-28 | U.D. Electronic Corp. | MA-FN-0003 | G | PWA BOM |  |
|  |  | ADD | 34050BF00-245-G | CONN,RJ45,Multi port,R/A,Bla,1.27mm,30u,G,DIP-28 | AMPHENOL | RJMG221031470NR | G | PWA BOM |  |
| 45 | PBAR65,PAAR65 |  | TLRH3APTTE20L0F | RES,20mOhm,+/-1%,2W,G,SMD2512 | KOA SPEER ELECTRONICS, INC. | TLRH3APTTE20L0F | G | PWA BOM |  |
|  |  | ADD | LRMAP2512-R01FT4 | RES,20mOhm,+/-1%,2W,G,SMD2512 | INTERNATIONAL RESISTIVE COMPANY, INC. | LRMAP2512-R01FT4 |  | PWA BOM |  |
| 46 | PBER65,PAFR65,PAER65,PBFR66 |  | SLW1TTE50L0F | RES,50mOhm,+/-1%,1.5W,G,SMD2512 | KOA SPEER ELECTRONICS, INC. | SLW1TTE50L0F | G | PWA BOM |  |
|  |  | ADD | LRMAP2512-R05FT4 | RES,50mOhm,+/-1%,1.5W,G,SMD2512 | INTERNATIONAL RESISTIVE COMPANY, INC. | LRMAP2512-R05FT4 |  | PWA BOM |  |
| 47 | PBMR65,PAMR65 |  | SLW1TTE75L0F | RES,75mOhm,+/-1%,1.5W,G,SMD2512 | KOA SPEER ELECTRONICS, INC. | SLW1TTE75L0F | G | PWA BOM |  |
|  |  | ADD | LRMAP2512-R075FT4 | RES,75mOhm,+/-1%,1.5W,G,SMD2512 | INTERNATIONAL RESISTIVE COMPANY, INC. | LRMAP2512-R075FT4 |  | PWA BOM |  |
| OOOOOOOOOOOOOOOOOOOOOOOOOOOOOOOOOOOOOOOOOOOOOOOOOOOOOOOOOOOOOOOOOOOOOOOOOOOOOOOOOOOOOOOOOO | OOOOOOOOOOOOOOOOOOOOOOOOOOOOOOOOOOOOOOOOOOOOOOOOOOOOOOOOOOOOOOOOOOOOOOOOOOOOOOOOOOOOOOOOOO | OOOOOOOOOOOOOOOOOOOOOOOOOOOOOOOOOOOOOOOOOOOOOOOOOOOOOOOOOOOOOOOOOOOOOOOOOOOOOOOOOOOOOOOOOO | OOOOOOOOOOOOOOOOOOOOOOOOOOOOOOOOOOOOOOOOOOOOOOOOOOOOOOOOOOOOOOOOOOOOOOOOOOOOOOOOOOOOOOOOOO | OOOOOOOOOOOOOOOOOOOOOOOOOOOOOOOOOOOOOOOOOOOOOOOOOOOOOOOOOOOOOOOOOOOOOOOOOOOOOOOOOOOOOOOOOO | OOOOOOOOOOOOOOOOOOOOOOOOOOOOOOOOOOOOOOOOOOOOOOOOOOOOOOOOOOOOOOOOOOOOOOOOOOOOOOOOOOOOOOOOOO | OOOOOOOOOOOOOOOOOOOOOOOOOOOOOOOOOOOOOOOOOOOOOOOOOOOOOOOOOOOOOOOOOOOOOOOOOOOOOOOOOOOOOOOOOO | OOOOOOOOOOOOOOOOOOOOOOOOOOOOOOOOOOOOOOOOOOOOOOOOOOOOOOOOOOOOOOOOOOOOOOOOOOOOOOOOOOOOOOOOOO | OOOOOOOOOOOOOOOOOOOOOOOOOOOOOOOOOOOOOOOOOOOOOOOOOOOOOOOOOOOOOOOOOOOOOOOOOOOOOOOOOOOOOOOOOO | OOOOOOOOOOOOOOOOOOOOOOOOOOOOOOOOOOOOOOOOOOOOOOOOOOOOOOOOOOOOOOOOOOOOOOOOOOOOOOOOOOOOOOOOOO |
| Master Materials Change |  |  |  |  |  |  |  |  |  |
| Item | Foxconn P/N | Orig._Usage | New_Usage | Part Description | Manufacturer Full Name | Manufacturer P/N | RoHS | Location | Sheet |
| 1 | 610108300-017-G | 109 | 108 | RES,0 Ohm,+/-5%,1/10W,G,SMD0603 | KOA SPEER ELECTRONICS, INC. | RK73Z1JTTD | G | (-)R1845 | PWA BOM |
|  | 610108300-012-G |  |  | RES,0 Ohm,+/-5%,1/10W,G,SMD0603 | WALSIN TECHNOLOGY CORPORATION | WR06X000PTL |  |  | PWA BOM |
|  | 610108300-011-G |  |  | RES,0 Ohm,+/-5%,1/10W,G,SMD0603 | YAGEO CORPORATION COMPONENT | RC0603JR-070RL |  |  | PWA BOM |
|  | 610108300-044-G |  |  | RES,0 Ohm,+/-5%,1/10W,G,SMD0603 | TA-I TECHNOLOGY CO., LTD | RM06JTN0 |  |  | PWA BOM |
|  | 610108300-024-G |  |  | RES,0 Ohm,+/-5%,1/10W,G,SMD0603 | PANASONIC INDUSTRIAL CO.,LTD. | ERJ3GEY0R00V |  |  | PWA BOM |
| 2 | 610107A00-017-G | 719 | 722 | RES,0 Ohm,+/-5%,1/16W,G,SMD0402 | KOA SPEER ELECTRONICS, INC. | RK73Z1ETTP | G | (+)R1519,R1848,R1849 | PWA BOM |
|  | 610107A00-012-G |  |  | RES,0 Ohm,+/-5%,1/16W,G,SMD0402 | WALSIN TECHNOLOGY CORPORATION | WR04X000PTL |  |  | PWA BOM |
|  | 610107A00-011-G |  |  | RES,0 Ohm,+/-5%,1/16W,G,SMD0402 | YAGEO CORPORATION COMPONENT | RC0402JR-070RL |  |  | PWA BOM |
|  | 610107A00-044-G |  |  | RES,0 Ohm,+/-5%,1/16W,G,SMD0402 | TA-I TECHNOLOGY CO., LTD | RM04JTN0 |  |  | PWA BOM |
|  | 610107A00-024-G |  |  | RES,0 Ohm,+/-5%,1/16W,G,SMD0402 | PANASONIC INDUSTRIAL CO.,LTD. | ERJ2GE0R00X |  |  | PWA BOM |
|  | 610107A00-029-G |  |  | RES,0 Ohm,+/-5%,1/16W,G,SMD0402 | VISHAY ENTER TECHNO LOGY.INC | CRCW04020000Z0ED |  |  | PWA BOM |
| 3 | 610113800-017-G | 31 | 27 | RES,10 Ohm,+/-1%,1/16W,G,SMD0402 | KOA SPEER ELECTRONICS, INC. | RK73H1ETTP10R0F | G | (-)PALR19,PALR20,PBLR23,PBLR24 | PWA BOM |
|  | 610113800-012-G |  |  | RES,10 Ohm,+/-1%,1/16W,G,SMD0402 | WALSIN TECHNOLOGY CORPORATION | WR04X10R0FTL |  |  | PWA BOM |
|  | 610113800-011-G |  |  | RES,10 Ohm,+/-1%,1/16W,G,SMD0402 | YAGEO CORPORATION COMPONENT | RC0402FR-0710RL |  |  | PWA BOM |
|  | 610113800-044-G |  |  | RES,10 Ohm,+/-1%,1/16W,G,SMD0402 | TA-I TECHNOLOGY CO., LTD | RM04FTN10R0 |  |  | PWA BOM |
| 4 | 61100LR00-017-G | 27 | 31 | RES,100 Ohm,+/-1%,1/16W,G,SMD0402 | KOA SPEER ELECTRONICS, INC. | RN731ETTP1000F50 | G | (+)PALR19,PALR20,PBLR23,PBLR24 | PWA BOM |
|  | 61100LR00-012-G |  |  | RES,100 Ohm,+/-1%,1/16W,G,SMD0402 | WALSIN TECHNOLOGY CORPORATION | WF04T1000FTL |  |  | PWA BOM |
|  | 61100LR01-011-G |  |  | RES,100 Ohm,+/-1%,1/16W,G,SMD0402 | YAGEO CORPORATION COMPONENT | RT0402FRE07100RL |  |  | PWA BOM |
|  | 61100LR00-044-G |  |  | RES,100 Ohm,+/-1%,1/16W,G,SMD0402 | TA-I TECHNOLOGY CO., LTD | RB04FTS1000 |  |  | PWA BOM |
| 5 | 61010L100-017-G | 16 | 17 | RES,100KOhm,+/-1%,1/16W,G,SMD0402 | KOA SPEER ELECTRONICS, INC. | RK73H1ETTP1003F | G | (+)R1559 | PWA BOM |
|  | 61010L100-012-G |  |  | RES,100KOhm,+/-1%,1/16W,G,SMD0402 | WALSIN TECHNOLOGY CORPORATION | WR04X1003FTL |  |  | PWA BOM |
|  | 61010L100-011-G |  |  | RES,100KOhm,+/-1%,1/16W,G,SMD0402 | YAGEO CORPORATION COMPONENT | RC0402FR-07100KL |  |  | PWA BOM |
|  | 61010L100-044-G |  |  | RES,100KOhm,+/-1%,1/16W,G,SMD0402 | TA-I TECHNOLOGY CO., LTD | RM04FTN1003 |  |  | PWA BOM |
|  | 61010L106-029-G |  |  | RES,100KOhm,+/-1%,1/16W,G,SMD0402 | VISHAY ENTER TECHNO LOGY.INC | CRCW0402100KFKEDC |  |  | PWA BOM |
|  | 61010L100-024-G |  |  | RES,100KOhm,+/-1%,1/16W,G,SMD0402 | PANASONIC INDUSTRIAL CO.,LTD. | ERJ2RKF1003X |  |  | PWA BOM |
| 6 | 610119U00-017-G | 0 | 2 | RES,133 Ohm,+/-1%,1/16W,G,SMD0402 | KOA SPEER ELECTRONICS, INC. | RK73H1ETTP1330F | G | (+)PBMR57,PAMR57 | PWA BOM |
| 7 | 61010LA00-017-G | 152 | 153 | RES,4.7KOhm,+/-1%,1/16W,G,SMD0402 | KOA SPEER ELECTRONICS, INC. | RK73H1ETTP4701F | G | (+)R1558 | PWA BOM |
|  | 61010LA00-012-G |  |  | RES,4.7KOhm,+/-1%,1/16W,G,SMD0402 | WALSIN TECHNOLOGY CORPORATION | WR04X4701FTL |  |  | PWA BOM |
|  | 61010LA00-011-G |  |  | RES,4.7KOhm,+/-1%,1/16W,G,SMD0402 | YAGEO CORPORATION COMPONENT | RC0402FR-074K7L |  |  | PWA BOM |
|  | 61010LA00-044-G |  |  | RES,4.7KOhm,+/-1%,1/16W,G,SMD0402 | TA-I TECHNOLOGY CO., LTD | RM04FTN4701 |  |  | PWA BOM |
| 8 | 510301N00-223-G | 4 | 6 | MOS N,2N7002LT1G,60V,0.115A,7.5ohm@5V,G,SOT23-3,SMD | ON SEMICONDUCTOR CORP | 2N7002LT1G | G | (+)Q15,PSUQ1 | PWA BOM |
|  | 51030CQ00-185-G |  |  | MOS N,2N7002,60V,115mA,7.5ohm@5V,G,SOT23-3,SMD | FAIRCHILD SEMICONDUCTOR CORP | 2N7002 |  |  | PWA BOM |
| 9 | 610102700-017-G | 209 | 208 | RES,49.9 Ohm,+/-1%,1/16W,G,SMD0402 | KOA SPEER ELECTRONICS, INC. | RK73H1ETTP49R9F | G | (-)R1811 | PWA BOM |
|  | 610102700-012-G |  |  | RES,49.9 Ohm,+/-1%,1/16W,G,SMD0402 | WALSIN TECHNOLOGY CORPORATION | WR04X49R9FTL |  |  | PWA BOM |
|  | 610102700-011-G |  |  | RES,49.9 Ohm,+/-1%,1/16W,G,SMD0402 | YAGEO CORPORATION COMPONENT | RC0402FR-0749R9L |  |  | PWA BOM |
|  | 610102700-044-G |  |  | RES,49.9 Ohm,+/-1%,1/16W,G,SMD0402 | TA-I TECHNOLOGY CO., LTD | RM04FTN49R9 |  |  | PWA BOM |
|  | 610102700-029-G |  |  | RES,49.9 Ohm,+/-1%,1/16W,G,SMD0402 | VISHAY ENTER TECHNO LOGY.INC | CRCW040249R9FKED |  |  | PWA BOM |
|  | 610102700-024-G |  |  | RES,49.9 Ohm,+/-1%,1/16W,G,SMD0402 | PANASONIC INDUSTRIAL CO.,LTD. | ERJ2RKF49R9X |  |  | PWA BOM |
| 10 | RN731ETTP3160B25 | 0 | 2 | RES,316 Ohm,+/-0.1%,1/16W,G,SMD0402 | KOA SPEER ELECTRONICS, INC. | RN731ETTP3160B25 | G | (+)PBMR34,PAMR34 | PWA BOM |
| 11 | 61100RF00-017-G | 2 | 0 | RES,402 Ohm,+/-0.1%,1/16W,G,SMD0402 | KOA SPEER ELECTRONICS, INC. | RN731ETTP4020B25 | N | (-)PBMR34,PAMR34 | PWA BOM |
| 12 | 610123T00-017-G | 2 | 0 | RES,232 Ohm,+/-1%,1/16W,G,SMD0402 | KOA SPEER ELECTRONICS, INC. | RK73H1ETTP2320F | N | (-)PBMR57,PAMR57 | PWA BOM |
| 13 | 51030CQ00-185-G | 1 | 0 | MOS N,2N7002,60V,115mA,7.5ohm@5V,G,SOT23-3,SMD | FAIRCHILD SEMICONDUCTOR CORP | 2N7002 | N | (-)PSUQ1 | PWA BOM |
|  | 510301N00-223-G_1 |  |  | MOS N,2N7002LT1G,60V,0.115A,7.5ohm@5V,G,SOT23-3,SMD | ON SEMICONDUCTOR CORP | 2N7002LT1G |  |  | PWA BOM |
| OOOOOOOOOOOOOOOOOOOOOOOOOOOOOOOOOOOOOOOOOOOOOOOOOOOOOOOOOOOOOOOOOOOOOOOOOOOOOOOOOOOOOOOOOO | OOOOOOOOOOOOOOOOOOOOOOOOOOOOOOOOOOOOOOOOOOOOOOOOOOOOOOOOOOOOOOOOOOOOOOOOOOOOOOOOOOOOOOOOOO | OOOOOOOOOOOOOOOOOOOOOOOOOOOOOOOOOOOOOOOOOOOOOOOOOOOOOOOOOOOOOOOOOOOOOOOOOOOOOOOOOOOOOOOOOO | OOOOOOOOOOOOOOOOOOOOOOOOOOOOOOOOOOOOOOOOOOOOOOOOOOOOOOOOOOOOOOOOOOOOOOOOOOOOOOOOOOOOOOOOOO | OOOOOOOOOOOOOOOOOOOOOOOOOOOOOOOOOOOOOOOOOOOOOOOOOOOOOOOOOOOOOOOOOOOOOOOOOOOOOOOOOOOOOOOOOO | OOOOOOOOOOOOOOOOOOOOOOOOOOOOOOOOOOOOOOOOOOOOOOOOOOOOOOOOOOOOOOOOOOOOOOOOOOOOOOOOOOOOOOOOOO | OOOOOOOOOOOOOOOOOOOOOOOOOOOOOOOOOOOOOOOOOOOOOOOOOOOOOOOOOOOOOOOOOOOOOOOOOOOOOOOOOOOOOOOOOO | OOOOOOOOOOOOOOOOOOOOOOOOOOOOOOOOOOOOOOOOOOOOOOOOOOOOOOOOOOOOOOOOOOOOOOOOOOOOOOOOOOOOOOOOOO | OOOOOOOOOOOOOOOOOOOOOOOOOOOOOOOOOOOOOOOOOOOOOOOOOOOOOOOOOOOOOOOOOOOOOOOOOOOOOOOOOOOOOOOOOO | OOOOOOOOOOOOOOOOOOOOOOOOOOOOOOOOOOOOOOOOOOOOOOOOOOOOOOOOOOOOOOOOOOOOOOOOOOOOOOOOOOOOOOOOOO |
| TLA Parts Change |  |  |  |  |  |  |  |  |  |
| Item | Foxconn P/N | Qty | Part Description | Manufacturer Full Name | Manufacturer P/N | RoHS | Location | Remark | BOM |
| BOM Change List Date:Wed May 31 11:31:40 CST 2017 |  |  |  |  |  |  |  |  |  |
| New BOM file : C:\<user>\bg2 new.xls |  |  |  |  |  |  |  |  |  |
| Old BOM file : C:\<user>\bg2 old.xls |  |  |  |  |  |  |  |  |  |
| ##### Add Parts |  |  |  |  |  |  |  |  |  |
| Item | Location | Qty | Foxconn P/N | Part Description | Manufacturer Full Name | Manufacturer P/N | RoHS | Sheet |  |
| ##### Remove Parts |  |  |  |  |  |  |  |  |  |
| Item | Location | Qty | Foxconn P/N | Part Description | Manufacturer Full Name | Manufacturer P/N | RoHS | Sheet |  |
| ##### Change Parts |  |  |  |  |  |  |  |  |  |
| Item | Location | Qty | Foxconn P/N | Part Description | Manufacturer Full Name | Manufacturer P/N | RoHS | Sheet | Remark |
| 1 | Q12 | 1 | 510501900-237-G | MOS N/N,2N7002DW-7-F,60V,0.115A,7.5ohm@5V,G,SOT363-6,SMD | DIODES INEORPORATION | 2N7002DW-7-F | G | PWA BOM | In New BOM |
|  |  |  | 51050HV00-031-G | FET Dual channel,NX7002BKS,60V,240mA,2.8Ohm@Vgs=10V,3.2Ohm@Vgs=5V,SOT-363,6P,G | NXP SEMICONDUCTORS | NX7002BKS | G | PWA BOM | In New BOM |
|  |  |  | SSM6N7002KFU | MOS N/N,SSM6N7002KFU,60V,200mA,3.3Ohm@4.5V,G,SC88-6,SMD | TOSHIBA ELECTRONICS ASIA LTD | SSM6N7002KFU | G | PWA BOM | In New BOM |
|  | Q12 | 1 | 510501900-237-G | MOS N/N,2N7002DW-7-F,60V,0.115A,7.5ohm@5V,G,SOT363-6,SMD | DIODES INEORPORATION | 2N7002DW-7-F | G | PWA BOM | In Old BOM |
|  |  |  | 51050HV00-031-G | FET Dual channel,NX7002BKS,60V,240mA,2.8Ohm@Vgs=10V,3.2Ohm@Vgs=5V,SOT-363,6P,G | NXP SEMICONDUCTORS | NX7002BKS | G | PWA BOM | In Old BOM |
|  |  |  | 510507800-131-G | MOS N/N,SSM6N7002BFU,60V,200mA,3.3Ohm@4.5V,G,SC88-6,SMD | TOSHIBA ELECTRONICS ASIA LTD | SSM6N7002BFU | G | PWA BOM | In Old BOM |
| ##### Change Revision |  |  |  |  |  |  |  |  |  |
| Sheet | REV OF BOM | CUSTOMER | CUSTOMER P/N | PWA PN | PWA DESCRIPTION | PWA REV | DATE | Remark |  |
| OOOOOOOOOOOOOOOOOOOOOOOOOOOOOOOOOOOOOOOOOOOOOOOOOOOOOOOOOOOOOOOOOOOOOOOOOOOOOOOOOOOOOOOOOO | OOOOOOOOOOOOOOOOOOOOOOOOOOOOOOOOOOOOOOOOOOOOOOOOOOOOOOOOOOOOOOOOOOOOOOOOOOOOOOOOOOOOOOOOOO | OOOOOOOOOOOOOOOOOOOOOOOOOOOOOOOOOOOOOOOOOOOOOOOOOOOOOOOOOOOOOOOOOOOOOOOOOOOOOOOOOOOOOOOOOO | OOOOOOOOOOOOOOOOOOOOOOOOOOOOOOOOOOOOOOOOOOOOOOOOOOOOOOOOOOOOOOOOOOOOOOOOOOOOOOOOOOOOOOOOOO | OOOOOOOOOOOOOOOOOOOOOOOOOOOOOOOOOOOOOOOOOOOOOOOOOOOOOOOOOOOOOOOOOOOOOOOOOOOOOOOOOOOOOOOOOO | OOOOOOOOOOOOOOOOOOOOOOOOOOOOOOOOOOOOOOOOOOOOOOOOOOOOOOOOOOOOOOOOOOOOOOOOOOOOOOOOOOOOOOOOOO | OOOOOOOOOOOOOOOOOOOOOOOOOOOOOOOOOOOOOOOOOOOOOOOOOOOOOOOOOOOOOOOOOOOOOOOOOOOOOOOOOOOOOOOOOO | OOOOOOOOOOOOOOOOOOOOOOOOOOOOOOOOOOOOOOOOOOOOOOOOOOOOOOOOOOOOOOOOOOOOOOOOOOOOOOOOOOOOOOOOOO | OOOOOOOOOOOOOOOOOOOOOOOOOOOOOOOOOOOOOOOOOOOOOOOOOOOOOOOOOOOOOOOOOOOOOOOOOOOOOOOOOOOOOOOOOO | OOOOOOOOOOOOOOOOOOOOOOOOOOOOOOOOOOOOOOOOOOOOOOOOOOOOOOOOOOOOOOOOOOOOOOOOOOOOOOOOOOOOOOOOOO |
| Second Source Change |  |  |  |  |  |  |  |  |  |
| Item | Location | Change Type | Foxconn P/N | Part Description | Manufacturer Full Name | Manufacturer P/N | RoHS | Sheet |  |
| 1 | Q12 |  | 510501900-237-G | MOS N/N,2N7002DW-7-F,60V,0.115A,7.5ohm@5V,G,SOT363-6,SMD | DIODES INEORPORATION | 2N7002DW-7-F | G | PWA BOM |  |
|  |  | NO | 51050HV00-031-G | FET Dual channel,NX7002BKS,60V,240mA,2.8Ohm@Vgs=10V,3.2Ohm@Vgs=5V,SOT-363,6P,G | NXP SEMICONDUCTORS | NX7002BKS | G | PWA BOM |  |
|  |  | ADD | SSM6N7002KFU | MOS N/N,SSM6N7002KFU,60V,200mA,3.3Ohm@4.5V,G,SC88-6,SMD | TOSHIBA ELECTRONICS ASIA LTD | SSM6N7002KFU | G | PWA BOM |  |
|  |  | Delete | 510507800-131-G | MOS N/N,SSM6N7002BFU,60V,200mA,3.3Ohm@4.5V,G,SC88-6,SMD | TOSHIBA ELECTRONICS ASIA LTD | SSM6N7002BFU | G | PWA BOM |  |
| OOOOOOOOOOOOOOOOOOOOOOOOOOOOOOOOOOOOOOOOOOOOOOOOOOOOOOOOOOOOOOOOOOOOOOOOOOOOOOOOOOOOOOOOOO | OOOOOOOOOOOOOOOOOOOOOOOOOOOOOOOOOOOOOOOOOOOOOOOOOOOOOOOOOOOOOOOOOOOOOOOOOOOOOOOOOOOOOOOOOO | OOOOOOOOOOOOOOOOOOOOOOOOOOOOOOOOOOOOOOOOOOOOOOOOOOOOOOOOOOOOOOOOOOOOOOOOOOOOOOOOOOOOOOOOOO | OOOOOOOOOOOOOOOOOOOOOOOOOOOOOOOOOOOOOOOOOOOOOOOOOOOOOOOOOOOOOOOOOOOOOOOOOOOOOOOOOOOOOOOOOO | OOOOOOOOOOOOOOOOOOOOOOOOOOOOOOOOOOOOOOOOOOOOOOOOOOOOOOOOOOOOOOOOOOOOOOOOOOOOOOOOOOOOOOOOOO | OOOOOOOOOOOOOOOOOOOOOOOOOOOOOOOOOOOOOOOOOOOOOOOOOOOOOOOOOOOOOOOOOOOOOOOOOOOOOOOOOOOOOOOOOO | OOOOOOOOOOOOOOOOOOOOOOOOOOOOOOOOOOOOOOOOOOOOOOOOOOOOOOOOOOOOOOOOOOOOOOOOOOOOOOOOOOOOOOOOOO | OOOOOOOOOOOOOOOOOOOOOOOOOOOOOOOOOOOOOOOOOOOOOOOOOOOOOOOOOOOOOOOOOOOOOOOOOOOOOOOOOOOOOOOOOO | OOOOOOOOOOOOOOOOOOOOOOOOOOOOOOOOOOOOOOOOOOOOOOOOOOOOOOOOOOOOOOOOOOOOOOOOOOOOOOOOOOOOOOOOOO | OOOOOOOOOOOOOOOOOOOOOOOOOOOOOOOOOOOOOOOOOOOOOOOOOOOOOOOOOOOOOOOOOOOOOOOOOOOOOOOOOOOOOOOOOO |
| Master Materials Change |  |  |  |  |  |  |  |  |  |
| Item | Foxconn P/N | Orig._Usage | New_Usage | Part Description | Manufacturer Full Name | Manufacturer P/N | RoHS | Location | Sheet |
| OOOOOOOOOOOOOOOOOOOOOOOOOOOOOOOOOOOOOOOOOOOOOOOOOOOOOOOOOOOOOOOOOOOOOOOOOOOOOOOOOOOOOOOOOO | OOOOOOOOOOOOOOOOOOOOOOOOOOOOOOOOOOOOOOOOOOOOOOOOOOOOOOOOOOOOOOOOOOOOOOOOOOOOOOOOOOOOOOOOOO | OOOOOOOOOOOOOOOOOOOOOOOOOOOOOOOOOOOOOOOOOOOOOOOOOOOOOOOOOOOOOOOOOOOOOOOOOOOOOOOOOOOOOOOOOO | OOOOOOOOOOOOOOOOOOOOOOOOOOOOOOOOOOOOOOOOOOOOOOOOOOOOOOOOOOOOOOOOOOOOOOOOOOOOOOOOOOOOOOOOOO | OOOOOOOOOOOOOOOOOOOOOOOOOOOOOOOOOOOOOOOOOOOOOOOOOOOOOOOOOOOOOOOOOOOOOOOOOOOOOOOOOOOOOOOOOO | OOOOOOOOOOOOOOOOOOOOOOOOOOOOOOOOOOOOOOOOOOOOOOOOOOOOOOOOOOOOOOOOOOOOOOOOOOOOOOOOOOOOOOOOOO | OOOOOOOOOOOOOOOOOOOOOOOOOOOOOOOOOOOOOOOOOOOOOOOOOOOOOOOOOOOOOOOOOOOOOOOOOOOOOOOOOOOOOOOOOO | OOOOOOOOOOOOOOOOOOOOOOOOOOOOOOOOOOOOOOOOOOOOOOOOOOOOOOOOOOOOOOOOOOOOOOOOOOOOOOOOOOOOOOOOOO | OOOOOOOOOOOOOOOOOOOOOOOOOOOOOOOOOOOOOOOOOOOOOOOOOOOOOOOOOOOOOOOOOOOOOOOOOOOOOOOOOOOOOOOOOO | OOOOOOOOOOOOOOOOOOOOOOOOOOOOOOOOOOOOOOOOOOOOOOOOOOOOOOOOOOOOOOOOOOOOOOOOOOOOOOOOOOOOOOOOOO |
| TLA Parts Change |  |  |  |  |  |  |  |  |  |
| Item | Foxconn P/N | Qty | Part Description | Manufacturer Full Name | Manufacturer P/N | RoHS | Location | Remark | BOM |
| BOM Change List Date:Wed May 31 18:35:46 CST 2017 |  |  |  |  |  |  |  |  |  |
| New BOM file : C:\<user>\BARRELEYE-G2-MB-DVT-HW-X03-BOM-X17_20170531.xls |  |  |  |  |  |  |  |  |  |
| Old BOM file : C:\<user>\BARRELEYE-G2-MB-DVT-HW-X03-BOM-X17_20170531 noon.xls |  |  |  |  |  |  |  |  |  |
| ##### Add Parts |  |  |  |  |  |  |  |  |  |
| Item | Location | Qty | Foxconn P/N | Part Description | Manufacturer Full Name | Manufacturer P/N | RoHS | Sheet |  |
| ##### Remove Parts |  |  |  |  |  |  |  |  |  |
| Item | Location | Qty | Foxconn P/N | Part Description | Manufacturer Full Name | Manufacturer P/N | RoHS | Sheet |  |
| ##### Change Parts |  |  |  |  |  |  |  |  |  |
| Item | Location | Qty | Foxconn P/N | Part Description | Manufacturer Full Name | Manufacturer P/N | RoHS | Sheet | Remark |
| 1 | PCB | 1 | 0101EW800-000-G | PCB,Zaius-MB DVT-X03,OSP,Blu,22L,22.20*13.00,G | GOLD CIRCUIT ELECTRONICS LTD. | 0101EW800-000-G | G | PWA BOM | In New BOM |
|  |  |  | 0101EW800-000-G | PCB,Zaius-MB DVT-X03,OSP,Blu,22L,22.20*13.00,G | ZHUHAI FOUNDER PRINTED CIRCUIT BOARD（HK） DEVELOPMENT LIMITED | 0101EW800-000-G | G | PWA BOM | In New BOM |
|  |  |  | 0101EW800-000-G | PCB,Zaius-MB DVT-X03,OSP,Blu,22L,22.20*13.00,G | ISUPETASYS CO., LTD | 0101EW800-000-G | G | PWA BOM | In New BOM |
|  | PCB | 1 | 0101EW800-000-G | PCB,Zaius-MB DVT-X03,OSP,Blu,22L,22.20*13.00,G | GOLD CIRCUIT ELECTRONICS LTD. | 0101EW800-000-G | G | PWA BOM | In Old BOM |
|  |  |  | 0101EW800-000-G | PCB,Zaius-MB DVT-X03,OSP,Blu,22L,22.20*13.00,G | ZHUHAI FOUNDER PRINTED CIRCUIT BOARD（HK） DEVELOPMENT LIMITED | 0101EW800-000-G | G | PWA BOM | In Old BOM |
| 2 | ED1,ED2,ED3 | 3 | 521800900-227-G | DIODE,Array-TVS,SRV05-4.TCT,5V,12A,G,SOT23-6,SMD | SEMTECH CORPORATION. | SRV05-4.TCT | G | PWA BOM | In New BOM |
|  |  |  | 52180C200-086-G | Diode,Array-TVS,SRV05-4HTG,SOT-23,6P,G | LITTELFUSE FAR EAST PTE LTD | SRV05-4HTG | G | PWA BOM | In New BOM |
|  | ED1,ED2,ED3 | 3 | 521800900-227-G | DIODE,Array-TVS,SRV05-4.TCT,5V,12A,G,SOT23-6,SMD | SEMTECH CORPORATION. | SRV05-4.TCT | G | PWA BOM | In Old BOM |
|  |  |  | 52180H500-086-G | Diode,Array-TVS,SRV05-04HTG,SOT-23,6P,G | LITTELFUSE FAR EAST PTE LTD | SRV05-04HTG | G | PWA BOM | In Old BOM |
| 3 | LED10,LED14 | 2 | 52113B000-289-G | LED,Yellow,LTL-42NSV8DH184P,5V,20mA,G,DIP-2 | LITE-ON TECHNOLOGY CORPORATION | LTL-42NSV8DH184P | G | PWA BOM | In New BOM |
|  | LED10,LED14 | 2 | 52113B000-289-G | LED,Yellow,LTL-42NSV8DH184P,5V,20mA,G,DIP-2 | LITE-ON TECHNOLOGY CORPORATION | LTL-42NSV8DH184P | G | PWA BOM | In Old BOM |
|  |  |  | L-7104ADFX012-TW | LED,L-7104ADFX012-TW | Kingbright | L-7104ADFX012-TW | G | PWA BOM | In Old BOM |
| 4 | LED11,LED12 | 2 | 52113AW00-289-G | LED,Green,LTL-42NGY8DH184P,5V,20mA,G,DIP-2 | LITE-ON TECHNOLOGY CORPORATION | LTL-42NGY8DH184P | G | PWA BOM | In New BOM |
|  | LED11,LED12 | 2 | 52113AW00-289-G | LED,Green,LTL-42NGY8DH184P,5V,20mA,G,DIP-2 | LITE-ON TECHNOLOGY CORPORATION | LTL-42NGY8DH184P | G | PWA BOM | In Old BOM |
|  |  |  | SSF-LXH303GD | LED,Green,SSF-LXH303GD,5V,20mA,G,DIP-2 | LUEMX INC,TAIWAN BRANCH | SSF-LXH303GD | G | PWA BOM | In Old BOM |
| 5 | LED13 | 1 | 52113B100-289-G | LED,Blue,LTL42TB6NH184P,5V,30mA,G,DIP-2 | LITE-ON TECHNOLOGY CORPORATION | LTL42TB6NH184P | G | PWA BOM | In New BOM |
|  | LED13 | 1 | 52113B100-289-G | LED,Blue,LTL42TB6NH184P,5V,30mA,G,DIP-2 | LITE-ON TECHNOLOGY CORPORATION | LTL42TB6NH184P | G | PWA BOM | In Old BOM |
|  |  |  | L-7104ADFX010-TW | LED,Blue,LTL42TB6NH184P,5V,30mA,G,DIP-2 | Kingbright | L-7104ADFX010-TW | G | PWA BOM | In Old BOM |
| 6 | PHAQ4 | 1 | 51020A000-031-G | TRANS P,PBHV9115T,150V,1A,G,SOT23-3,SMD | NXP SEMICONDUCTORS | PBHV9115T | G | PWA BOM | In New BOM |
|  |  |  | MMBT5401 | TRANS P,150V,1A,G,SOT23-3,SMD | FAIRCHILD SEMICONDUCTOR CORP | MMBT5401 | G | PWA BOM | In New BOM |
|  |  |  | 510204N00-237-G | Trans PNP,MMBT5401-7-F,-150V,-600mA,SOT-23,3P,G | DIODES INCORPORATION | MMBT5401-7-F | G | PWA BOM | In New BOM |
|  | PHAQ4 | 1 | 51020A000-031-G | TRANS P,PBHV9115T,150V,1A,G,SOT23-3,SMD | NXP SEMICONDUCTORS | PBHV9115T | G | PWA BOM | In Old BOM |
|  |  |  | MMBT5401 | TRANS P,150V,1A,G,SOT23-3,SMD | FAIRCHILD SEMICONDUCTOR CORP | MMBT5401 | G | PWA BOM | In Old BOM |
|  |  |  | MMBT5401_1 | TRANS P,150V,1A,G,SOT23-3,SMD | DIODES INCORPORATION | MMBT5401_1 | G | PWA BOM | In Old BOM |
| 7 | U24 | 1 | 41050DL00-233-G | Flash,MX25L6445EMI-10G,2.7~3.6V,64M,SPI,G,SOP-16,SMD | MACRONIX INTERNATIONAL CO.,LTD. | MX25L6445EMI-10G | G | PWA BOM | In New BOM |
|  |  |  | 41050DW00-396-G | Flash,S25FL064P0XMFI001,2.7~3.6V,64M,SPI,G,SO-16,SMD | SPANSION INTERNATIONAL LLC | S25FL064P0XMFI001 | G | PWA BOM | In New BOM |
|  |  |  | W25Q64JVSFIQ | Flash,2.7~3.6V,64M,SPI,G,SOP-16,SMD | WINBOND | W25Q64JVSFIQ |  | PWA BOM | In New BOM |
|  |  |  | 41050SF00-233-G | Flash,MX25L6435EMI-10G,2.7~3.6V,64M,SPI,G,SOP-16,SMD | MACRONIX INTERNATIONAL CO.,LTD. | MX25L6435EMI-10G | G | PWA BOM | In New BOM |
|  | U24 | 1 | 41050DL00-233-G | Flash,MX25L6445EMI-10G,2.7~3.6V,64M,SPI,G,SOP-16,SMD | MACRONIX INTERNATIONAL CO.,LTD. | MX25L6445EMI-10G | G | PWA BOM | In Old BOM |
|  |  |  | 41050DW00-396-G | Flash,S25FL064P0XMFI001,2.7~3.6V,64M,SPI,G,SO-16,SMD | SPANSION INTERNATIONAL LLC | S25FL064P0XMFI001 | G | PWA BOM | In Old BOM |
|  |  |  | W25Q64JVSFIM | Flash,2.7~3.6V,64M,SPI,G,SOP-16,SMD | WINBOND | W25Q64JVSFIM |  | PWA BOM | In Old BOM |
|  |  |  | 41050SF00-233-G | Flash,MX25L6435EMI-10G,2.7~3.6V,64M,SPI,G,SOP-16,SMD | MACRONIX INTERNATIONAL CO.,LTD. | MX25L6435EMI-10G | G | PWA BOM | In Old BOM |
| ##### Change Revision |  |  |  |  |  |  |  |  |  |
| Sheet | REV OF BOM | CUSTOMER | CUSTOMER P/N | PWA PN | PWA DESCRIPTION | PWA REV | DATE | Remark |  |
| OOOOOOOOOOOOOOOOOOOOOOOOOOOOOOOOOOOOOOOOOOOOOOOOOOOOOOOOOOOOOOOOOOOOOOOOOOOOOOOOOOOOOOOOOO | OOOOOOOOOOOOOOOOOOOOOOOOOOOOOOOOOOOOOOOOOOOOOOOOOOOOOOOOOOOOOOOOOOOOOOOOOOOOOOOOOOOOOOOOOO | OOOOOOOOOOOOOOOOOOOOOOOOOOOOOOOOOOOOOOOOOOOOOOOOOOOOOOOOOOOOOOOOOOOOOOOOOOOOOOOOOOOOOOOOOO | OOOOOOOOOOOOOOOOOOOOOOOOOOOOOOOOOOOOOOOOOOOOOOOOOOOOOOOOOOOOOOOOOOOOOOOOOOOOOOOOOOOOOOOOOO | OOOOOOOOOOOOOOOOOOOOOOOOOOOOOOOOOOOOOOOOOOOOOOOOOOOOOOOOOOOOOOOOOOOOOOOOOOOOOOOOOOOOOOOOOO | OOOOOOOOOOOOOOOOOOOOOOOOOOOOOOOOOOOOOOOOOOOOOOOOOOOOOOOOOOOOOOOOOOOOOOOOOOOOOOOOOOOOOOOOOO | OOOOOOOOOOOOOOOOOOOOOOOOOOOOOOOOOOOOOOOOOOOOOOOOOOOOOOOOOOOOOOOOOOOOOOOOOOOOOOOOOOOOOOOOOO | OOOOOOOOOOOOOOOOOOOOOOOOOOOOOOOOOOOOOOOOOOOOOOOOOOOOOOOOOOOOOOOOOOOOOOOOOOOOOOOOOOOOOOOOOO | OOOOOOOOOOOOOOOOOOOOOOOOOOOOOOOOOOOOOOOOOOOOOOOOOOOOOOOOOOOOOOOOOOOOOOOOOOOOOOOOOOOOOOOOOO | OOOOOOOOOOOOOOOOOOOOOOOOOOOOOOOOOOOOOOOOOOOOOOOOOOOOOOOOOOOOOOOOOOOOOOOOOOOOOOOOOOOOOOOOOO |
| Second Source Change |  |  |  |  |  |  |  |  |  |
| Item | Location | Change Type | Foxconn P/N | Part Description | Manufacturer Full Name | Manufacturer P/N | RoHS | Sheet |  |
| 1 | PCB |  | 0101EW800-000-G | PCB,Zaius-MB DVT-X03,OSP,Blu,22L,22.20*13.00,G | GOLD CIRCUIT ELECTRONICS LTD. | 0101EW800-000-G | G | PWA BOM |  |
|  |  | NO | 0101EW800-000-G | PCB,Zaius-MB DVT-X03,OSP,Blu,22L,22.20*13.00,G | ZHUHAI FOUNDER PRINTED CIRCUIT BOARD（HK） DEVELOPMENT LIMITED | 0101EW800-000-G | G | PWA BOM |  |
|  |  | NO | 0101EW800-000-G | PCB,Zaius-MB DVT-X03,OSP,Blu,22L,22.20*13.00,G | ISUPETASYS CO., LTD | 0101EW800-000-G | G | PWA BOM |  |
| 2 | ED1,ED2,ED3 |  | 521800900-227-G | DIODE,Array-TVS,SRV05-4.TCT,5V,12A,G,SOT23-6,SMD | SEMTECH CORPORATION. | SRV05-4.TCT | G | PWA BOM |  |
|  |  | ADD | 52180C200-086-G | Diode,Array-TVS,SRV05-4HTG,SOT-23,6P,G | LITTELFUSE FAR EAST PTE LTD | SRV05-4HTG | G | PWA BOM |  |
|  |  | Delete | 52180H500-086-G | Diode,Array-TVS,SRV05-04HTG,SOT-23,6P,G | LITTELFUSE FAR EAST PTE LTD | SRV05-04HTG | G | PWA BOM |  |
| 3 | LED10,LED14 |  | 52113B000-289-G | LED,Yellow,LTL-42NSV8DH184P,5V,20mA,G,DIP-2 | LITE-ON TECHNOLOGY CORPORATION | LTL-42NSV8DH184P | G | PWA BOM |  |
|  |  | Delete | L-7104ADFX012-TW | LED,L-7104ADFX012-TW | Kingbright | L-7104ADFX012-TW | G | PWA BOM |  |
| 4 | LED11,LED12 |  | 52113AW00-289-G | LED,Green,LTL-42NGY8DH184P,5V,20mA,G,DIP-2 | LITE-ON TECHNOLOGY CORPORATION | LTL-42NGY8DH184P | G | PWA BOM |  |
|  |  | Delete | SSF-LXH303GD | LED,Green,SSF-LXH303GD,5V,20mA,G,DIP-2 | LUEMX INC,TAIWAN BRANCH | SSF-LXH303GD | G | PWA BOM |  |
| 5 | LED13 |  | 52113B100-289-G | LED,Blue,LTL42TB6NH184P,5V,30mA,G,DIP-2 | LITE-ON TECHNOLOGY CORPORATION | LTL42TB6NH184P | G | PWA BOM |  |
|  |  | Delete | L-7104ADFX010-TW | LED,Blue,LTL42TB6NH184P,5V,30mA,G,DIP-2 | Kingbright | L-7104ADFX010-TW | G | PWA BOM |  |
| 6 | PHAQ4 |  | 51020A000-031-G | TRANS P,PBHV9115T,150V,1A,G,SOT23-3,SMD | NXP SEMICONDUCTORS | PBHV9115T | G | PWA BOM |  |
|  |  | NO | MMBT5401 | TRANS P,150V,1A,G,SOT23-3,SMD | FAIRCHILD SEMICONDUCTOR CORP | MMBT5401 | G | PWA BOM |  |
|  |  | ADD | 510204N00-237-G | Trans PNP,MMBT5401-7-F,-150V,-600mA,SOT-23,3P,G | DIODES INCORPORATION | MMBT5401-7-F | G | PWA BOM |  |
|  |  | Delete | MMBT5401 | TRANS P,150V,1A,G,SOT23-3,SMD | DIODES INCORPORATION | MMBT5401 | G | PWA BOM |  |
| 7 | U24 |  | 41050DL00-233-G | Flash,MX25L6445EMI-10G,2.7~3.6V,64M,SPI,G,SOP-16,SMD | MACRONIX INTERNATIONAL CO.,LTD. | MX25L6445EMI-10G | G | PWA BOM |  |
|  |  | NO | 41050DW00-396-G | Flash,S25FL064P0XMFI001,2.7~3.6V,64M,SPI,G,SO-16,SMD | SPANSION INTERNATIONAL LLC | S25FL064P0XMFI001 | G | PWA BOM |  |
|  |  | ADD | W25Q64JVSFIQ | Flash,2.7~3.6V,64M,SPI,G,SOP-16,SMD | WINBOND | W25Q64JVSFIQ |  | PWA BOM |  |
|  |  | NO | 41050SF00-233-G | Flash,MX25L6435EMI-10G,2.7~3.6V,64M,SPI,G,SOP-16,SMD | MACRONIX INTERNATIONAL CO.,LTD. | MX25L6435EMI-10G | G | PWA BOM |  |
|  |  | Delete | W25Q64JVSFIM | Flash,2.7~3.6V,64M,SPI,G,SOP-16,SMD | WINBOND | W25Q64JVSFIM |  | PWA BOM |  |
| OOOOOOOOOOOOOOOOOOOOOOOOOOOOOOOOOOOOOOOOOOOOOOOOOOOOOOOOOOOOOOOOOOOOOOOOOOOOOOOOOOOOOOOOOO | OOOOOOOOOOOOOOOOOOOOOOOOOOOOOOOOOOOOOOOOOOOOOOOOOOOOOOOOOOOOOOOOOOOOOOOOOOOOOOOOOOOOOOOOOO | OOOOOOOOOOOOOOOOOOOOOOOOOOOOOOOOOOOOOOOOOOOOOOOOOOOOOOOOOOOOOOOOOOOOOOOOOOOOOOOOOOOOOOOOOO | OOOOOOOOOOOOOOOOOOOOOOOOOOOOOOOOOOOOOOOOOOOOOOOOOOOOOOOOOOOOOOOOOOOOOOOOOOOOOOOOOOOOOOOOOO | OOOOOOOOOOOOOOOOOOOOOOOOOOOOOOOOOOOOOOOOOOOOOOOOOOOOOOOOOOOOOOOOOOOOOOOOOOOOOOOOOOOOOOOOOO | OOOOOOOOOOOOOOOOOOOOOOOOOOOOOOOOOOOOOOOOOOOOOOOOOOOOOOOOOOOOOOOOOOOOOOOOOOOOOOOOOOOOOOOOOO | OOOOOOOOOOOOOOOOOOOOOOOOOOOOOOOOOOOOOOOOOOOOOOOOOOOOOOOOOOOOOOOOOOOOOOOOOOOOOOOOOOOOOOOOOO | OOOOOOOOOOOOOOOOOOOOOOOOOOOOOOOOOOOOOOOOOOOOOOOOOOOOOOOOOOOOOOOOOOOOOOOOOOOOOOOOOOOOOOOOOO | OOOOOOOOOOOOOOOOOOOOOOOOOOOOOOOOOOOOOOOOOOOOOOOOOOOOOOOOOOOOOOOOOOOOOOOOOOOOOOOOOOOOOOOOOO | OOOOOOOOOOOOOOOOOOOOOOOOOOOOOOOOOOOOOOOOOOOOOOOOOOOOOOOOOOOOOOOOOOOOOOOOOOOOOOOOOOOOOOOOOO |
| Master Materials Change |  |  |  |  |  |  |  |  |  |
| Item | Foxconn P/N | Orig._Usage | New_Usage | Part Description | Manufacturer Full Name | Manufacturer P/N | RoHS | Location | Sheet |
| OOOOOOOOOOOOOOOOOOOOOOOOOOOOOOOOOOOOOOOOOOOOOOOOOOOOOOOOOOOOOOOOOOOOOOOOOOOOOOOOOOOOOOOOOO | OOOOOOOOOOOOOOOOOOOOOOOOOOOOOOOOOOOOOOOOOOOOOOOOOOOOOOOOOOOOOOOOOOOOOOOOOOOOOOOOOOOOOOOOOO | OOOOOOOOOOOOOOOOOOOOOOOOOOOOOOOOOOOOOOOOOOOOOOOOOOOOOOOOOOOOOOOOOOOOOOOOOOOOOOOOOOOOOOOOOO | OOOOOOOOOOOOOOOOOOOOOOOOOOOOOOOOOOOOOOOOOOOOOOOOOOOOOOOOOOOOOOOOOOOOOOOOOOOOOOOOOOOOOOOOOO | OOOOOOOOOOOOOOOOOOOOOOOOOOOOOOOOOOOOOOOOOOOOOOOOOOOOOOOOOOOOOOOOOOOOOOOOOOOOOOOOOOOOOOOOOO | OOOOOOOOOOOOOOOOOOOOOOOOOOOOOOOOOOOOOOOOOOOOOOOOOOOOOOOOOOOOOOOOOOOOOOOOOOOOOOOOOOOOOOOOOO | OOOOOOOOOOOOOOOOOOOOOOOOOOOOOOOOOOOOOOOOOOOOOOOOOOOOOOOOOOOOOOOOOOOOOOOOOOOOOOOOOOOOOOOOOO | OOOOOOOOOOOOOOOOOOOOOOOOOOOOOOOOOOOOOOOOOOOOOOOOOOOOOOOOOOOOOOOOOOOOOOOOOOOOOOOOOOOOOOOOOO | OOOOOOOOOOOOOOOOOOOOOOOOOOOOOOOOOOOOOOOOOOOOOOOOOOOOOOOOOOOOOOOOOOOOOOOOOOOOOOOOOOOOOOOOOO | OOOOOOOOOOOOOOOOOOOOOOOOOOOOOOOOOOOOOOOOOOOOOOOOOOOOOOOOOOOOOOOOOOOOOOOOOOOOOOOOOOOOOOOOOO |
| TLA Parts Change |  |  |  |  |  |  |  |  |  |
| Item | Foxconn P/N | Qty | Part Description | Manufacturer Full Name | Manufacturer P/N | RoHS | Location | Remark | BOM |
| BOM Change List Date:Tue Jun 13 19:13:07 CST 2017 |  |  |  |  |  |  |  |  |  |
| New BOM file : C:\<user>\BG2 0609.xls |  |  |  |  |  |  |  |  |  |
| Old BOM file : C:\<user>\BG2 0605.xls |  |  |  |  |  |  |  |  |  |
| ##### Add Parts |  |  |  |  |  |  |  |  |  |
| Item | Location | Qty | Foxconn P/N | Part Description | Manufacturer Full Name | Manufacturer P/N | RoHS | Sheet |  |
| ##### Remove Parts |  |  |  |  |  |  |  |  |  |
| Item | Location | Qty | Foxconn P/N | Part Description | Manufacturer Full Name | Manufacturer P/N | RoHS | Sheet |  |
| ##### Change Parts |  |  |  |  |  |  |  |  |  |
| Item | Location | Qty | Foxconn P/N | Part Description | Manufacturer Full Name | Manufacturer P/N | RoHS | Sheet | Remark |
| 1 | X2 | 1 | 71010SY00-107-G | XTAL,25MHz,+/-30ppm,20pF,G,SMD | DAISHINKU CORPORATION/DAISHINKU SINGAPORE PTE LTD/KDS | 1Y725000CC1G | G | PWA BOM | In New BOM |
|  |  |  | CX5032GA25000R0KDQZ1 | XTAL,25MHz,+/-30ppm,20pF,G,SMD-2P | Kyocera | CX5032GA25000R0KDQZ1 | G | PWA BOM | In New BOM |
|  | X2 | 1 | 71010SY00-107-G | XTAL,25MHz,+/-30ppm,20pF,G,SMD | DAISHINKU CORPORATION/DAISHINKU SINGAPORE PTE LTD/KDS | 1Y725000CC1G | G | PWA BOM | In Old BOM |
|  |  |  | 71010V100-100-G | XTAL,25MHz,+/-30ppm,20pF,G,SMD-2P | TXC CORPORATION | 7A25000058 | G | PWA BOM | In Old BOM |
| 2 | X3 | 1 | 710113800-100-G | XTAL,24MHz,+/-30ppm,20pF,G,SMD | TXC CORPORATION | 7B24000038 | G | PWA BOM | In New BOM |
|  |  |  | CX5032SB24000R0KZQ01 | XTAL,24MHz,+/-30ppm,20pF,G,SMD | Kyocera | CX5032SB24000R0KZQ01 |  | PWA BOM | In New BOM |
|  | X3 | 1 | 710113800-100-G | XTAL,24MHz,+/-30ppm,20pF,G,SMD | TXC CORPORATION | 7B24000038 | G | PWA BOM | In Old BOM |
| 3 | Y4 | 1 | 71020KL00-100-G | OSC,33MHz,+/-50ppm,3.3V,15pF,G,SMD | TXC CORPORATION | 7X33000013 | G | PWA BOM | In New BOM |
|  |  |  | 710211800-967-G | OSC,33MHz,+/-50ppm,3.3V,15pF,G,SMD | eCERA | FK3300011 | G | PWA BOM | In New BOM |
|  |  |  | KC3225K33.0000C10E00 | OSC,33MHz,+/-50ppm,3.3V,15pF,G,SMD | Kyocera | KC3225K33.0000C10E00 | G | PWA BOM | In New BOM |
|  | Y4 | 1 | 71020KL00-100-G | OSC,33MHz,+/-50ppm,3.3V,15pF,G,SMD | TXC CORPORATION | 7X33000013 | G | PWA BOM | In Old BOM |
|  |  |  | 710211800-967-G | OSC,33MHz,+/-50ppm,3.3V,15pF,,-40℃~85℃,SMD,G | eCERA | FK3300011 | G | PWA BOM | In Old BOM |
|  |  |  | SSW033000I3CH-SR5 | OSC,33MHz,+/-50ppm,3.3V,15pF,,-40℃~85℃,SMD,G | HARMONY | SSW033000I3CH-SR5 | G | PWA BOM | In Old BOM |
| ##### Change Revision |  |  |  |  |  |  |  |  |  |
| Sheet | REV OF BOM | CUSTOMER | CUSTOMER P/N | PWA PN | PWA DESCRIPTION | PWA REV | DATE | Remark |  |
| OOOOOOOOOOOOOOOOOOOOOOOOOOOOOOOOOOOOOOOOOOOOOOOOOOOOOOOOOOOOOOOOOOOOOOOOOOOOOOOOOOOOOOOOOO | OOOOOOOOOOOOOOOOOOOOOOOOOOOOOOOOOOOOOOOOOOOOOOOOOOOOOOOOOOOOOOOOOOOOOOOOOOOOOOOOOOOOOOOOOO | OOOOOOOOOOOOOOOOOOOOOOOOOOOOOOOOOOOOOOOOOOOOOOOOOOOOOOOOOOOOOOOOOOOOOOOOOOOOOOOOOOOOOOOOOO | OOOOOOOOOOOOOOOOOOOOOOOOOOOOOOOOOOOOOOOOOOOOOOOOOOOOOOOOOOOOOOOOOOOOOOOOOOOOOOOOOOOOOOOOOO | OOOOOOOOOOOOOOOOOOOOOOOOOOOOOOOOOOOOOOOOOOOOOOOOOOOOOOOOOOOOOOOOOOOOOOOOOOOOOOOOOOOOOOOOOO | OOOOOOOOOOOOOOOOOOOOOOOOOOOOOOOOOOOOOOOOOOOOOOOOOOOOOOOOOOOOOOOOOOOOOOOOOOOOOOOOOOOOOOOOOO | OOOOOOOOOOOOOOOOOOOOOOOOOOOOOOOOOOOOOOOOOOOOOOOOOOOOOOOOOOOOOOOOOOOOOOOOOOOOOOOOOOOOOOOOOO | OOOOOOOOOOOOOOOOOOOOOOOOOOOOOOOOOOOOOOOOOOOOOOOOOOOOOOOOOOOOOOOOOOOOOOOOOOOOOOOOOOOOOOOOOO | OOOOOOOOOOOOOOOOOOOOOOOOOOOOOOOOOOOOOOOOOOOOOOOOOOOOOOOOOOOOOOOOOOOOOOOOOOOOOOOOOOOOOOOOOO | OOOOOOOOOOOOOOOOOOOOOOOOOOOOOOOOOOOOOOOOOOOOOOOOOOOOOOOOOOOOOOOOOOOOOOOOOOOOOOOOOOOOOOOOOO |
| Second Source Change |  |  |  |  |  |  |  |  |  |
| Item | Location | Change Type | Foxconn P/N | Part Description | Manufacturer Full Name | Manufacturer P/N | RoHS | Sheet |  |
| 1 | X2 |  | 71010SY00-107-G | XTAL,25MHz,+/-30ppm,20pF,G,SMD | DAISHINKU CORPORATION/DAISHINKU SINGAPORE PTE LTD/KDS | 1Y725000CC1G | G | PWA BOM |  |
|  |  | ADD | CX5032GA25000R0KDQZ1 | XTAL,25MHz,+/-30ppm,20pF,G,SMD-2P | Kyocera | CX5032GA25000R0KDQZ1 | G | PWA BOM |  |
|  |  | Delete | 71010V100-100-G | XTAL,25MHz,+/-30ppm,20pF,G,SMD-2P | TXC CORPORATION | 7A25000058 | G | PWA BOM |  |
| 2 | X3 |  | 710113800-100-G | XTAL,24MHz,+/-30ppm,20pF,G,SMD | TXC CORPORATION | 7B24000038 | G | PWA BOM |  |
|  |  | ADD | CX5032SB24000R0KZQ01 | XTAL,24MHz,+/-30ppm,20pF,G,SMD | Kyocera | CX5032SB24000R0KZQ01 |  | PWA BOM |  |
| OOOOOOOOOOOOOOOOOOOOOOOOOOOOOOOOOOOOOOOOOOOOOOOOOOOOOOOOOOOOOOOOOOOOOOOOOOOOOOOOOOOOOOOOOO | OOOOOOOOOOOOOOOOOOOOOOOOOOOOOOOOOOOOOOOOOOOOOOOOOOOOOOOOOOOOOOOOOOOOOOOOOOOOOOOOOOOOOOOOOO | OOOOOOOOOOOOOOOOOOOOOOOOOOOOOOOOOOOOOOOOOOOOOOOOOOOOOOOOOOOOOOOOOOOOOOOOOOOOOOOOOOOOOOOOOO | OOOOOOOOOOOOOOOOOOOOOOOOOOOOOOOOOOOOOOOOOOOOOOOOOOOOOOOOOOOOOOOOOOOOOOOOOOOOOOOOOOOOOOOOOO | OOOOOOOOOOOOOOOOOOOOOOOOOOOOOOOOOOOOOOOOOOOOOOOOOOOOOOOOOOOOOOOOOOOOOOOOOOOOOOOOOOOOOOOOOO | OOOOOOOOOOOOOOOOOOOOOOOOOOOOOOOOOOOOOOOOOOOOOOOOOOOOOOOOOOOOOOOOOOOOOOOOOOOOOOOOOOOOOOOOOO | OOOOOOOOOOOOOOOOOOOOOOOOOOOOOOOOOOOOOOOOOOOOOOOOOOOOOOOOOOOOOOOOOOOOOOOOOOOOOOOOOOOOOOOOOO | OOOOOOOOOOOOOOOOOOOOOOOOOOOOOOOOOOOOOOOOOOOOOOOOOOOOOOOOOOOOOOOOOOOOOOOOOOOOOOOOOOOOOOOOOO | OOOOOOOOOOOOOOOOOOOOOOOOOOOOOOOOOOOOOOOOOOOOOOOOOOOOOOOOOOOOOOOOOOOOOOOOOOOOOOOOOOOOOOOOOO | OOOOOOOOOOOOOOOOOOOOOOOOOOOOOOOOOOOOOOOOOOOOOOOOOOOOOOOOOOOOOOOOOOOOOOOOOOOOOOOOOOOOOOOOOO |
| Master Materials Change |  |  |  |  |  |  |  |  |  |
| Item | Foxconn P/N | Orig._Usage | New_Usage | Part Description | Manufacturer Full Name | Manufacturer P/N | RoHS | Location | Sheet |
| OOOOOOOOOOOOOOOOOOOOOOOOOOOOOOOOOOOOOOOOOOOOOOOOOOOOOOOOOOOOOOOOOOOOOOOOOOOOOOOOOOOOOOOOOO | OOOOOOOOOOOOOOOOOOOOOOOOOOOOOOOOOOOOOOOOOOOOOOOOOOOOOOOOOOOOOOOOOOOOOOOOOOOOOOOOOOOOOOOOOO | OOOOOOOOOOOOOOOOOOOOOOOOOOOOOOOOOOOOOOOOOOOOOOOOOOOOOOOOOOOOOOOOOOOOOOOOOOOOOOOOOOOOOOOOOO | OOOOOOOOOOOOOOOOOOOOOOOOOOOOOOOOOOOOOOOOOOOOOOOOOOOOOOOOOOOOOOOOOOOOOOOOOOOOOOOOOOOOOOOOOO | OOOOOOOOOOOOOOOOOOOOOOOOOOOOOOOOOOOOOOOOOOOOOOOOOOOOOOOOOOOOOOOOOOOOOOOOOOOOOOOOOOOOOOOOOO | OOOOOOOOOOOOOOOOOOOOOOOOOOOOOOOOOOOOOOOOOOOOOOOOOOOOOOOOOOOOOOOOOOOOOOOOOOOOOOOOOOOOOOOOOO | OOOOOOOOOOOOOOOOOOOOOOOOOOOOOOOOOOOOOOOOOOOOOOOOOOOOOOOOOOOOOOOOOOOOOOOOOOOOOOOOOOOOOOOOOO | OOOOOOOOOOOOOOOOOOOOOOOOOOOOOOOOOOOOOOOOOOOOOOOOOOOOOOOOOOOOOOOOOOOOOOOOOOOOOOOOOOOOOOOOOO | OOOOOOOOOOOOOOOOOOOOOOOOOOOOOOOOOOOOOOOOOOOOOOOOOOOOOOOOOOOOOOOOOOOOOOOOOOOOOOOOOOOOOOOOOO | OOOOOOOOOOOOOOOOOOOOOOOOOOOOOOOOOOOOOOOOOOOOOOOOOOOOOOOOOOOOOOOOOOOOOOOOOOOOOOOOOOOOOOOOOO |
| TLA Parts Change |  |  |  |  |  |  |  |  |  |
| Item | Foxconn P/N | Qty | Part Description | Manufacturer Full Name | Manufacturer P/N | RoHS | Location | Remark | BOM |
| BOM Change List Date:Tue Jun 13 19:06:12 CST 2017 |  |  |  |  |  |  |  |  |  |
| New BOM file : C:\<user>\BG2 0613.xls |  |  |  |  |  |  |  |  |  |
| Old BOM file : C:\<user>\BG2 0609.xls |  |  |  |  |  |  |  |  |  |
| ##### Add Parts |  |  |  |  |  |  |  |  |  |
| Item | Location | Qty | Foxconn P/N | Part Description | Manufacturer Full Name | Manufacturer P/N | RoHS | Sheet |  |
| ##### Remove Parts |  |  |  |  |  |  |  |  |  |
| Item | Location | Qty | Foxconn P/N | Part Description | Manufacturer Full Name | Manufacturer P/N | RoHS | Sheet |  |
| ##### Change Parts |  |  |  |  |  |  |  |  |  |
| Item | Location | Qty | Foxconn P/N | Part Description | Manufacturer Full Name | Manufacturer P/N | RoHS | Sheet | Remark |
| 1 | BAT1 | 1 | 890100800-024-G | Battery,PANASONIC,CR-2032L/BE,Lithium,3V,225mAH,G | PANASONIC INDUSTRIAL CO.,LTD. | CR-2032L/BE | G | PWA BOM | In New BOM |
|  |  |  | 6032-101-501 | Battery,VARTA,CR-2032,Lithium,3V,230mAH,G | Varta | 6032-101-501 | G | PWA BOM | In New BOM |
|  | BAT1 | 1 | 890100800-024-G | Battery,PANASONIC,CR-2032L/BE,Lithium,3V,225mAH,G | PANASONIC INDUSTRIAL CO.,LTD. | CR-2032L/BE | G | PWA BOM | In Old BOM |
|  |  |  | 6032-101-501 | Battery,6032-101-501 | Varta | 6032-101-501 | G | PWA BOM | In Old BOM |
| 2 | LED2,LED6 | 2 | 52111AE00-289-G | LED,Ora,LTST-C281KFKT-5A,5V,30mA,G,SMD0402 | LITE-ON TECHNOLOGY CORPORATION | LTST-C281KFKT-5A | G | PWA BOM | In New BOM |
|  |  |  | 52113GM00-290-G | LED LAMP,B1851UD--05D-000214,Orange,28.5mcd@IF=20mA,605nm,5V,20mA,N/A,,SMD0402,2P,G | HARVATEK CORPORATION | B1851UD--05D-000214 | G | PWA BOM | In New BOM |
|  | LED2,LED6 | 2 | 52111AE00-289-G | LED,Ora,LTST-C281KFKT-5A,5V,30mA,G,SMD0402 | LITE-ON TECHNOLOGY CORPORATION | LTST-C281KFKT-5A | G | PWA BOM | In Old BOM |
|  |  |  | 52113GM00-290-G | LED LAMP,B1851UD--05D-000214,Orange,28.5mcd@IF=20mA,605nm,5V,20mA,N/A,,SMD0402,2P,G | HARVATEK | B1851UD--05D-000214 | G | PWA BOM | In Old BOM |
| 3 | LED3,LED7 | 2 | 52111J100-289-G | LED,Gre,LTST-C281KGKT-5A,2.3V,30mA,G,SMD0402 | LITE-ON TECHNOLOGY CORPORATION | LTST-C281KGKT-5A | G | PWA BOM | In New BOM |
|  |  |  | 52113AE00-290-G | LED LAMP,B1851UYG-05D-000114,Ultra Bright Yellow Green,11.25mcd@IF=5mA,571nm,5V,20mA,N/A,,SMD0402,2P,G | HARVATEK CORPORATION | B1851UYG-05D-000114 | G | PWA BOM | In New BOM |
|  | LED3,LED7 | 2 | 52111J100-289-G | LED,Gre,LTST-C281KGKT-5A,2.3V,30mA,G,SMD0402 | LITE-ON TECHNOLOGY CORPORATION | LTST-C281KGKT-5A | G | PWA BOM | In Old BOM |
|  |  |  | 52113AE00-290-G | LED LAMP,B1851UYG-05D-000114,Ultra Bright Yellow Green,11.25mcd@IF=5mA,571nm,5V,20mA,N/A,,SMD0402,2P,G | HARVATEK | B1851UYG-05D-000114 | G | PWA BOM | In Old BOM |
| 4 | L22,L23,L24,L25 | 4 | 720105P00-016-G | FB,80 Ohm@100MHz,+/-25%,500mA,150mOhm,G,SMD0603 | TDK ELECTRONICS EUROPE GMBH | MMZ1608S800AT | G | PWA BOM | In New BOM |
|  |  |  | 72010WQ00-129-G | FB,Multilayer,40mOhm,80Ohm@100MHz,+/-25%,3A,,SMD0603,G | MAG.LAYERS, SCIENTIFIC-TECHNICS (KUNSHAN) CO., LTD. | GMLB-160808-0080P-N8 | G | PWA BOM | In New BOM |
|  | L22,L23,L24,L25 | 4 | 720105P00-016-G | FB,80 Ohm@100MHz,+/-25%,500mA,150mOhm,G,SMD0603 | TDK ELECTRONICS EUROPE GMBH | MMZ1608S800AT | G | PWA BOM | In Old BOM |
|  |  |  | 72010WQ00-129-G | FB,80 Ohm@100MHz,+/-25%,3A,0.04Ohm,G,SMD0603 | MAG.LAYERS, SCIENTIFIC-TECHNICS (KUNSHAN) CO., LTD. | GMLB-160808-0080P-N8 | G | PWA BOM | In Old BOM |
| 5 | PBMQ10,PBAQ10,PAMQ10,PAAQ10,PBFQ11,PBEQ11,PAFQ11,PAEQ11 | 8 | 51032DL00-237-G | MOS N,DMT10H014LSS-13,100V,8.9A,15m@10V,G,SO-8,SMD | DIODES INCORPORATION | DMT10H014LSS-13 | G | PWA BOM | In New BOM |
|  |  |  | Si4190ADY-T1-GE3 | MOS N,Si4190ADY-T1-GE3,100V,18.4A,8.8m@10V,G,SO-8,SMD | VISHAY ENTER TECHNO LOGY.INC | Si4190ADY-T1-GE3 | G | PWA BOM | In New BOM |
|  | PBMQ10,PBAQ10,PAMQ10,PAAQ10,PBFQ11,PBEQ11,PAFQ11,PAEQ11 | 8 | 51032DL00-237-G | MOS N,DMT10H014LSS-13,100V,8.9A,15m@10V,G,SO-8,SMD | DIODES INCORPORATION | DMT10H014LSS-13 | G | PWA BOM | In Old BOM |
|  |  |  | Si4190ADY-T1-GE3 | Si4190ADY-T1-GE3 | VISHAY ENTER TECHNO LOGY.INC | Si4190ADY-T1-GE3 | G | PWA BOM | In Old BOM |
| 6 | PBFL1,PBEL1,PAFL1,PAEL1,PBML2,PAML2 | 6 | 63035NF00-57M-G | IND,1.5uH@100KHz,+/-10%,12A,6mOhm,SHLD,G,SMD | Eaton Corporation | HCV1206-1R5-R | G | PWA BOM | In New BOM |
|  |  |  | HMS1360-1R5 | IND,1.5uH@100KHz,+/-10%,12A,6mOhm,SHLD,G,SMD | DELTA ELECTRONICS INDUSTRIAL CO.,LTD | HMS1360-1R5 | G | PWA BOM | In New BOM |
|  | PBFL1,PBEL1,PAFL1,PAEL1,PBML2,PAML2 | 6 | 63035NF00-57M-G | IND,1.5uH@100KHz,+/-10%,12A,6mOhm,SHLD,G,SMD | Eaton Corporation | HCV1206-1R5-R | G | PWA BOM | In Old BOM |
|  |  |  | HMS1360-1R5 | IND,HMS1360-1R5 | DELTA ELECTRONICS INDUSTRIAL CO.,LTD | HMS1360-1R5 | G | PWA BOM | In Old BOM |
| 7 | PBNL1,PANL1 | 2 | 630330G00-088-G | IND,300nH@100KHz,+/-10%,32.5A,304.5uOhm,SHLD,G,SMD | COOPER BUSSMANN, INC. | FP0906R1-R30-R | G | PWA BOM | In New BOM |
|  |  |  | 630332A01-051-G | Coil Ind,Shielded(SHLD),300nH@100KHz,+/-10%,33A,304.5uOhm,SMD,9.2*6.2*7.8,G | PULSE ELECTRONICS (SINGAPORE) | PA3288.301HLT | G | PWA BOM | In New BOM |
|  |  |  | MSI-900608-R30K-E | IND,300nH@100KHz,+/-10%,32.5A,290uOhm,SHLD,G,SMD | MAG.LAYERS, SCIENTIFIC-TECHNICS (KUNSHAN) CO., LTD. | MSI-900608-R30K-E | G | PWA BOM | In New BOM |
|  | PBNL1,PANL1 | 2 | 630330G00-088-G | IND,300nH@100KHz,+/-10%,32.5A,304.5uOhm,SHLD,G,SMD | COOPER BUSSMANN, INC. | FP0906R1-R30-R | G | PWA BOM | In Old BOM |
|  |  |  | 630332A01-051-G | Coil Ind,Shielded(SHLD),300nH@100KHz,+/-10%,33A,304.5uOhm,SMD,9.2*6.2*7.8,G | PULSE ELECTRONICS (SINGAPORE) | PA3288.301HLT | G | PWA BOM | In Old BOM |
|  |  |  | MSI-900608-R30K-E | IND,MSI-900608-R30K-E | MAG.LAYERS, SCIENTIFIC-TECHNICS (KUNSHAN) CO., LTD. | MSI-900608-R30K-E | G | PWA BOM | In Old BOM |
| 8 | PSPL2,PIPL2,PFPL2,PEPL2 | 4 | 630341400-088-G | IND,22nH@1MHz,+/-20%,19A,368uOhm,SHLD,G,SMD | COOPER BUSSMANN, INC. | FP0404R1-R022-R | G | PWA BOM | In New BOM |
|  |  |  | HCB0430-220 | IND,22nH@1MHz,+/-20%,19A,320uOhm,SHLD,G,SMD | DELTA ELECTRONICS INDUSTRIAL CO.,LTD | HCB0430-220 | G | PWA BOM | In New BOM |
|  | PSPL2,PIPL2,PFPL2,PEPL2 | 4 | 630341400-088-G | IND,22nH@1MHz,+/-20%,19A,368uOhm,SHLD,G,SMD | COOPER BUSSMANN, INC. | FP0404R1-R022-R | G | PWA BOM | In Old BOM |
|  |  |  | HCB0430-220 | IND,HCB0430-220 | DELTA ELECTRONICS INDUSTRIAL CO.,LTD | HCB0430-220 | G | PWA BOM | In Old BOM |
| 9 | PHAD3 | 1 | 52040EC00-237-G | DIODE,Zener,MMSZ5246B-7-F,16V,7.8mA,G,SOD123-2,SMD | DIODES INEORPORATION | MMSZ5246B-7-F | G | PWA BOM | In New BOM |
|  |  |  | 52040B500-223-G | DIODE,Zener,MMSZ5246BT1G,16V,7.8mA,G,SOD123-2,SMD | ON SEMICONDUCTOR CORP | MMSZ5246BT1G | G | PWA BOM | In New BOM |
|  |  |  | 52040EY00-031-G | Diode,ZENER,BZT52H-C16,17.1V,5mA,G,SOD123F-2,SMD | NXP SEMICONDUCTORS | BZT52H-C16 | G | PWA BOM | In New BOM |
|  | PHAD3 | 1 | 52040EC00-237-G | DIODE,Zener,MMSZ5246B-7-F,16V,7.8mA,G,SOD123-2,SMD | DIODES INEORPORATION | MMSZ5246B-7-F | G | PWA BOM | In Old BOM |
|  |  |  | 52040B500-223-G | DIODE,Zener,MMSZ5246BT1G,16V,7.8mA,G,SOD123-2,SMD | ON | MMSZ5246BT1G | G | PWA BOM | In Old BOM |
|  |  |  | 52040EY00-031-G | Diode,ZENER,BZT52H-C16,17.1V,5mA,G,SOD123F-2,SMD | NXP SEMICONDUCTORS | BZT52H-C16 | G | PWA BOM | In Old BOM |
| 10 | PHAQ1,PHAQ2,PHAQ3 | 3 | 51031VY00-031-G | MOS N,PSMN4R8-100BSE,100V,120A,4.8m@10V,G,SOT404-3,SMD | NXP SEMICONDUCTORS | PSMN4R8-100BSE | G | PWA BOM | In New BOM |
|  |  |  | FDB047N10 | MOS N,FDB047N10,100V,120A,3.9m@10V,G,TO263-3,SMD | FAIRCHILD SEMICONDUCTOR CORP | FDB047N10 | G | PWA BOM | In New BOM |
|  |  |  | SUM70040E-GE3 | MOS N,SUM70040E-GE3,100V,120A,4.0m@10V,G,TO263-3,SMD | VISHAY ENTER TECHNO LOGY.INC | SUM70040E-GE3 | G | PWA BOM | In New BOM |
|  | PHAQ1,PHAQ2,PHAQ3 | 3 | 51031VY00-031-G | MOS N,PSMN4R8-100BSE,100V,120A,4.8m@10V,G,SOT404-3,SMD | NXP SEMICONDUCTORS | PSMN4R8-100BSE | G | PWA BOM | In Old BOM |
|  |  |  | SUM70040E-GE3 | MOS N,SUM70040E-GE3 | VISHAY ENTER TECHNO LOGY.INC | SUM70040E-GE3 | G | PWA BOM | In Old BOM |
|  |  |  | FDB047N10 | MOS N,FDB047N10 | FAIRCHILD SEMICONDUCTOR CORP | FDB047N10 | G | PWA BOM | In Old BOM |
| 11 | QN2,QN3 | 2 | 510503B00-223-G | MOS N/N,NTZD3154NT1G,20V,0.54A,550m24.5V,G,SOT563-6,SMD | ON SEMICONDUCTOR CORP | NTZD3154NT1G | G | PWA BOM | In New BOM |
|  |  |  | Si1034CX-T1-GE3 | MOS N/N,Si1034CX,20V,0.5A,1ohm@4V,G,EMT-6,SMD | VISHAY ENTER TECHNO LOGY.INC | Si1034CX-T1-GE3 | G | PWA BOM | In New BOM |
|  |  |  | SSM6N36FE | MOS N/N,20V,0.54A,550m24.5V,G,SOT563-6,SMD | TOSHIBA ELECTRONICS ASIA LTD | SSM6N36FE | G | PWA BOM | In New BOM |
|  | QN2,QN3 | 2 | 510503B00-223-G | MOS N/N,NTZD3154NT1G,20V,0.54A,550m24.5V,G,SOT563-6,SMD | ON SEMICONDUCTOR CORP | NTZD3154NT1G | G | PWA BOM | In Old BOM |
|  |  |  | Si1034CX-T1-GE3 | MOS N/N,Si1034CX-T1-GE3 | VISHAY ENTER TECHNO LOGY.INC | Si1034CX-T1-GE3 | G | PWA BOM | In Old BOM |
|  |  |  | SSM6N36FE | MOS N/N,SSM6N36FE | TOSHIBA ELECTRONICS ASIA LTD | SSM6N36FE | G | PWA BOM | In Old BOM |
| 12 | R1092,R1093,R1114,R1115 | 4 | 61100QH00-017-G | RES,510 Ohm,+/-0.1%,1/16W,G,SMD0402 | KOA SPEER ELECTRONICS, INC. | RN731ETTP5100B25 | G | PWA BOM | In New BOM |
|  |  |  | 61100QH00-012-G | RES,510 Ohm,+/-0.1%,1/16W,G,SMD0402 | WALSIN TECHNOLOGY CORPORATION | WF04U5100BTL | G | PWA BOM | In New BOM |
|  |  |  | 61100QH00-011-G | RES,510 Ohm,+/-0.1%,1/16W,G,SMD0402 | YAGEO CORPORATION COMPONENT | RT0402BRD07510RL | G | PWA BOM | In New BOM |
|  | R1092,R1093,R1114,R1115 | 4 | 61100QH00-017-G | RES,510 Ohm,+/-0.1%,1/16W,G,SMD0402 | KOA SPEER ELECTRONICS, INC. | RN731ETTP5100B25 | G | PWA BOM | In Old BOM |
|  |  |  | 61100QH00-012-G | RES,510 Ohm,+/-0.1%,1/16W,G,SMD0402 | WALSIN TECHNOLOGY CORPORATION | WF04U5100BTL | G | PWA BOM | In Old BOM |
|  |  |  | 61100QH00-011-G | RES,510 Ohm,+/-0.1%,1/16W,G,SMD0402 | YAGEO CORPORATION COMPONENT | RT0402BRD07510RL | G | PWA BOM | In Old BOM |
|  |  |  | 61100QH00-044-G | RES,510 Ohm,+/-0.1%,1/16W,G,SMD0402 | TA-I TECHNOLOGY CO., LTD | RB04BTP5100 | G | PWA BOM | In Old BOM |
| 13 | U29 | 1 | 21050F900-217-G | IC,IDT,2305B-1DCG8,B,G,SOIC-8,SMD | INTEGRATED DEVICE TECHNOLOGY | 2305B-1DCG8 | G | PWA BOM | In New BOM |
|  |  |  | 31050JC00-223-G | Logic IC,Buffer,NB2305AI1DR2G,3.0V~3.6V,0.35ns,SOIC,8P,G | ON SEMICONDUCTOR CORP | NB2305AI1DR2G | G | PWA BOM | In New BOM |
|  | U29 | 1 | 21050F900-217-G | IC,IDT,2305B-1DCG8,B,G,SOIC-8,SMD | INTEGRATED DEVICE TECHNOLOGY | 2305B-1DCG8 | G | PWA BOM | In Old BOM |
|  |  |  | 31050JC00-223-G | Logic IC,Buffer,NB2305AI1DR2G,3.0V~3.6V,0.35ns,SOIC,8P,G | ON SEMICONDUCTOR CORP | NB2305AI1DR2G | G | PWA BOM | In Old BOM |
|  |  |  | SL2305SC-1 | IC,IDT,2305B-1DCG8,B,G,SOIC-8,SMD | Silicon Laboratories Inc. | SL2305SC-1 | G | PWA BOM | In Old BOM |
| 14 | U37 | 1 | 41050J100-233-G | Flash,MX25L5121EMC-20G,2.7~3.6V,512K,SPI,G,SOP-8,SMD | MACRONIX INTERNATIONAL CO.,LTD. | MX25L5121EMC-20G | G | PWA BOM | In New BOM |
|  | U37 | 1 | 41050J100-233-G | Flash,MX25L5121EMC-20G,2.7~3.6V,512K,SPI,G,SOP-8,SMD | MACRONIX INTERNATIONAL CO.,LTD. | MX25L5121EMC-20G | G | PWA BOM | In Old BOM |
|  |  |  | 41050YB00-36F-G | NOR Flash,GD25D05BTIG,2.7V,N/A,3.6V,512K,SPI,-40_x0003_~85_x0003_,SOP,8P,G | GIGADEVICE | GD25D05BTIG | G | PWA BOM | In Old BOM |
| 15 | U46 | 1 | 41050K700-233-G | Flash,MX25L4006EM2I-12G,2.7V~3.6V,4M,SPI,G,SOP-8,SMD | MACRONIX INTERNATIONAL CO.,LTD. | MX25L4006EM2I-12G | G | PWA BOM | In New BOM |
|  |  |  | 41050RL00-205-G | NOR Flash,W25X40CLSSIG,2.3V,N/A,3.6V,4M,SPI,-40_x0003_~85_x0003_,SOIC,8P,G | WINBOND ELECTRONIC CO.,LTD. | W25X40CLSSIG | G | PWA BOM | In New BOM |
|  | U46 | 1 | 41050K700-233-G | Flash,MX25L4006EM2I-12G,2.7V~3.6V,4M,SPI,G,SOP-8,SMD | MACRONIX INTERNATIONAL CO.,LTD. | MX25L4006EM2I-12G | G | PWA BOM | In Old BOM |
|  |  |  | 41050RL00-205-G | NOR Flash,W25X40CLSSIG,2.3V,N/A,3.6V,4M,SPI,-40_x0003_~85_x0003_,SOIC,8P,G | WINBOND | W25X40CLSSIG | G | PWA BOM | In Old BOM |
| 16 | U61 | 1 | 21050Q600-217-G | IC,IDT,5PB1102PGGI8,G,TSSOP-8,SMD | INTEGRATED DEVICE TECHNOLOGY | 5PB1102PGGI8 | G | PWA BOM | In New BOM |
|  |  |  | 31050JY00-223-G | Logic IC,Buffer,NB3V1102CDTR2G,1.8V/2.5V/3.3V,3.5ns,TSSOP,8P,G | ON SEMICONDUCTOR CORP | NB3V1102CDTR2G | G | PWA BOM | In New BOM |
|  | U61 | 1 | 21050Q600-217-G | IC,IDT,5PB1102PGGI8,G,TSSOP-8,SMD | INTEGRATED DEVICE TECHNOLOGY | 5PB1102PGGI8 | G | PWA BOM | In Old BOM |
|  |  |  | 31050JY00-223-G | Logic IC,Buffer,NB3V1102CDTR2G,1.8V/2.5V/3.3V,3.5ns,TSSOP,8P,G | ON | NB3V1102CDTR2G | G | PWA BOM | In Old BOM |
| 17 | U171 | 1 | 31050KL00-031-G | IC,Buffer,74HC75PW,2.0V~6.0V,G,TSSOP-16,SMD | NXP SEMICONDUCTORS | 74HC75PW | G | PWA BOM | In New BOM |
|  |  |  | CD74HC75PWRG4 | IC,Buffer,CD74HC75PWRG4,2.0V~6.0V,G,TSSOP-16,SMD | Texas Instruments | CD74HC75PWRG4 | G | PWA BOM | In New BOM |
|  | U171 | 1 | 31050KL00-031-G | IC,Buffer,74HC75PW,2.0V~6.0V,G,TSSOP-16,SMD | NXP SEMICONDUCTORS | 74HC75PW | G | PWA BOM | In Old BOM |
|  |  |  | CD74HC75PWRG4 | IC,Buffer,CD74HC75PWRG4 | Texas Instruments | CD74HC75PWRG4 | G | PWA BOM | In Old BOM |
| 18 | X2 | 1 | 71010SY00-107-G | XTAL,25MHz,+/-30ppm,20pF,G,SMD | DAISHINKU CORPORATION/DAISHINKU SINGAPORE PTE LTD/KDS | 1Y725000CC1G | G | PWA BOM | In New BOM |
|  |  |  | CX5032GA25000R0KDQ | XTAL,25MHz,+/-30ppm,20pF,G,SMD-2P | Kyocera | CX5032GA25000R0KDQZ1 | G | PWA BOM | In New BOM |
|  | X2 | 1 | 71010SY00-107-G | XTAL,25MHz,+/-30ppm,20pF,G,SMD | DAISHINKU CORPORATION/DAISHINKU SINGAPORE PTE LTD/KDS | 1Y725000CC1G | G | PWA BOM | In Old BOM |
|  |  |  | CX5032GA25000R0KDQZ1 | XTAL,25MHz,+/-30ppm,20pF,G,SMD-2P | Kyocera | CX5032GA25000R0KDQZ1 | G | PWA BOM | In Old BOM |
| 19 | X3 | 1 | 710113800-100-G | XTAL,24MHz,+/-30ppm,20pF,G,SMD | TXC CORPORATION | 7B24000038 | G | PWA BOM | In New BOM |
|  |  |  | CX5032SB24000R0KZQ | XTAL,24MHz,+/-30ppm,20pF,G,SMD | Kyocera | CX5032SB24000R0KZQ01 |  | PWA BOM | In New BOM |
|  | X3 | 1 | 710113800-100-G | XTAL,24MHz,+/-30ppm,20pF,G,SMD | TXC CORPORATION | 7B24000038 | G | PWA BOM | In Old BOM |
|  |  |  | CX5032SB24000R0KZQ01 | XTAL,24MHz,+/-30ppm,20pF,G,SMD | Kyocera | CX5032SB24000R0KZQ01 |  | PWA BOM | In Old BOM |
| 20 | X6 | 1 | 710106900-162-G | XTAL,32.768KHz,+/-20ppm,12.5pF,G,SMD | EPSON ELECTRONICS AMERICA,INC. | Q13FC1350000400 | G | PWA BOM | In New BOM |
|  |  |  | ST3215SB32768H5HPW | XTAL,32.768KHz,+/-20ppm,12.5pF,G,SMD | Kyocera | ST3215SB32768H5HPWAA | G | PWA BOM | In New BOM |
|  |  |  | 710123400-061-G | XTAL,32.768KHz,+/-20ppm,12.5pF,-40℃~85℃,SMD,G | TAITIEN | 06172-W-052-3 | G | PWA BOM | In New BOM |
|  | X6 | 1 | 710106900-162-G | XTAL,32.768KHz,+/-20ppm,12.5pF,G,SMD | EPSON ELECTRONICS AMERICA,INC. | Q13FC1350000400 | G | PWA BOM | In Old BOM |
|  |  |  | 71011P300-100-G | XTAL,32.768KHz,+/-20ppm,12.5pF,G,SMD | TXC CORPORATION | 9H03200031 | G | PWA BOM | In Old BOM |
|  |  |  | 710123400-061-G | XTAL,32.768KHz,+/-20ppm,12.5pF,-40℃~85℃,SMD,G | TAITIEN | 06172-W-052-3 | G | PWA BOM | In Old BOM |
| 21 | Y2 | 1 | 71020Q600-16G-G | OSC,50MHz,50ppm,3.3V,G,SMD | SiTime Corporation | SIT1602AC-23-33E-50.000000T | G | PWA BOM | In New BOM |
|  |  |  | 71012DA00-100-G | OSC,50MHz,+/-25ppm,15pF,G,SMD | TXC CORPORATION | 7X50000015 |  | PWA BOM | In New BOM |
|  |  |  | SSW050000I3CHE | OSC,50MHz,50ppm,3.3V,G,SMD | HARMONY (HELE) | SSW050000I3CHE-ST7R2 |  | PWA BOM | In New BOM |
|  |  |  | KC3225K50.0000C1GE | OSC,50MHz,50ppm,3.3V,G,SMD | Kyocera | KC3225K50.0000C1GE00 |  | PWA BOM | In New BOM |
|  | Y2 | 1 | 71020Q600-16G-G | OSC,50MHz,50ppm,3.3V,G,SMD | SiTime Corporation | SIT1602AC-23-33E-50.000000T | G | PWA BOM | In Old BOM |
|  |  |  | 71012DA00-100-G | OSC,50MHz,+/-25ppm,15pF,G,SMD | TXC CORPORATION | 7X50000015 | G | PWA BOM | In Old BOM |
|  |  |  | SSW050000I3CHE-ST7R2 | OSC,50MHz,+/-25ppm,15pF,G,SMD | HARMONY | SSW050000I3CHE-ST7R2 | G | PWA BOM | In Old BOM |
| 22 | Y4 | 1 | 71020KL00-100-G | OSC,33MHz,+/-50ppm,3.3V,15pF,G,SMD | TXC CORPORATION | 7X33000013 | G | PWA BOM | In New BOM |
|  |  |  | 710211800-967-G | OSC,33MHz,+/-50ppm,3.3V,15pF,G,SMD | eCERA | FK3300011 | G | PWA BOM | In New BOM |
|  |  |  | KC3225K33.0000C10E | OSC,33MHz,+/-50ppm,3.3V,15pF,G,SMD | Kyocera | KC3225K33.0000C10E00 | G | PWA BOM | In New BOM |
|  | Y4 | 1 | 71020KL00-100-G | OSC,33MHz,+/-50ppm,3.3V,15pF,G,SMD | TXC CORPORATION | 7X33000013 | G | PWA BOM | In Old BOM |
|  |  |  | 710211800-967-G | OSC,33MHz,+/-50ppm,3.3V,15pF,G,SMD | eCERA | FK3300011 | G | PWA BOM | In Old BOM |
|  |  |  | KC3225K33.0000C10E00 | OSC,33MHz,+/-50ppm,3.3V,15pF,G,SMD | Kyocera | KC3225K33.0000C10E00 | G | PWA BOM | In Old BOM |
| 23 | JP1(2-3),JP4(2-3),JP5(2-3),JP6(1-2) | 4 | 340612R00-309-G | CONN,Jumper,Bla,2.54mm,G,DIP-2 | SAMTEC INC. | SNT-100-BK-G | G | PWA BOM | In New BOM |
|  |  |  | 34065L900-GRT-G | CONN,jumper,Bla,2.54mm,30u,G,DIP-2 | PINREX TECHNOLOGY CORP. | 201-71-01DB00 | G | PWA BOM | In New BOM |
|  |  |  | 34066N500-600-G | CONN,Header,Jumper,1X2,V/T,Bla,2.54mm,G/F,G,DIP-2 | FOXCONN TECHNOLOGY CO.,LTD. | SJ0520F-A0 | G | PWA BOM | In New BOM |
|  | JP1(2-3),JP4(2-3),JP5(2-3),JP6(1-2) | 4 | 340612R00-309-G | CONN,Jumper,Bla,2.54mm,G,DIP-2 | SAMTEC INC. | SNT-100-BK-G | G | PWA BOM | In Old BOM |
|  |  |  | 34065L900-GRT-G | CONN,jumper,Bla,2.54mm,30u,G,DIP-2 | PINREX TECHNOLOGY CORP. | 201-71-01DB00 | G | PWA BOM | In Old BOM |
|  |  |  | 34066N500-600-G | Header&Socket Connector,SJ0520F-A0,Jumper,2,DIP,PBT,2.54mm,3u",Black,G | FOXCONN TECHNOLOGY CO.,LTD. | SJ0520F-A0 | G | PWA BOM | In Old BOM |
| 24 | J11 | 1 | 3406AEU00-245-G | CONN,Header,Shrouded,2X4,R/A,Bla,2.54mm,G/F,G,DIP-8 | AMPHENOL SHANGHAI CORP. | G821EU208AGN00Y | G | PWA BOM | In New BOM |
|  |  |  | 3406AYC00-GRT-G | Header&Socket Connector,511-90-08GB00,Shrouded Header,8,DIP,NY9T,2.54mm,3u",Black,G | PINREX TECHNOLOGY CORP. | 511-90-08GB00 | G | PWA BOM | In New BOM |
|  |  |  | 3406AYE00-637-G | Header&Socket Connector,3112110800-0231,Shrouded Header,8,DIP,NY6T,2.54mm,3u",Black,G | LONG SHOUNG CO.,LTD. | 3112110800-0231 | G | PWA BOM | In New BOM |
|  | J11 | 1 | 3406AEU00-245-G | CONN,Header,Shrouded,2X4,R/A,Bla,2.54mm,G/F,G,DIP-8 | AMPHENOL SHANGHAI CORP. | G821EU208AGN00Y | G | PWA BOM | In Old BOM |
|  |  |  | 3406AYC00-GRT-G | Header&Socket Connector,511-90-08GB00,Shrouded Header,8,DIP,NY9T,2.54mm,3u",Black,G | PINREX TECHNOLOGY CORP. | 511-90-08GB00 | G | PWA BOM | In Old BOM |
|  |  |  | 3406AYD00-971-G | Header&Socket Connector,C18359-10839-Y,Shrouded Header,8,DIP,LCP,2.54mm,999.9999u",Black,G | ALLTOP TECHNOLOGY CO.,LTD | C18359-10839-Y | G | PWA BOM | In Old BOM |
|  |  |  | 3406AYE00-637-G | Header&Socket Connector,3112110800-0231,Shrouded Header,8,DIP,NY6T,2.54mm,3u",Black,G | LONG SHOUNG CO.,LTD. | 3112110800-0231 | G | PWA BOM | In Old BOM |
| ##### Change Revision |  |  |  |  |  |  |  |  |  |
| Sheet | REV OF BOM | CUSTOMER | CUSTOMER P/N | PWA PN | PWA DESCRIPTION | PWA REV | DATE | Remark |  |
| OOOOOOOOOOOOOOOOOOOOOOOOOOOOOOOOOOOOOOOOOOOOOOOOOOOOOOOOOOOOOOOOOOOOOOOOOOOOOOOOOOOOOOOOOO | OOOOOOOOOOOOOOOOOOOOOOOOOOOOOOOOOOOOOOOOOOOOOOOOOOOOOOOOOOOOOOOOOOOOOOOOOOOOOOOOOOOOOOOOOO | OOOOOOOOOOOOOOOOOOOOOOOOOOOOOOOOOOOOOOOOOOOOOOOOOOOOOOOOOOOOOOOOOOOOOOOOOOOOOOOOOOOOOOOOOO | OOOOOOOOOOOOOOOOOOOOOOOOOOOOOOOOOOOOOOOOOOOOOOOOOOOOOOOOOOOOOOOOOOOOOOOOOOOOOOOOOOOOOOOOOO | OOOOOOOOOOOOOOOOOOOOOOOOOOOOOOOOOOOOOOOOOOOOOOOOOOOOOOOOOOOOOOOOOOOOOOOOOOOOOOOOOOOOOOOOOO | OOOOOOOOOOOOOOOOOOOOOOOOOOOOOOOOOOOOOOOOOOOOOOOOOOOOOOOOOOOOOOOOOOOOOOOOOOOOOOOOOOOOOOOOOO | OOOOOOOOOOOOOOOOOOOOOOOOOOOOOOOOOOOOOOOOOOOOOOOOOOOOOOOOOOOOOOOOOOOOOOOOOOOOOOOOOOOOOOOOOO | OOOOOOOOOOOOOOOOOOOOOOOOOOOOOOOOOOOOOOOOOOOOOOOOOOOOOOOOOOOOOOOOOOOOOOOOOOOOOOOOOOOOOOOOOO | OOOOOOOOOOOOOOOOOOOOOOOOOOOOOOOOOOOOOOOOOOOOOOOOOOOOOOOOOOOOOOOOOOOOOOOOOOOOOOOOOOOOOOOOOO | OOOOOOOOOOOOOOOOOOOOOOOOOOOOOOOOOOOOOOOOOOOOOOOOOOOOOOOOOOOOOOOOOOOOOOOOOOOOOOOOOOOOOOOOOO |
| Second Source Change |  |  |  |  |  |  |  |  |  |
| Item | Location | Change Type | Foxconn P/N | Part Description | Manufacturer Full Name | Manufacturer P/N | RoHS | Sheet |  |
| 1 | R1092,R1093,R1114,R1115 |  | 61100QH00-017-G | RES,510 Ohm,+/-0.1%,1/16W,G,SMD0402 | KOA SPEER ELECTRONICS, INC. | RN731ETTP5100B25 | G | PWA BOM |  |
|  |  | NO | 61100QH00-012-G | RES,510 Ohm,+/-0.1%,1/16W,G,SMD0402 | WALSIN TECHNOLOGY CORPORATION | WF04U5100BTL | G | PWA BOM |  |
|  |  | NO | 61100QH00-011-G | RES,510 Ohm,+/-0.1%,1/16W,G,SMD0402 | YAGEO CORPORATION COMPONENT | RT0402BRD07510RL | G | PWA BOM |  |
|  |  | Delete | 61100QH00-044-G | RES,510 Ohm,+/-0.1%,1/16W,G,SMD0402 | TA-I TECHNOLOGY CO., LTD | RB04BTP5100 | G | PWA BOM |  |
| 2 | U29 |  | 21050F900-217-G | IC,IDT,2305B-1DCG8,B,G,SOIC-8,SMD | INTEGRATED DEVICE TECHNOLOGY | 2305B-1DCG8 | G | PWA BOM |  |
|  |  | NO | 31050JC00-223-G | Logic IC,Buffer,NB2305AI1DR2G,3.0V~3.6V,0.35ns,SOIC,8P,G | ON SEMICONDUCTOR CORP | NB2305AI1DR2G | G | PWA BOM |  |
|  |  | Delete | SL2305SC-1 | IC,IDT,2305B-1DCG8,B,G,SOIC-8,SMD | Silicon Laboratories Inc. | SL2305SC-1 | G | PWA BOM |  |
| 3 | U37 |  | 41050J100-233-G | Flash,MX25L5121EMC-20G,2.7~3.6V,512K,SPI,G,SOP-8,SMD | MACRONIX INTERNATIONAL CO.,LTD. | MX25L5121EMC-20G | G | PWA BOM |  |
|  |  | Delete | 41050YB00-36F-G | NOR Flash,GD25D05BTIG,2.7V,N/A,3.6V,512K,SPI,-40_x0003_~85_x0003_,SOP,8P,G | GIGADEVICE | GD25D05BTIG | G | PWA BOM |  |
| 4 | X2 |  | 71010SY00-107-G | XTAL,25MHz,+/-30ppm,20pF,G,SMD | DAISHINKU CORPORATION/DAISHINKU SINGAPORE PTE LTD/KDS | 1Y725000CC1G | G | PWA BOM |  |
|  |  | ADD | CX5032GA25000R0KDQ | XTAL,25MHz,+/-30ppm,20pF,G,SMD-2P | Kyocera | CX5032GA25000R0KDQZ1 | G | PWA BOM |  |
|  |  | Delete | CX5032GA25000R0KDQZ1 | XTAL,25MHz,+/-30ppm,20pF,G,SMD-2P | Kyocera | CX5032GA25000R0KDQZ1 | G | PWA BOM |  |
| 5 | X3 |  | 710113800-100-G | XTAL,24MHz,+/-30ppm,20pF,G,SMD | TXC CORPORATION | 7B24000038 | G | PWA BOM |  |
|  |  | ADD | CX5032SB24000R0KZQ | XTAL,24MHz,+/-30ppm,20pF,G,SMD | Kyocera | CX5032SB24000R0KZQ01 |  | PWA BOM |  |
|  |  | Delete | CX5032SB24000R0KZQ01 | XTAL,24MHz,+/-30ppm,20pF,G,SMD | Kyocera | CX5032SB24000R0KZQ01 |  | PWA BOM |  |
| 6 | X6 |  | 710106900-162-G | XTAL,32.768KHz,+/-20ppm,12.5pF,G,SMD | EPSON ELECTRONICS AMERICA,INC. | Q13FC1350000400 | G | PWA BOM |  |
|  |  | ADD | ST3215SB32768H5HPW | XTAL,32.768KHz,+/-20ppm,12.5pF,G,SMD | Kyocera | ST3215SB32768H5HPWAA | G | PWA BOM |  |
|  |  | NO | 710123400-061-G | XTAL,32.768KHz,+/-20ppm,12.5pF,-40℃~85℃,SMD,G | TAITIEN | 06172-W-052-3 | G | PWA BOM |  |
|  |  | Delete | 71011P300-100-G | XTAL,32.768KHz,+/-20ppm,12.5pF,G,SMD | TXC CORPORATION | 9H03200031 | G | PWA BOM |  |
| 7 | Y2 |  | 71020Q600-16G-G | OSC,50MHz,50ppm,3.3V,G,SMD | SiTime Corporation | SIT1602AC-23-33E-50.000000T | G | PWA BOM |  |
|  |  | NO | 71012DA00-100-G | OSC,50MHz,+/-25ppm,15pF,G,SMD | TXC CORPORATION | 7X50000015 |  | PWA BOM |  |
|  |  | ADD | SSW050000I3CHE | OSC,50MHz,50ppm,3.3V,G,SMD | HARMONY (HELE) | SSW050000I3CHE-ST7R2 |  | PWA BOM |  |
|  |  | ADD | KC3225K50.0000C1GE | OSC,50MHz,50ppm,3.3V,G,SMD | Kyocera | KC3225K50.0000C1GE00 |  | PWA BOM |  |
|  |  | Delete | SSW050000I3CHE-ST7R2 | OSC,50MHz,+/-25ppm,15pF,G,SMD | HARMONY | SSW050000I3CHE-ST7R2 | G | PWA BOM |  |
| 8 | Y4 |  | 71020KL00-100-G | OSC,33MHz,+/-50ppm,3.3V,15pF,G,SMD | TXC CORPORATION | 7X33000013 | G | PWA BOM |  |
|  |  | NO | 710211800-967-G | OSC,33MHz,+/-50ppm,3.3V,15pF,G,SMD | eCERA | FK3300011 | G | PWA BOM |  |
|  |  | ADD | KC3225K33.0000C10E | OSC,33MHz,+/-50ppm,3.3V,15pF,G,SMD | Kyocera | KC3225K33.0000C10E00 | G | PWA BOM |  |
|  |  | Delete | KC3225K33.0000C10E00 | OSC,33MHz,+/-50ppm,3.3V,15pF,G,SMD | Kyocera | KC3225K33.0000C10E00 | G | PWA BOM |  |
| 9 | J11 |  | 3406AEU00-245-G | CONN,Header,Shrouded,2X4,R/A,Bla,2.54mm,G/F,G,DIP-8 | AMPHENOL SHANGHAI CORP. | G821EU208AGN00Y | G | PWA BOM |  |
|  |  | NO | 3406AYC00-GRT-G | Header&Socket Connector,511-90-08GB00,Shrouded Header,8,DIP,NY9T,2.54mm,3u",Black,G | PINREX TECHNOLOGY CORP. | 511-90-08GB00 | G | PWA BOM |  |
|  |  | NO | 3406AYE00-637-G | Header&Socket Connector,3112110800-0231,Shrouded Header,8,DIP,NY6T,2.54mm,3u",Black,G | LONG SHOUNG CO.,LTD. | 3112110800-0231 | G | PWA BOM |  |
|  |  | Delete | 3406AYD00-971-G | Header&Socket Connector,C18359-10839-Y,Shrouded Header,8,DIP,LCP,2.54mm,999.9999u",Black,G | ALLTOP TECHNOLOGY CO.,LTD | C18359-10839-Y | G | PWA BOM |  |
| OOOOOOOOOOOOOOOOOOOOOOOOOOOOOOOOOOOOOOOOOOOOOOOOOOOOOOOOOOOOOOOOOOOOOOOOOOOOOOOOOOOOOOOOOO | OOOOOOOOOOOOOOOOOOOOOOOOOOOOOOOOOOOOOOOOOOOOOOOOOOOOOOOOOOOOOOOOOOOOOOOOOOOOOOOOOOOOOOOOOO | OOOOOOOOOOOOOOOOOOOOOOOOOOOOOOOOOOOOOOOOOOOOOOOOOOOOOOOOOOOOOOOOOOOOOOOOOOOOOOOOOOOOOOOOOO | OOOOOOOOOOOOOOOOOOOOOOOOOOOOOOOOOOOOOOOOOOOOOOOOOOOOOOOOOOOOOOOOOOOOOOOOOOOOOOOOOOOOOOOOOO | OOOOOOOOOOOOOOOOOOOOOOOOOOOOOOOOOOOOOOOOOOOOOOOOOOOOOOOOOOOOOOOOOOOOOOOOOOOOOOOOOOOOOOOOOO | OOOOOOOOOOOOOOOOOOOOOOOOOOOOOOOOOOOOOOOOOOOOOOOOOOOOOOOOOOOOOOOOOOOOOOOOOOOOOOOOOOOOOOOOOO | OOOOOOOOOOOOOOOOOOOOOOOOOOOOOOOOOOOOOOOOOOOOOOOOOOOOOOOOOOOOOOOOOOOOOOOOOOOOOOOOOOOOOOOOOO | OOOOOOOOOOOOOOOOOOOOOOOOOOOOOOOOOOOOOOOOOOOOOOOOOOOOOOOOOOOOOOOOOOOOOOOOOOOOOOOOOOOOOOOOOO | OOOOOOOOOOOOOOOOOOOOOOOOOOOOOOOOOOOOOOOOOOOOOOOOOOOOOOOOOOOOOOOOOOOOOOOOOOOOOOOOOOOOOOOOOO | OOOOOOOOOOOOOOOOOOOOOOOOOOOOOOOOOOOOOOOOOOOOOOOOOOOOOOOOOOOOOOOOOOOOOOOOOOOOOOOOOOOOOOOOOO |
| Master Materials Change |  |  |  |  |  |  |  |  |  |
| Item | Foxconn P/N | Orig._Usage | New_Usage | Part Description | Manufacturer Full Name | Manufacturer P/N | RoHS | Location | Sheet |
| OOOOOOOOOOOOOOOOOOOOOOOOOOOOOOOOOOOOOOOOOOOOOOOOOOOOOOOOOOOOOOOOOOOOOOOOOOOOOOOOOOOOOOOOOO | OOOOOOOOOOOOOOOOOOOOOOOOOOOOOOOOOOOOOOOOOOOOOOOOOOOOOOOOOOOOOOOOOOOOOOOOOOOOOOOOOOOOOOOOOO | OOOOOOOOOOOOOOOOOOOOOOOOOOOOOOOOOOOOOOOOOOOOOOOOOOOOOOOOOOOOOOOOOOOOOOOOOOOOOOOOOOOOOOOOOO | OOOOOOOOOOOOOOOOOOOOOOOOOOOOOOOOOOOOOOOOOOOOOOOOOOOOOOOOOOOOOOOOOOOOOOOOOOOOOOOOOOOOOOOOOO | OOOOOOOOOOOOOOOOOOOOOOOOOOOOOOOOOOOOOOOOOOOOOOOOOOOOOOOOOOOOOOOOOOOOOOOOOOOOOOOOOOOOOOOOOO | OOOOOOOOOOOOOOOOOOOOOOOOOOOOOOOOOOOOOOOOOOOOOOOOOOOOOOOOOOOOOOOOOOOOOOOOOOOOOOOOOOOOOOOOOO | OOOOOOOOOOOOOOOOOOOOOOOOOOOOOOOOOOOOOOOOOOOOOOOOOOOOOOOOOOOOOOOOOOOOOOOOOOOOOOOOOOOOOOOOOO | OOOOOOOOOOOOOOOOOOOOOOOOOOOOOOOOOOOOOOOOOOOOOOOOOOOOOOOOOOOOOOOOOOOOOOOOOOOOOOOOOOOOOOOOOO | OOOOOOOOOOOOOOOOOOOOOOOOOOOOOOOOOOOOOOOOOOOOOOOOOOOOOOOOOOOOOOOOOOOOOOOOOOOOOOOOOOOOOOOOOO | OOOOOOOOOOOOOOOOOOOOOOOOOOOOOOOOOOOOOOOOOOOOOOOOOOOOOOOOOOOOOOOOOOOOOOOOOOOOOOOOOOOOOOOOOO |
| TLA Parts Change |  |  |  |  |  |  |  |  |  |
| Item | Foxconn P/N | Qty | Part Description | Manufacturer Full Name | Manufacturer P/N | RoHS | Location | Remark | BOM |
| BOM Change List Date:Wed Jun 14 14:39:11 CST 2017 |  |  |  |  |  |  |  |  |  |
| New BOM file : C:\<user>\BG2 0614.xls |  |  |  |  |  |  |  |  |  |
| Old BOM file : C:\<user>\BG2 0613.xls |  |  |  |  |  |  |  |  |  |
| ##### Add Parts |  |  |  |  |  |  |  |  |  |
| Item | Location | Qty | Foxconn P/N | Part Description | Manufacturer Full Name | Manufacturer P/N | RoHS | Sheet |  |
| ##### Remove Parts |  |  |  |  |  |  |  |  |  |
| Item | Location | Qty | Foxconn P/N | Part Description | Manufacturer Full Name | Manufacturer P/N | RoHS | Sheet |  |
| ##### Change Parts |  |  |  |  |  |  |  |  |  |
| Item | Location | Qty | Foxconn P/N | Part Description | Manufacturer Full Name | Manufacturer P/N | RoHS | Sheet | Remark |
| 1 | PCIE1,PCIE5 | 2 | 10061913-102HLF | CONN,PCIE-8X,V/T,Bla,1mm,30u,G,SMD-98 | FCI CONNECTORS HONGKONG LTD. | 10061913-102HLF | G | PWA BOM | In New BOM |
|  |  |  | 2041366-4 | CONN,PCIE-8X,V/T,Bla,1mm,30u,G,SMD-98 | TYCO ELECTRONICS CORPORATION | 2041366-4 | G | PWA BOM | In New BOM |
|  |  |  | APCI0282-P003C | CONN,PCIE-8X,V/T,Bla,1mm,30u,G,SMD-98 | LOTES CO LTD | APCI0282-P003C |  | PWA BOM | In New BOM |
|  | PCIE1,PCIE5 | 2 | 10061913-102HLF | CONN,PCIE-8X,V/T,Bla,1mm,30u,G,SMD-98 | FCI CONNECTORS HONGKONG LTD. | 10061913-102HLF | G | PWA BOM | In Old BOM |
|  |  |  | 2041366-4 | CONN,PCIE-8X,V/T,Bla,1mm,30u,G,SMD-98 | TYCO ELECTRONICS CORPORATION | 2041366-4 | G | PWA BOM | In Old BOM |
| 2 | PCIE2,PCIE3,PCIE4 | 3 | 10061913-103HLF | CONN,PCIE-16X,V/T,Bla,1mm,30u,G,SMD-164 | FCI CONNECTORS HONGKONG LTD. | 10061913-103HLF | G | PWA BOM | In New BOM |
|  |  |  | 2041366-6 | CONN,PCIE-16X,V/T,Bla,1mm,30u,G,SMD-164 | TYCO ELECTRONICS CORPORATION | 2041366-6 | G | PWA BOM | In New BOM |
|  |  |  | APCI0261-P001C | CONN,PCIE-16X,V/T,Bla,1mm,30u,G,SMD-164 | LOTES CO LTD | APCI0261-P001C |  | PWA BOM | In New BOM |
|  | PCIE2,PCIE3,PCIE4 | 3 | 10061913-103HLF | CONN,PCIE-16X,V/T,Bla,1mm,30u,G,SMD-164 | FCI CONNECTORS HONGKONG LTD. | 10061913-103HLF | G | PWA BOM | In Old BOM |
|  |  |  | 2041366-6 | CONN,PCIE-16X,V/T,Bla,1mm,30u,G,SMD-164 | TYCO ELECTRONICS CORPORATION | 2041366-6 | G | PWA BOM | In Old BOM |
| 3 | DIMM02,DIMM04,DIMM06,DIMM09,DIMM11,DIMM13,DIMM15,DIMM16,DIMM18,DIMM20,DIMM22,DIMM25,DIMM27,DIMM29,DIMM31,DIMM00 | 16 | 34021BC00-G78-G | CONN,DDR IV,V/T,1.2V,Blu,0.85mm,15u,G,SMD-288 | FCI CONNECTORS HONGKONG LTD. | 10140702-0302K11LF | G | PWA BOM | In New BOM |
|  |  |  | 34021CD00-600-G | Memory Connector,AH58897-T2L31-3F,DDR IV,288,SMD,THERMOPLASTIC,0.85mm,15u",Blue,G | FOXCONN TECHNOLOGY CO.,LTD. | AH58897-T2L31-3F | G | PWA BOM | In New BOM |
|  |  |  | ADDR0245-K010C | CONN,DDR IV,V/T,1.2V,Blu,0.85mm,15u,G,SMD-288 | LOTES CO LTD | ADDR0245-K010C | G | PWA BOM | In New BOM |
|  |  |  | 34021CC00-245-G | Memory Connector,DDR4288S05A1H,DDR IV,288,SMD,NYLON,0.85mm,15u",Blue,G | AMPHENOL SHANGHAI CORP. | DDR4288S05A1H | G | PWA BOM | In New BOM |
|  | DIMM02,DIMM04,DIMM06,DIMM09,DIMM11,DIMM13,DIMM15,DIMM16,DIMM18,DIMM20,DIMM22,DIMM25,DIMM27,DIMM29,DIMM31,DIMM00 | 16 | 34021BC00-G78-G | CONN,DDR IV,V/T,1.2V,Blu,0.85mm,15u,G,SMD-288 | FCI CONNECTORS HONGKONG LTD. | 10140702-0302K11LF | G | PWA BOM | In Old BOM |
|  |  |  | 34021CD00-600-G | Memory Connector,AH58897-T2L31-3F,DDR IV,288,SMD,THERMOPLASTIC,0.85mm,15u",Blue,G | FOXCONN TECHNOLOGY CO.,LTD. | AH58897-T2L31-3F | G | PWA BOM | In Old BOM |
|  |  |  | 34021CC00-245-G | Memory Connector,DDR4288S05A1H,DDR IV,288,SMD,NYLON,0.85mm,15u",Blue,G | AMPHENOL SHANGHAI CORP. | DDR4288S05A1H | G | PWA BOM | In Old BOM |
| 4 | DIMM01,DIMM03,DIMM05,DIMM07,DIMM08,DIMM10,DIMM12,DIMM14,DIMM17,DIMM19,DIMM21,DIMM23,DIMM24,DIMM26,DIMM28,DIMM30 | 16 | 34021BD00-G78-G | CONN,DDR IV,V/T,1.2V,Bla,0.85mm,15u,G,SMD-288 | FCI CONNECTORS HONGKONG LTD. | 10140702-0301K11LF | G | PWA BOM | In New BOM |
|  |  |  | ADDR0245-P009C | CONN,DDR IV,V/T,1.2V,Bla,0.85mm,15u,G,SMD-288 | LOTES CO LTD | ADDR0245-P009C |  | PWA BOM | In New BOM |
|  |  |  | 34021CF00-600-G | Memory Connector,AH58897-T2B21-3F,DDR IV,288,SMD,THERMOPLASTIC,0.85mm,15u",Black,G | FOXCONN TECHNOLOGY CO.,LTD. | AH58897-T2B21-3F | G | PWA BOM | In New BOM |
|  |  |  | 34021CE00-245-G | Memory Connector,DDR4288S0511H,DDR IV,288,SMD,NYLON,0.85mm,15u",Black,G | AMPHENOL SHANGHAI CORP. | DDR4288S0511H | G | PWA BOM | In New BOM |
|  | DIMM01,DIMM03,DIMM05,DIMM07,DIMM08,DIMM10,DIMM12,DIMM14,DIMM17,DIMM19,DIMM21,DIMM23,DIMM24,DIMM26,DIMM28,DIMM30 | 16 | 34021BD00-G78-G | CONN,DDR IV,V/T,1.2V,Bla,0.85mm,15u,G,SMD-288 | FCI CONNECTORS HONGKONG LTD. | 10140702-0301K11LF | G | PWA BOM | In Old BOM |
|  |  |  | 34021CF00-600-G | Memory Connector,AH58897-T2B21-3F,DDR IV,288,SMD,THERMOPLASTIC,0.85mm,15u",Black,G | FOXCONN TECHNOLOGY CO.,LTD. | AH58897-T2B21-3F | G | PWA BOM | In Old BOM |
|  |  |  | 34021CE00-245-G | Memory Connector,DDR4288S0511H,DDR IV,288,SMD,NYLON,0.85mm,15u",Black,G | AMPHENOL SHANGHAI CORP. | DDR4288S0511H | G | PWA BOM | In Old BOM |
| ##### Change Revision |  |  |  |  |  |  |  |  |  |
| Sheet | REV OF BOM | CUSTOMER | CUSTOMER P/N | PWA PN | PWA DESCRIPTION | PWA REV | DATE | Remark |  |
| OOOOOOOOOOOOOOOOOOOOOOOOOOOOOOOOOOOOOOOOOOOOOOOOOOOOOOOOOOOOOOOOOOOOOOOOOOOOOOOOOOOOOOOOOO | OOOOOOOOOOOOOOOOOOOOOOOOOOOOOOOOOOOOOOOOOOOOOOOOOOOOOOOOOOOOOOOOOOOOOOOOOOOOOOOOOOOOOOOOOO | OOOOOOOOOOOOOOOOOOOOOOOOOOOOOOOOOOOOOOOOOOOOOOOOOOOOOOOOOOOOOOOOOOOOOOOOOOOOOOOOOOOOOOOOOO | OOOOOOOOOOOOOOOOOOOOOOOOOOOOOOOOOOOOOOOOOOOOOOOOOOOOOOOOOOOOOOOOOOOOOOOOOOOOOOOOOOOOOOOOOO | OOOOOOOOOOOOOOOOOOOOOOOOOOOOOOOOOOOOOOOOOOOOOOOOOOOOOOOOOOOOOOOOOOOOOOOOOOOOOOOOOOOOOOOOOO | OOOOOOOOOOOOOOOOOOOOOOOOOOOOOOOOOOOOOOOOOOOOOOOOOOOOOOOOOOOOOOOOOOOOOOOOOOOOOOOOOOOOOOOOOO | OOOOOOOOOOOOOOOOOOOOOOOOOOOOOOOOOOOOOOOOOOOOOOOOOOOOOOOOOOOOOOOOOOOOOOOOOOOOOOOOOOOOOOOOOO | OOOOOOOOOOOOOOOOOOOOOOOOOOOOOOOOOOOOOOOOOOOOOOOOOOOOOOOOOOOOOOOOOOOOOOOOOOOOOOOOOOOOOOOOOO | OOOOOOOOOOOOOOOOOOOOOOOOOOOOOOOOOOOOOOOOOOOOOOOOOOOOOOOOOOOOOOOOOOOOOOOOOOOOOOOOOOOOOOOOOO | OOOOOOOOOOOOOOOOOOOOOOOOOOOOOOOOOOOOOOOOOOOOOOOOOOOOOOOOOOOOOOOOOOOOOOOOOOOOOOOOOOOOOOOOOO |
| Second Source Change |  |  |  |  |  |  |  |  |  |
| Item | Location | Change Type | Foxconn P/N | Part Description | Manufacturer Full Name | Manufacturer P/N | RoHS | Sheet |  |
| 1 | PCIE1,PCIE5 |  | 10061913-102HLF | CONN,PCIE-8X,V/T,Bla,1mm,30u,G,SMD-98 | FCI CONNECTORS HONGKONG LTD. | 10061913-102HLF | G | PWA BOM |  |
|  |  | NO | 2041366-4 | CONN,PCIE-8X,V/T,Bla,1mm,30u,G,SMD-98 | TYCO ELECTRONICS CORPORATION | 2041366-4 | G | PWA BOM |  |
|  |  | ADD | APCI0282-P003C | CONN,PCIE-8X,V/T,Bla,1mm,30u,G,SMD-98 | LOTES CO LTD | APCI0282-P003C |  | PWA BOM |  |
| 2 | PCIE2,PCIE3,PCIE4 |  | 10061913-103HLF | CONN,PCIE-16X,V/T,Bla,1mm,30u,G,SMD-164 | FCI CONNECTORS HONGKONG LTD. | 10061913-103HLF | G | PWA BOM |  |
|  |  | NO | 2041366-6 | CONN,PCIE-16X,V/T,Bla,1mm,30u,G,SMD-164 | TYCO ELECTRONICS CORPORATION | 2041366-6 | G | PWA BOM |  |
|  |  | ADD | APCI0261-P001C | CONN,PCIE-16X,V/T,Bla,1mm,30u,G,SMD-164 | LOTES CO LTD | APCI0261-P001C |  | PWA BOM |  |
| 3 | DIMM02,DIMM04,DIMM06,DIMM09,DIMM11,DIMM13,DIMM15,DIMM16,DIMM18,DIMM20,DIMM22,DIMM25,DIMM27,DIMM29,DIMM31,DIMM00 |  | 34021BC00-G78-G | CONN,DDR IV,V/T,1.2V,Blu,0.85mm,15u,G,SMD-288 | FCI CONNECTORS HONGKONG LTD. | 10140702-0302K11LF | G | PWA BOM |  |
|  |  | NO | 34021CD00-600-G | Memory Connector,AH58897-T2L31-3F,DDR IV,288,SMD,THERMOPLASTIC,0.85mm,15u",Blue,G | FOXCONN TECHNOLOGY CO.,LTD. | AH58897-T2L31-3F | G | PWA BOM |  |
|  |  | ADD | ADDR0245-K010C | CONN,DDR IV,V/T,1.2V,Blu,0.85mm,15u,G,SMD-288 | LOTES CO LTD | ADDR0245-K010C | G | PWA BOM |  |
|  |  | NO | 34021CC00-245-G | Memory Connector,DDR4288S05A1H,DDR IV,288,SMD,NYLON,0.85mm,15u",Blue,G | AMPHENOL SHANGHAI CORP. | DDR4288S05A1H | G | PWA BOM |  |
| 4 | DIMM01,DIMM03,DIMM05,DIMM07,DIMM08,DIMM10,DIMM12,DIMM14,DIMM17,DIMM19,DIMM21,DIMM23,DIMM24,DIMM26,DIMM28,DIMM30 |  | 34021BD00-G78-G | CONN,DDR IV,V/T,1.2V,Bla,0.85mm,15u,G,SMD-288 | FCI CONNECTORS HONGKONG LTD. | 10140702-0301K11LF | G | PWA BOM |  |
|  |  | ADD | ADDR0245-P009C | CONN,DDR IV,V/T,1.2V,Bla,0.85mm,15u,G,SMD-288 | LOTES CO LTD | ADDR0245-P009C |  | PWA BOM |  |
|  |  | NO | 34021CF00-600-G | Memory Connector,AH58897-T2B21-3F,DDR IV,288,SMD,THERMOPLASTIC,0.85mm,15u",Black,G | FOXCONN TECHNOLOGY CO.,LTD. | AH58897-T2B21-3F | G | PWA BOM |  |
|  |  | NO | 34021CE00-245-G | Memory Connector,DDR4288S0511H,DDR IV,288,SMD,NYLON,0.85mm,15u",Black,G | AMPHENOL SHANGHAI CORP. | DDR4288S0511H | G | PWA BOM |  |
| OOOOOOOOOOOOOOOOOOOOOOOOOOOOOOOOOOOOOOOOOOOOOOOOOOOOOOOOOOOOOOOOOOOOOOOOOOOOOOOOOOOOOOOOOO | OOOOOOOOOOOOOOOOOOOOOOOOOOOOOOOOOOOOOOOOOOOOOOOOOOOOOOOOOOOOOOOOOOOOOOOOOOOOOOOOOOOOOOOOOO | OOOOOOOOOOOOOOOOOOOOOOOOOOOOOOOOOOOOOOOOOOOOOOOOOOOOOOOOOOOOOOOOOOOOOOOOOOOOOOOOOOOOOOOOOO | OOOOOOOOOOOOOOOOOOOOOOOOOOOOOOOOOOOOOOOOOOOOOOOOOOOOOOOOOOOOOOOOOOOOOOOOOOOOOOOOOOOOOOOOOO | OOOOOOOOOOOOOOOOOOOOOOOOOOOOOOOOOOOOOOOOOOOOOOOOOOOOOOOOOOOOOOOOOOOOOOOOOOOOOOOOOOOOOOOOOO | OOOOOOOOOOOOOOOOOOOOOOOOOOOOOOOOOOOOOOOOOOOOOOOOOOOOOOOOOOOOOOOOOOOOOOOOOOOOOOOOOOOOOOOOOO | OOOOOOOOOOOOOOOOOOOOOOOOOOOOOOOOOOOOOOOOOOOOOOOOOOOOOOOOOOOOOOOOOOOOOOOOOOOOOOOOOOOOOOOOOO | OOOOOOOOOOOOOOOOOOOOOOOOOOOOOOOOOOOOOOOOOOOOOOOOOOOOOOOOOOOOOOOOOOOOOOOOOOOOOOOOOOOOOOOOOO | OOOOOOOOOOOOOOOOOOOOOOOOOOOOOOOOOOOOOOOOOOOOOOOOOOOOOOOOOOOOOOOOOOOOOOOOOOOOOOOOOOOOOOOOOO | OOOOOOOOOOOOOOOOOOOOOOOOOOOOOOOOOOOOOOOOOOOOOOOOOOOOOOOOOOOOOOOOOOOOOOOOOOOOOOOOOOOOOOOOOO |
| Master Materials Change |  |  |  |  |  |  |  |  |  |
| Item | Foxconn P/N | Orig._Usage | New_Usage | Part Description | Manufacturer Full Name | Manufacturer P/N | RoHS | Location | Sheet |
| OOOOOOOOOOOOOOOOOOOOOOOOOOOOOOOOOOOOOOOOOOOOOOOOOOOOOOOOOOOOOOOOOOOOOOOOOOOOOOOOOOOOOOOOOO | OOOOOOOOOOOOOOOOOOOOOOOOOOOOOOOOOOOOOOOOOOOOOOOOOOOOOOOOOOOOOOOOOOOOOOOOOOOOOOOOOOOOOOOOOO | OOOOOOOOOOOOOOOOOOOOOOOOOOOOOOOOOOOOOOOOOOOOOOOOOOOOOOOOOOOOOOOOOOOOOOOOOOOOOOOOOOOOOOOOOO | OOOOOOOOOOOOOOOOOOOOOOOOOOOOOOOOOOOOOOOOOOOOOOOOOOOOOOOOOOOOOOOOOOOOOOOOOOOOOOOOOOOOOOOOOO | OOOOOOOOOOOOOOOOOOOOOOOOOOOOOOOOOOOOOOOOOOOOOOOOOOOOOOOOOOOOOOOOOOOOOOOOOOOOOOOOOOOOOOOOOO | OOOOOOOOOOOOOOOOOOOOOOOOOOOOOOOOOOOOOOOOOOOOOOOOOOOOOOOOOOOOOOOOOOOOOOOOOOOOOOOOOOOOOOOOOO | OOOOOOOOOOOOOOOOOOOOOOOOOOOOOOOOOOOOOOOOOOOOOOOOOOOOOOOOOOOOOOOOOOOOOOOOOOOOOOOOOOOOOOOOOO | OOOOOOOOOOOOOOOOOOOOOOOOOOOOOOOOOOOOOOOOOOOOOOOOOOOOOOOOOOOOOOOOOOOOOOOOOOOOOOOOOOOOOOOOOO | OOOOOOOOOOOOOOOOOOOOOOOOOOOOOOOOOOOOOOOOOOOOOOOOOOOOOOOOOOOOOOOOOOOOOOOOOOOOOOOOOOOOOOOOOO | OOOOOOOOOOOOOOOOOOOOOOOOOOOOOOOOOOOOOOOOOOOOOOOOOOOOOOOOOOOOOOOOOOOOOOOOOOOOOOOOOOOOOOOOOO |
| TLA Parts Change |  |  |  |  |  |  |  |  |  |
| Item | Foxconn P/N | Qty | Part Description | Manufacturer Full Name | Manufacturer P/N | RoHS | Location | Remark | BOM |
| BOM Change List Date:Tue Jun 20 15:34:33 CST 2017 |  |  |  |  |  |  |  |  |  |
| New BOM file : C:\<user>\BG2 20.xls |  |  |  |  |  |  |  |  |  |
| Old BOM file : C:\<user>\BG2 14.xls |  |  |  |  |  |  |  |  |  |
| ##### Add Parts |  |  |  |  |  |  |  |  |  |
| Item | Location | Qty | Foxconn P/N | Part Description | Manufacturer Full Name | Manufacturer P/N | RoHS | Sheet |  |
| ##### Remove Parts |  |  |  |  |  |  |  |  |  |
| Item | Location | Qty | Foxconn P/N | Part Description | Manufacturer Full Name | Manufacturer P/N | RoHS | Sheet |  |
| ##### Change Parts |  |  |  |  |  |  |  |  |  |
| Item | Location | Qty | Foxconn P/N | Part Description | Manufacturer Full Name | Manufacturer P/N | RoHS | Sheet | Remark |
| 1 | PSRL1 | 1 | 63033PG00-15A-G | IND,22nH@100KHz,+/-15%,22A,249.55uOhm,SHLD,G,SMD | The Inter-Technical Group, Inc. | SLC1615A-R022LHF | G | PWA BOM | In New BOM |
|  |  |  | 63035Y500-129-G | IND,22nH@100KHz,+/-15%,22A,249.55uOhm,SHLD,G,SMD | MAG.LAYERS, SCIENTIFIC-TECHNICS (KUNSHAN) CO., LTD. | MSI-400404-22NL-I | G | PWA BOM | In New BOM |
|  |  |  | 63035SH00-065-G | IND,22nH@100KHz,+/-15%,22A,249.55uOhm,SHLD,G,SMD | DELTA ELECTRONICS INDUSTRIAL CO.,LTD | HCB0439-220 | G | PWA BOM | In New BOM |
|  | PSRL1 | 1 | 63033PG00-15A-G | IND,22nH@100KHz,+/-15%,22A,249.55uOhm,SHLD,G,SMD | The Inter-Technical Group, Inc. | SLC1615A-R022LHF | G | PWA BOM | In Old BOM |
|  |  |  | 63035Y500-129-G | IND,22nH@100KHz,+/-15%,22A,249.55uOhm,SHLD,G,SMD | MAG.LAYERS, SCIENTIFIC-TECHNICS (KUNSHAN) CO., LTD. | MSI-400404-22NL-I | G | PWA BOM | In Old BOM |
|  |  |  | 630352U00-034-G | IND,22nH@100KHz,+/-15%,22A,249.55uOhm,SHLD,G,SMD | CYNTEC CO. LTD | HCB0439-220 | G | PWA BOM | In Old BOM |
| 2 | U110 | 1 | 330103N00-426-G | IC,Optocoupler,PS2811-1-F3-A,G,SSOP-4,SMD | RENESAS TECHNOLOGY AMERICA INC | PS2811-1-F3-A | G | PWA BOM | In New BOM |
|  |  |  | 330102900-289-G | OPTO-IC,ISOL,LTV-217-G,SSOP,4P,G | LITE-ON TECHNOLOGY CORPORATION | LTV-217-G | G | PWA BOM | In New BOM |
|  |  |  | VOS618A-3X001T | OPTO-IC,VOS618A-3X001T | VISHAY ENTER TECHNO LOGY.INC | VOS618A-3X001T | G | PWA BOM | In New BOM |
|  | U110 | 1 | 330103N00-426-G | IC,Optocoupler,PS2811-1-F3-A,G,SSOP-4,SMD | RENESAS TECHNOLOGY AMERICA INC | PS2811-1-F3-A | G | PWA BOM | In Old BOM |
|  |  |  | 330102900-289-G | OPTO-IC,ISOL,LTV-217-G,SSOP,4P,G | LITE-ON TECHNOLOGY CORPORATION | LTV-217-G | G | PWA BOM | In Old BOM |
|  |  |  | VOS618A-3T | OPTO-IC,VOS618A-3T | VISHAY ENTER TECHNO LOGY.INC | VOS618A-3T | G | PWA BOM | In Old BOM |
| 3 | PCIE1,PCIE5 | 2 | 340316300-G78-G | CONN,PCIE-8X,V/T,Bla,1mm,30u,G,SMD-98 | FCI CONNECTORS HONGKONG LTD. | 10061913-102PLF | G | PWA BOM | In New BOM |
|  |  |  | 2041366-4 | CONN,PCIE-8X,V/T,Bla,1mm,30u,G,SMD-98 | TYCO ELECTRONICS CORPORATION | 2041366-4 | G | PWA BOM | In New BOM |
|  |  |  | APCI0282-P003A | CONN,PCIE-8X,V/T,Bla,1mm,30u,G,SMD-98 | LOTES CO LTD | APCI0282-P003A | G | PWA BOM | In New BOM |
|  | PCIE1,PCIE5 | 2 | 10061913-102HLF | CONN,PCIE-8X,V/T,Bla,1mm,30u,G,SMD-98 | FCI CONNECTORS HONGKONG LTD. | 10061913-102HLF | G | PWA BOM | In Old BOM |
|  |  |  | 2041366-4 | CONN,PCIE-8X,V/T,Bla,1mm,30u,G,SMD-98 | TYCO ELECTRONICS CORPORATION | 2041366-4 | G | PWA BOM | In Old BOM |
|  |  |  | APCI0282-P003C | CONN,PCIE-8X,V/T,Bla,1mm,30u,G,SMD-98 | LOTES CO LTD | APCI0282-P003C |  | PWA BOM | In Old BOM |
| 4 | PCIE2,PCIE3,PCIE4 | 3 | 34031U600-G78-G | CONN,PCIE-16X,V/T,Bla,1mm,30u,G,SMD-164 | FCI CONNECTORS HONGKONG LTD. | 10061913-103BLF | G | PWA BOM | In New BOM |
|  |  |  | 2041366-6 | CONN,PCIE-16X,V/T,Bla,1mm,30u,G,SMD-164 | TYCO ELECTRONICS CORPORATION | 2041366-6 | G | PWA BOM | In New BOM |
|  |  |  | APCI0261-P001C | CONN,PCIE-16X,V/T,Bla,1mm,30u,G,SMD-164 | LOTES CO LTD | APCI0261-P001C | G | PWA BOM | In New BOM |
|  | PCIE2,PCIE3,PCIE4 | 3 | 10061913-103HLF | CONN,PCIE-16X,V/T,Bla,1mm,30u,G,SMD-164 | FCI CONNECTORS HONGKONG LTD. | 10061913-103HLF | G | PWA BOM | In Old BOM |
|  |  |  | 2041366-6 | CONN,PCIE-16X,V/T,Bla,1mm,30u,G,SMD-164 | TYCO ELECTRONICS CORPORATION | 2041366-6 | G | PWA BOM | In Old BOM |
|  |  |  | APCI0261-P001C | CONN,PCIE-16X,V/T,Bla,1mm,30u,G,SMD-164 | LOTES CO LTD | APCI0261-P001C |  | PWA BOM | In Old BOM |
| 5 | PBMR34,PAMR34 | 2 | 61011H300-017-G | RES,316 Ohm,+/-1%,1/16W,G,SMD0402 | KOA SPEER ELECTRONICS, INC. | RK73H1ETTP3160F | G | PWA BOM | In New BOM |
|  |  |  | 61011H300-012-G | RES,316 Ohm,+/-1%,1/16W,G,SMD0402 | WALSIN TECHNOLOGY CORPORATION | WR04X3160FTL | G | PWA BOM | In New BOM |
|  |  |  | 61011H300-011-G | RES,316 Ohm,+/-1%,1/16W,G,SMD0402 | YAGEO CORPORATION COMPONENT | RC0402FR-07316RL | G | PWA BOM | In New BOM |
|  | PBMR34,PAMR34 | 2 | RN731ETTP3160B25 | RES,316 Ohm,+/-0.1%,1/16W,G,SMD0402 | KOA SPEER ELECTRONICS, INC. | RN731ETTP3160B25 | G | PWA BOM | In Old BOM |
| ##### Change Revision |  |  |  |  |  |  |  |  |  |
| Sheet | REV OF BOM | CUSTOMER | CUSTOMER P/N | PWA PN | PWA DESCRIPTION | PWA REV | DATE | Remark |  |
| OOOOOOOOOOOOOOOOOOOOOOOOOOOOOOOOOOOOOOOOOOOOOOOOOOOOOOOOOOOOOOOOOOOOOOOOOOOOOOOOOOOOOOOOOO | OOOOOOOOOOOOOOOOOOOOOOOOOOOOOOOOOOOOOOOOOOOOOOOOOOOOOOOOOOOOOOOOOOOOOOOOOOOOOOOOOOOOOOOOOO | OOOOOOOOOOOOOOOOOOOOOOOOOOOOOOOOOOOOOOOOOOOOOOOOOOOOOOOOOOOOOOOOOOOOOOOOOOOOOOOOOOOOOOOOOO | OOOOOOOOOOOOOOOOOOOOOOOOOOOOOOOOOOOOOOOOOOOOOOOOOOOOOOOOOOOOOOOOOOOOOOOOOOOOOOOOOOOOOOOOOO | OOOOOOOOOOOOOOOOOOOOOOOOOOOOOOOOOOOOOOOOOOOOOOOOOOOOOOOOOOOOOOOOOOOOOOOOOOOOOOOOOOOOOOOOOO | OOOOOOOOOOOOOOOOOOOOOOOOOOOOOOOOOOOOOOOOOOOOOOOOOOOOOOOOOOOOOOOOOOOOOOOOOOOOOOOOOOOOOOOOOO | OOOOOOOOOOOOOOOOOOOOOOOOOOOOOOOOOOOOOOOOOOOOOOOOOOOOOOOOOOOOOOOOOOOOOOOOOOOOOOOOOOOOOOOOOO | OOOOOOOOOOOOOOOOOOOOOOOOOOOOOOOOOOOOOOOOOOOOOOOOOOOOOOOOOOOOOOOOOOOOOOOOOOOOOOOOOOOOOOOOOO | OOOOOOOOOOOOOOOOOOOOOOOOOOOOOOOOOOOOOOOOOOOOOOOOOOOOOOOOOOOOOOOOOOOOOOOOOOOOOOOOOOOOOOOOOO | OOOOOOOOOOOOOOOOOOOOOOOOOOOOOOOOOOOOOOOOOOOOOOOOOOOOOOOOOOOOOOOOOOOOOOOOOOOOOOOOOOOOOOOOOO |
| Second Source Change |  |  |  |  |  |  |  |  |  |
| Item | Location | Change Type | Foxconn P/N | Part Description | Manufacturer Full Name | Manufacturer P/N | RoHS | Sheet |  |
| 1 | PSRL1 |  | 63033PG00-15A-G | IND,22nH@100KHz,+/-15%,22A,249.55uOhm,SHLD,G,SMD | The Inter-Technical Group, Inc. | SLC1615A-R022LHF | G | PWA BOM |  |
|  |  | NO | 63035Y500-129-G | IND,22nH@100KHz,+/-15%,22A,249.55uOhm,SHLD,G,SMD | MAG.LAYERS, SCIENTIFIC-TECHNICS (KUNSHAN) CO., LTD. | MSI-400404-22NL-I | G | PWA BOM |  |
|  |  | ADD | 63035SH00-065-G | IND,22nH@100KHz,+/-15%,22A,249.55uOhm,SHLD,G,SMD | DELTA ELECTRONICS INDUSTRIAL CO.,LTD | HCB0439-220 | G | PWA BOM |  |
|  |  | Delete | 630352U00-034-G | IND,22nH@100KHz,+/-15%,22A,249.55uOhm,SHLD,G,SMD | CYNTEC CO. LTD | HCB0439-220 | G | PWA BOM |  |
| 2 | U110 |  | 330103N00-426-G | IC,Optocoupler,PS2811-1-F3-A,G,SSOP-4,SMD | RENESAS TECHNOLOGY AMERICA INC | PS2811-1-F3-A | G | PWA BOM |  |
|  |  | NO | 330102900-289-G | OPTO-IC,ISOL,LTV-217-G,SSOP,4P,G | LITE-ON TECHNOLOGY CORPORATION | LTV-217-G | G | PWA BOM |  |
|  |  | ADD | VOS618A-3X001T | OPTO-IC,VOS618A-3X001T | VISHAY ENTER TECHNO LOGY.INC | VOS618A-3X001T | G | PWA BOM |  |
|  |  | Delete | VOS618A-3T | OPTO-IC,VOS618A-3T | VISHAY ENTER TECHNO LOGY.INC | VOS618A-3T | G | PWA BOM |  |
| OOOOOOOOOOOOOOOOOOOOOOOOOOOOOOOOOOOOOOOOOOOOOOOOOOOOOOOOOOOOOOOOOOOOOOOOOOOOOOOOOOOOOOOOOO | OOOOOOOOOOOOOOOOOOOOOOOOOOOOOOOOOOOOOOOOOOOOOOOOOOOOOOOOOOOOOOOOOOOOOOOOOOOOOOOOOOOOOOOOOO | OOOOOOOOOOOOOOOOOOOOOOOOOOOOOOOOOOOOOOOOOOOOOOOOOOOOOOOOOOOOOOOOOOOOOOOOOOOOOOOOOOOOOOOOOO | OOOOOOOOOOOOOOOOOOOOOOOOOOOOOOOOOOOOOOOOOOOOOOOOOOOOOOOOOOOOOOOOOOOOOOOOOOOOOOOOOOOOOOOOOO | OOOOOOOOOOOOOOOOOOOOOOOOOOOOOOOOOOOOOOOOOOOOOOOOOOOOOOOOOOOOOOOOOOOOOOOOOOOOOOOOOOOOOOOOOO | OOOOOOOOOOOOOOOOOOOOOOOOOOOOOOOOOOOOOOOOOOOOOOOOOOOOOOOOOOOOOOOOOOOOOOOOOOOOOOOOOOOOOOOOOO | OOOOOOOOOOOOOOOOOOOOOOOOOOOOOOOOOOOOOOOOOOOOOOOOOOOOOOOOOOOOOOOOOOOOOOOOOOOOOOOOOOOOOOOOOO | OOOOOOOOOOOOOOOOOOOOOOOOOOOOOOOOOOOOOOOOOOOOOOOOOOOOOOOOOOOOOOOOOOOOOOOOOOOOOOOOOOOOOOOOOO | OOOOOOOOOOOOOOOOOOOOOOOOOOOOOOOOOOOOOOOOOOOOOOOOOOOOOOOOOOOOOOOOOOOOOOOOOOOOOOOOOOOOOOOOOO | OOOOOOOOOOOOOOOOOOOOOOOOOOOOOOOOOOOOOOOOOOOOOOOOOOOOOOOOOOOOOOOOOOOOOOOOOOOOOOOOOOOOOOOOOO |
| Master Materials Change |  |  |  |  |  |  |  |  |  |
| Item | Foxconn P/N | Orig._Usage | New_Usage | Part Description | Manufacturer Full Name | Manufacturer P/N | RoHS | Location | Sheet |
| 1 | 340316300-G78-G | 0 | 2 | CONN,PCIE-8X,V/T,Bla,1mm,30u,G,SMD-98 | FCI CONNECTORS HONGKONG LTD. | 10061913-102PLF | G | (+)PCIE1,PCIE5 | PWA BOM |
|  | 2041366-4 |  |  | CONN,PCIE-8X,V/T,Bla,1mm,30u,G,SMD-98 | TYCO ELECTRONICS CORPORATION | 2041366-4 |  |  | PWA BOM |
|  | APCI0282-P003A |  |  | CONN,PCIE-8X,V/T,Bla,1mm,30u,G,SMD-98 | LOTES CO LTD | APCI0282-P003A |  |  | PWA BOM |
| 2 | 34031U600-G78-G | 0 | 3 | CONN,PCIE-16X,V/T,Bla,1mm,30u,G,SMD-164 | FCI CONNECTORS HONGKONG LTD. | 10061913-103BLF | G | (+)PCIE2,PCIE3,PCIE4 | PWA BOM |
|  | 2041366-6 |  |  | CONN,PCIE-16X,V/T,Bla,1mm,30u,G,SMD-164 | TYCO ELECTRONICS CORPORATION | 2041366-6 |  |  | PWA BOM |
|  | APCI0261-P001C |  |  | CONN,PCIE-16X,V/T,Bla,1mm,30u,G,SMD-164 | LOTES CO LTD | APCI0261-P001C |  |  | PWA BOM |
| 3 | 61011H300-017-G | 4 | 6 | RES,316 Ohm,+/-1%,1/16W,G,SMD0402 | KOA SPEER ELECTRONICS, INC. | RK73H1ETTP3160F | G | (+)PBMR34,PAMR34 | PWA BOM |
|  | 61011H300-012-G |  |  | RES,316 Ohm,+/-1%,1/16W,G,SMD0402 | WALSIN TECHNOLOGY CORPORATION | WR04X3160FTL |  |  | PWA BOM |
|  | 61011H300-011-G |  |  | RES,316 Ohm,+/-1%,1/16W,G,SMD0402 | YAGEO CORPORATION COMPONENT | RC0402FR-07316RL |  |  | PWA BOM |
| 4 | 10061913-102HLF | 2 | 0 | CONN,PCIE-8X,V/T,Bla,1mm,30u,G,SMD-98 | FCI CONNECTORS HONGKONG LTD. | 10061913-102HLF | G | (-)PCIE1,PCIE5 | PWA BOM |
|  | 2041366-4 |  |  | CONN,PCIE-8X,V/T,Bla,1mm,30u,G,SMD-98 | TYCO ELECTRONICS CORPORATION | 2041366-4 |  |  | PWA BOM |
|  | APCI0282-P003C |  |  | CONN,PCIE-8X,V/T,Bla,1mm,30u,G,SMD-98 | LOTES CO LTD | APCI0282-P003C |  |  | PWA BOM |
| 5 | 10061913-103HLF | 3 | 0 | CONN,PCIE-16X,V/T,Bla,1mm,30u,G,SMD-164 | FCI CONNECTORS HONGKONG LTD. | 10061913-103HLF | G | (-)PCIE2,PCIE3,PCIE4 | PWA BOM |
|  | 2041366-6 |  |  | CONN,PCIE-16X,V/T,Bla,1mm,30u,G,SMD-164 | TYCO ELECTRONICS CORPORATION | 2041366-6 |  |  | PWA BOM |
|  | APCI0261-P001C |  |  | CONN,PCIE-16X,V/T,Bla,1mm,30u,G,SMD-164 | LOTES CO LTD | APCI0261-P001C |  |  | PWA BOM |
| 6 | RN731ETTP3160B25 | 2 | 0 | RES,316 Ohm,+/-0.1%,1/16W,G,SMD0402 | KOA SPEER ELECTRONICS, INC. | RN731ETTP3160B25 | G | (-)PBMR34,PAMR34 | PWA BOM |
| OOOOOOOOOOOOOOOOOOOOOOOOOOOOOOOOOOOOOOOOOOOOOOOOOOOOOOOOOOOOOOOOOOOOOOOOOOOOOOOOOOOOOOOOOO | OOOOOOOOOOOOOOOOOOOOOOOOOOOOOOOOOOOOOOOOOOOOOOOOOOOOOOOOOOOOOOOOOOOOOOOOOOOOOOOOOOOOOOOOOO | OOOOOOOOOOOOOOOOOOOOOOOOOOOOOOOOOOOOOOOOOOOOOOOOOOOOOOOOOOOOOOOOOOOOOOOOOOOOOOOOOOOOOOOOOO | OOOOOOOOOOOOOOOOOOOOOOOOOOOOOOOOOOOOOOOOOOOOOOOOOOOOOOOOOOOOOOOOOOOOOOOOOOOOOOOOOOOOOOOOOO | OOOOOOOOOOOOOOOOOOOOOOOOOOOOOOOOOOOOOOOOOOOOOOOOOOOOOOOOOOOOOOOOOOOOOOOOOOOOOOOOOOOOOOOOOO | OOOOOOOOOOOOOOOOOOOOOOOOOOOOOOOOOOOOOOOOOOOOOOOOOOOOOOOOOOOOOOOOOOOOOOOOOOOOOOOOOOOOOOOOOO | OOOOOOOOOOOOOOOOOOOOOOOOOOOOOOOOOOOOOOOOOOOOOOOOOOOOOOOOOOOOOOOOOOOOOOOOOOOOOOOOOOOOOOOOOO | OOOOOOOOOOOOOOOOOOOOOOOOOOOOOOOOOOOOOOOOOOOOOOOOOOOOOOOOOOOOOOOOOOOOOOOOOOOOOOOOOOOOOOOOOO | OOOOOOOOOOOOOOOOOOOOOOOOOOOOOOOOOOOOOOOOOOOOOOOOOOOOOOOOOOOOOOOOOOOOOOOOOOOOOOOOOOOOOOOOOO | OOOOOOOOOOOOOOOOOOOOOOOOOOOOOOOOOOOOOOOOOOOOOOOOOOOOOOOOOOOOOOOOOOOOOOOOOOOOOOOOOOOOOOOOOO |
| TLA Parts Change |  |  |  |  |  |  |  |  |  |
| Item | Foxconn P/N | Qty | Part Description | Manufacturer Full Name | Manufacturer P/N | RoHS | Location | Remark | BOM |
| BOM Change List Date:Fri Aug 04 10:01:59 GMT+08:00 2017 |  |  |  |  |  |  |  |  |  |
| New BOM file : C:\<user>\BARRELEYE_G2-MB-PVT-HW-EBOM-20170804.xls |  |  |  |  |  |  |  |  |  |
| Old BOM file : C:\<user>\BARRELEYE-G2-MB-DVT-HW-EBOM-X03_20170519.xls |  |  |  |  |  |  |  |  |  |
| ##### Add Parts |  |  |  |  |  |  |  |  |  |
| Item | Location | Qty | Foxconn P/N | Part Description | Manufacturer Full Name | Manufacturer P/N | RoHS | Sheet |  |
| 1 | PBMD4,PBFD4,PBED4,PAMD4,PAFD4,PAED4,PBAD5,PAAD5 | 8 | 52030DA00-237-G | DIODE,Schottky,BAT46W-7-F,100V,150mA,G,SOD123-2,SMD | DIODES INEORPORATION | BAT46W-7-F |  | PWA BOM |  |
| ##### Remove Parts |  |  |  |  |  |  |  |  |  |
| Item | Location | Qty | Foxconn P/N | Part Description | Manufacturer Full Name | Manufacturer P/N | RoHS | Sheet |  |
| 1 | C2184,C2185 | 2 | 620108B00-015-G | CAP,120pF,+/-5%,NPO(C0G),50V,G,SMD0402 | MURATA ELEC. NORTH AMERICA | GRM1555C1H121J | N | PWA BOM |  |
| 2 | ED1 | 1 | 521800900-227-G | DIODE,Array-TVS,SRV05-4.TCT,5V,12A,G,SOT23-6,SMD | SEMTECH CORPORATION. | SRV05-4.TCT | N | PWA BOM |  |
| 3 | R1472,R1554,R1815,R1816,R1817,R1818,R1819 | 7 | 610107A00-017-G | RES,0 Ohm,+/-5%,1/16W,G,SMD0402 | KOA SPEER ELECTRONICS, INC. | RK73Z1ETTP | N | PWA BOM |  |
| 4 | PSUR4 | 1 | 610119C00-017-G | RES,130KOhm,+/-1%,1/16W,G,SMD0402 | KOA SPEER ELECTRONICS, INC. | RK73H1ETTP1303F | N | PWA BOM |  |
| 5 | PSUR5 | 1 | 610116G00-017-G | RES,150KOhm,+/-1%,1/16W,G,SMD0402 | KOA SPEER ELECTRONICS, INC. | RK73H1ETTP1503F | N | PWA BOM |  |
| 6 | R1093,R1114 | 2 | 61100QH00-017-G | RES,510 Ohm,+/-0.1%,1/16W,G,SMD0402 | KOA SPEER ELECTRONICS, INC. | RN731ETTP5100B25 | Y | PWA BOM |  |
| 7 | R1838,R1839 | 2 | 610124C00-017-G | RES,57.6 Ohm,+/-1%,1/16W,G,SMD0402 | KOA SPEER ELECTRONICS, INC. | RK73H1ETTP57R6F | N | PWA BOM |  |
| 8 | J3 | 1 | 34068LN00-317-G | CONN,Header,Pin Header,1X3,V/T,2.54mm,30u,G,SMD-3 | MOLEX INCORPORATED | 87898-0315 |  | PWA BOM |  |
| 9 | J10 | 1 | 3406B5J00-317-G | CONN,Header,Socket,V/T,Bla,2mm,15u,G,DIP-18 | MOLEX INCORPORATED | 79107-7008 |  | PWA BOM |  |
| 10 | J13 | 1 | 34064J800-317-G | CONN,Header,Socket,2X2,V/T,Bla,2mm,15u,G,DIP-4 | MOLEX INCORPORATED | 79107-7001 |  | PWA BOM |  |
| 11 | PSUSW1 | 1 | 34080F500-653-G | CONN,Switch,slide,25mA,24V,G,SMD-8 | DIPTRONICS MANUFACTURING INC. | DHN-04F-T-V-T/R |  | PWA BOM |  |
| ##### Change Parts |  |  |  |  |  |  |  |  |  |
| Item | Location | Qty | Foxconn P/N | Part Description | Manufacturer Full Name | Manufacturer P/N | RoHS | Sheet | Remark |
| 1 | FS5,FS8,FS11,FS14,FS17,FS19,FS20 | 7 | 0438005.WRGT | Fuse,Fast acting,32V,5A,G,SMD0603 | LITTELFUSE FAR EAST PTE LTD | 0438005.WRGT | Y | PWA BOM | In New BOM |
|  | FS5,FS8,FS11,FS14,FS17,FS19,FS20 | 7 | 730103M00-086-G | Fuse,Fast acting,32V,5A,G,SMD0603 | LITTELFUSE FAR EAST PTE LTD | 0438005.WR | Y | PWA BOM | In Old BOM |
| 2 | PBMD1,PBFD1,PBED1,PBAD1,PAMD1,PAFD1,PAED1,PAAD1 | 8 | 52030DA00-237-G | DIODE,Schottky,BAT46W-7-F,100V,150mA,G,SOD123-2,SMD | DIODES INEORPORATION | BAT46W-7-F |  | PWA BOM | In New BOM |
|  | PBMD1,PBFD1,PBED1,PBAD1,PAMD1,PAFD1,PAED1,PAAD1 | 8 | 520103B00-185-G | Diode,Rectifier&Switching,MMBD1205,100V,200mA,G,SOT-23-3,SMD | FAIRCHILD SEMICONDUCTOR CORP | MMBD1205 | N | PWA BOM | In Old BOM |
| 3 | PSUR2 | 1 | 61010G500-017-G | RES,10KOhm,+/-1%,1/16W,G,SMD0402 | KOA SPEER ELECTRONICS, INC. | RK73H1ETTP1002F | N | PWA BOM | In New BOM |
|  | PSUR2 | 1 | 610116G00-017-G | RES,150KOhm,+/-1%,1/16W,G,SMD0402 | KOA SPEER ELECTRONICS, INC. | RK73H1ETTP1503F | N | PWA BOM | In Old BOM |
| 4 | PBAU3,PAAU3 | 2 | 32014E200-53N-G | IC,Regulator,PI3753-00-LGIZ,ADJ,10.3A,G,LGA-108,SMD | Vicor Corporation | PI3753-00-LGIZ |  | PWA BOM | In New BOM |
|  | PBAU3,PAAU3 | 2 | PI3753-00-LGIZ | IC,Regulator,PI3753-00,ADJ,4A,G,LGA-71,SMD | Vicor Corporation | PI3753-00-LGIZ |  | PWA BOM | In Old BOM |
| 5 | R1226,R1502 | 2 | 61011H500-017-G | RES,22 Ohm,+/-1%,1/16W,G,SMD0402 | KOA SPEER ELECTRONICS, INC. | RK73H1ETTP22R0F | N | PWA BOM | In New BOM |
|  | R1226,R1502 | 2 | 610107A00-017-G | RES,0 Ohm,+/-5%,1/16W,G,SMD0402 | KOA SPEER ELECTRONICS, INC. | RK73Z1ETTP | N | PWA BOM | In Old BOM |
| 6 | ED2,ED3 | 2 | SRV05-4ATCT | DIODE,Array-TVS,SRV05-4.TCT,5V,12A,G,SOT23-6,SMD | SEMTECH CORPORATION. | SRV05-4ATCT | N | PWA BOM | In New BOM |
|  | ED2,ED3 | 2 | 521800900-227-G | DIODE,Array-TVS,SRV05-4.TCT,5V,12A,G,SOT23-6,SMD | SEMTECH CORPORATION. | SRV05-4.TCT | N | PWA BOM | In Old BOM |
| ##### Change Revision |  |  |  |  |  |  |  |  |  |
| Sheet | REV OF BOM | CUSTOMER | CUSTOMER P/N | PWA PN | PWA DESCRIPTION | PWA REV | DATE | Remark |  |
| OOOOOOOOOOOOOOOOOOOOOOOOOOOOOOOOOOOOOOOOOOOOOOOOOOOOOOOOOOOOOOOOOOOOOOOOOOOOOOOOOOOOOOOOOO | OOOOOOOOOOOOOOOOOOOOOOOOOOOOOOOOOOOOOOOOOOOOOOOOOOOOOOOOOOOOOOOOOOOOOOOOOOOOOOOOOOOOOOOOOO | OOOOOOOOOOOOOOOOOOOOOOOOOOOOOOOOOOOOOOOOOOOOOOOOOOOOOOOOOOOOOOOOOOOOOOOOOOOOOOOOOOOOOOOOOO | OOOOOOOOOOOOOOOOOOOOOOOOOOOOOOOOOOOOOOOOOOOOOOOOOOOOOOOOOOOOOOOOOOOOOOOOOOOOOOOOOOOOOOOOOO | OOOOOOOOOOOOOOOOOOOOOOOOOOOOOOOOOOOOOOOOOOOOOOOOOOOOOOOOOOOOOOOOOOOOOOOOOOOOOOOOOOOOOOOOOO | OOOOOOOOOOOOOOOOOOOOOOOOOOOOOOOOOOOOOOOOOOOOOOOOOOOOOOOOOOOOOOOOOOOOOOOOOOOOOOOOOOOOOOOOOO | OOOOOOOOOOOOOOOOOOOOOOOOOOOOOOOOOOOOOOOOOOOOOOOOOOOOOOOOOOOOOOOOOOOOOOOOOOOOOOOOOOOOOOOOOO | OOOOOOOOOOOOOOOOOOOOOOOOOOOOOOOOOOOOOOOOOOOOOOOOOOOOOOOOOOOOOOOOOOOOOOOOOOOOOOOOOOOOOOOOOO | OOOOOOOOOOOOOOOOOOOOOOOOOOOOOOOOOOOOOOOOOOOOOOOOOOOOOOOOOOOOOOOOOOOOOOOOOOOOOOOOOOOOOOOOOO | OOOOOOOOOOOOOOOOOOOOOOOOOOOOOOOOOOOOOOOOOOOOOOOOOOOOOOOOOOOOOOOOOOOOOOOOOOOOOOOOOOOOOOOOOO |
| Second Source Change |  |  |  |  |  |  |  |  |  |
| Item | Location | Change Type | Foxconn P/N | Part Description | Manufacturer Full Name | Manufacturer P/N | RoHS | Sheet |  |
| OOOOOOOOOOOOOOOOOOOOOOOOOOOOOOOOOOOOOOOOOOOOOOOOOOOOOOOOOOOOOOOOOOOOOOOOOOOOOOOOOOOOOOOOOO | OOOOOOOOOOOOOOOOOOOOOOOOOOOOOOOOOOOOOOOOOOOOOOOOOOOOOOOOOOOOOOOOOOOOOOOOOOOOOOOOOOOOOOOOOO | OOOOOOOOOOOOOOOOOOOOOOOOOOOOOOOOOOOOOOOOOOOOOOOOOOOOOOOOOOOOOOOOOOOOOOOOOOOOOOOOOOOOOOOOOO | OOOOOOOOOOOOOOOOOOOOOOOOOOOOOOOOOOOOOOOOOOOOOOOOOOOOOOOOOOOOOOOOOOOOOOOOOOOOOOOOOOOOOOOOOO | OOOOOOOOOOOOOOOOOOOOOOOOOOOOOOOOOOOOOOOOOOOOOOOOOOOOOOOOOOOOOOOOOOOOOOOOOOOOOOOOOOOOOOOOOO | OOOOOOOOOOOOOOOOOOOOOOOOOOOOOOOOOOOOOOOOOOOOOOOOOOOOOOOOOOOOOOOOOOOOOOOOOOOOOOOOOOOOOOOOOO | OOOOOOOOOOOOOOOOOOOOOOOOOOOOOOOOOOOOOOOOOOOOOOOOOOOOOOOOOOOOOOOOOOOOOOOOOOOOOOOOOOOOOOOOOO | OOOOOOOOOOOOOOOOOOOOOOOOOOOOOOOOOOOOOOOOOOOOOOOOOOOOOOOOOOOOOOOOOOOOOOOOOOOOOOOOOOOOOOOOOO | OOOOOOOOOOOOOOOOOOOOOOOOOOOOOOOOOOOOOOOOOOOOOOOOOOOOOOOOOOOOOOOOOOOOOOOOOOOOOOOOOOOOOOOOOO | OOOOOOOOOOOOOOOOOOOOOOOOOOOOOOOOOOOOOOOOOOOOOOOOOOOOOOOOOOOOOOOOOOOOOOOOOOOOOOOOOOOOOOOOOO |
| Master Materials Change |  |  |  |  |  |  |  |  |  |
| Item | Foxconn P/N | Orig._Usage | New_Usage | Part Description | Manufacturer Full Name | Manufacturer P/N | RoHS | Location | Sheet |
| 1 | 0438005.WRGT | 0 | 7 | Fuse,Fast acting,32V,5A,G,SMD0603 | LITTELFUSE FAR EAST PTE LTD | 0438005.WRGT | Y | (+)FS5,FS8,FS11,FS14,FS17,FS19,FS20 | PWA BOM |
| 2 | 52030DA00-237-G | 0 | 16 | DIODE,Schottky,BAT46W-7-F,100V,150mA,G,SOD123-2,SMD | DIODES INEORPORATION | BAT46W-7-F |  | (+)PBMD1,PBFD1,PBED1,PBAD1,PAMD1,PAFD1,PAED1,PAAD1,PBMD4,PBFD4,PBED4,PAMD4,PAFD4,PAED4,PBAD5,PAAD5 | PWA BOM |
| 3 | 610107A00-017-G | 722 | 713 | RES,0 Ohm,+/-5%,1/16W,G,SMD0402 | KOA SPEER ELECTRONICS, INC. | RK73Z1ETTP | N | (-)R1226,R1472,R1502,R1554,R1815,R1816,R1817,R1818,R1819 | PWA BOM |
| 4 | 61010G500-017-G | 100 | 101 | RES,10KOhm,+/-1%,1/16W,G,SMD0402 | KOA SPEER ELECTRONICS, INC. | RK73H1ETTP1002F | N | (+)PSUR2 | PWA BOM |
| 5 | 32014E200-53N-G | 0 | 2 | IC,Regulator,PI3753-00-LGIZ,ADJ,10.3A,G,LGA-108,SMD | Vicor Corporation | PI3753-00-LGIZ |  | (+)PBAU3,PAAU3 | PWA BOM |
| 6 | 610119C00-017-G | 2 | 1 | RES,130KOhm,+/-1%,1/16W,G,SMD0402 | KOA SPEER ELECTRONICS, INC. | RK73H1ETTP1303F | N | (-)PSUR4 | PWA BOM |
| 7 | 61011H500-017-G | 27 | 29 | RES,22 Ohm,+/-1%,1/16W,G,SMD0402 | KOA SPEER ELECTRONICS, INC. | RK73H1ETTP22R0F | N | (+)R1226,R1502 | PWA BOM |
| 8 | 61100QH00-017-G | 4 | 2 | RES,510 Ohm,+/-0.1%,1/16W,G,SMD0402 | KOA SPEER ELECTRONICS, INC. | RN731ETTP5100B25 | Y | (-)R1093,R1114 | PWA BOM |
| 9 | SRV05-4ATCT | 0 | 2 | DIODE,Array-TVS,SRV05-4.TCT,5V,12A,G,SOT23-6,SMD | SEMTECH CORPORATION. | SRV05-4ATCT | N | (+)ED2,ED3 | PWA BOM |
| 10 | 34068LN00-317-G | 11 | 10 | CONN,Header,Pin Header,1X3,V/T,2.54mm,30u,G,SMD-3 | MOLEX INCORPORATED | 87898-0315 |  | (-)J3 | PWA BOM |
| 11 | 620108B00-015-G | 2 | 0 | CAP,120pF,+/-5%,NPO(C0G),50V,G,SMD0402 | MURATA ELEC. NORTH AMERICA | GRM1555C1H121J | N | (-)C2184,C2185 | PWA BOM |
| 12 | 521800900-227-G | 3 | 0 | DIODE,Array-TVS,SRV05-4.TCT,5V,12A,G,SOT23-6,SMD | SEMTECH CORPORATION. | SRV05-4.TCT | N | (-)ED1,ED2,ED3 | PWA BOM |
| 13 | 730103M00-086-G | 7 | 0 | Fuse,Fast acting,32V,5A,G,SMD0603 | LITTELFUSE FAR EAST PTE LTD | 0438005.WR | Y | (-)FS5,FS8,FS11,FS14,FS17,FS19,FS20 | PWA BOM |
| 14 | 520103B00-185-G | 8 | 0 | Diode,Rectifier&Switching,MMBD1205,100V,200mA,G,SOT-23-3,SMD | FAIRCHILD SEMICONDUCTOR CORP | MMBD1205 | N | (-)PBMD1,PBFD1,PBED1,PBAD1,PAMD1,PAFD1,PAED1,PAAD1 | PWA BOM |
| 15 | 610116G00-017-G | 2 | 0 | RES,150KOhm,+/-1%,1/16W,G,SMD0402 | KOA SPEER ELECTRONICS, INC. | RK73H1ETTP1503F | N | (-)PSUR2,PSUR5 | PWA BOM |
| 16 | 610124C00-017-G | 2 | 0 | RES,57.6 Ohm,+/-1%,1/16W,G,SMD0402 | KOA SPEER ELECTRONICS, INC. | RK73H1ETTP57R6F | N | (-)R1838,R1839 | PWA BOM |
| 17 | 3406B5J00-317-G | 1 | 0 | CONN,Header,Socket,V/T,Bla,2mm,15u,G,DIP-18 | MOLEX INCORPORATED | 79107-7008 |  | (-)J10 | PWA BOM |
| 18 | 34064J800-317-G | 1 | 0 | CONN,Header,Socket,2X2,V/T,Bla,2mm,15u,G,DIP-4 | MOLEX INCORPORATED | 79107-7001 |  | (-)J13 | PWA BOM |
| 19 | PI3753-00-LGIZ | 2 | 0 | IC,Regulator,PI3753-00,ADJ,4A,G,LGA-71,SMD | Vicor Corporation | PI3753-00-LGIZ |  | (-)PBAU3,PAAU3 | PWA BOM |
| 20 | 34080F500-653-G | 1 | 0 | CONN,Switch,slide,25mA,24V,G,SMD-8 | DIPTRONICS MANUFACTURING INC. | DHN-04F-T-V-T/R |  | (-)PSUSW1 | PWA BOM |
| OOOOOOOOOOOOOOOOOOOOOOOOOOOOOOOOOOOOOOOOOOOOOOOOOOOOOOOOOOOOOOOOOOOOOOOOOOOOOOOOOOOOOOOOOO | OOOOOOOOOOOOOOOOOOOOOOOOOOOOOOOOOOOOOOOOOOOOOOOOOOOOOOOOOOOOOOOOOOOOOOOOOOOOOOOOOOOOOOOOOO | OOOOOOOOOOOOOOOOOOOOOOOOOOOOOOOOOOOOOOOOOOOOOOOOOOOOOOOOOOOOOOOOOOOOOOOOOOOOOOOOOOOOOOOOOO | OOOOOOOOOOOOOOOOOOOOOOOOOOOOOOOOOOOOOOOOOOOOOOOOOOOOOOOOOOOOOOOOOOOOOOOOOOOOOOOOOOOOOOOOOO | OOOOOOOOOOOOOOOOOOOOOOOOOOOOOOOOOOOOOOOOOOOOOOOOOOOOOOOOOOOOOOOOOOOOOOOOOOOOOOOOOOOOOOOOOO | OOOOOOOOOOOOOOOOOOOOOOOOOOOOOOOOOOOOOOOOOOOOOOOOOOOOOOOOOOOOOOOOOOOOOOOOOOOOOOOOOOOOOOOOOO | OOOOOOOOOOOOOOOOOOOOOOOOOOOOOOOOOOOOOOOOOOOOOOOOOOOOOOOOOOOOOOOOOOOOOOOOOOOOOOOOOOOOOOOOOO | OOOOOOOOOOOOOOOOOOOOOOOOOOOOOOOOOOOOOOOOOOOOOOOOOOOOOOOOOOOOOOOOOOOOOOOOOOOOOOOOOOOOOOOOOO | OOOOOOOOOOOOOOOOOOOOOOOOOOOOOOOOOOOOOOOOOOOOOOOOOOOOOOOOOOOOOOOOOOOOOOOOOOOOOOOOOOOOOOOOOO |  |
| TLA Parts Change |  |  |  |  |  |  |  |  |  |
| Item | Foxconn P/N | Qty | Part Description | Manufacturer Full Name | Manufacturer P/N | RoHS | Location | Remark |  |
| BOM Change List Date:Tue Aug 08 16:13:03 CST 2017 |  |  |  |  |  |  |  |  |  |
| New BOM file : C:\<user>\0803.xls |  |  |  |  |  |  |  |  |  |
| Old BOM file : C:\<user>\BG2 OLD.xls |  |  |  |  |  |  |  |  |  |
| ##### Add Parts |  |  |  |  |  |  |  |  |  |
| Item | Location | Qty | Foxconn P/N | Part Description | Manufacturer Full Name | Manufacturer P/N | RoHS | Sheet |  |
| 1 | PBMD4,PBFD4,PBED4,PAMD4,PAFD4,PAED4,PBAD5,PAAD5 | 8 | 52030DA00-237-G | DIODE,Schottky,BAT46W-7-F,100V,150mA,G,SOD123-2,SMD | DIODES INEORPORATION | BAT46W-7-F | G | PWA BOM |  |
| ##### Remove Parts |  |  |  |  |  |  |  |  |  |
| Item | Location | Qty | Foxconn P/N | Part Description | Manufacturer Full Name | Manufacturer P/N | RoHS | Sheet |  |
| 1 | C2126,C2127 | 2 | 620103700-015-G | CAP,100nF,+/-10%,X7R,10V,G,SMD0402 | MURATA ELEC. NORTH AMERICA | GRM155R71A104K | G | PWA BOM |  |
|  |  |  | 620103700-012-G | CAP,0.1uF,+/-10%,X7R,10V,G,SMD0402 | WALSIN TECHNOLOGY CORPORATION | 0402B104K100CT | G | PWA BOM |  |
|  |  |  | 620103700-023-G | CAP,100nF,+/-10%,X7R,10V,G,SMD0402 | TAIYO ELECTRIC IND.CO.LTD | LMK105B7104KV-F | G | PWA BOM |  |
|  |  |  | 620103700-026-G | CAP,100nF,+/-10%,X7R,10V,G,SMD0402 | SAMSUNG SEMICONDUCTOR | CL05B104KP5NNNC | G | PWA BOM |  |
| 2 | C2184,C2185 | 2 | 620108B00-015-G | CAP,120pF,+/-5%,NPO(C0G),50V,G,SMD0402 | MURATA ELEC. NORTH AMERICA | GRM1555C1H121J | G | PWA BOM |  |
|  |  |  | 620108B00-012-G | CAP,120pF,+/-5%,NPO(C0G),50V,G,SMD0402 | WALSIN TECHNOLOGY CORPORATION | 0402N121J500LT | G | PWA BOM |  |
|  |  |  | 620108B00-026-G | CAP,120pF,+/-5%,NPO(C0G),50V,G,SMD0402 | SAMSUNG SEMICONDUCTOR | CL05C121JB5NNNC | G | PWA BOM |  |
| 3 | ED1 | 1 | 521800900-227-G | DIODE,Array-TVS,SRV05-4.TCT,5V,12A,G,SOT23-6,SMD | SEMTECH CORPORATION. | SRV05-4.TCT | G | PWA BOM |  |
|  |  |  | 52180C200-086-G | Diode,Array-TVS,SRV05-4HTG,SOT-23,6P,G | LITTELFUSE FAR EAST PTE LTD | SRV05-4HTG | G | PWA BOM |  |
| 4 | R1472,R1554,R1556,R1815,R1816,R1817,R1818,R1819 | 8 | 610107A00-017-G | RES,0 Ohm,+/-5%,1/16W,G,SMD0402 | KOA SPEER ELECTRONICS, INC. | RK73Z1ETTP | G | PWA BOM |  |
|  |  |  | 610107A00-012-G | RES,0 Ohm,+/-5%,1/16W,G,SMD0402 | WALSIN TECHNOLOGY CORPORATION | WR04X000PTL | G | PWA BOM |  |
|  |  |  | 610107A00-011-G | RES,0 Ohm,+/-5%,1/16W,G,SMD0402 | YAGEO CORPORATION COMPONENT | RC0402JR-070RL | G | PWA BOM |  |
|  |  |  | 610107A00-044-G | RES,0 Ohm,+/-5%,1/16W,G,SMD0402 | TA-I TECHNOLOGY CO., LTD | RM04JTN0 | G | PWA BOM |  |
|  |  |  | 610107A00-024-G | RES,0 Ohm,+/-5%,1/16W,G,SMD0402 | PANASONIC INDUSTRIAL CO.,LTD. | ERJ2GE0R00X | G | PWA BOM |  |
|  |  |  | 610107A00-029-G | RES,0 Ohm,+/-5%,1/16W,G,SMD0402 | VISHAY ENTER TECHNO LOGY.INC | CRCW04020000Z0ED | G | PWA BOM |  |
| 5 | PSUR4 | 1 | 610119C00-017-G | RES,130KOhm,+/-1%,1/16W,G,SMD0402 | KOA SPEER ELECTRONICS, INC. | RK73H1ETTP1303F | G | PWA BOM |  |
|  |  |  | 610119C00-011-G | RES,130KOhm,+/-1%,1/16W,G,SMD0402 | YAGEO CORPORATION COMPONENT | RC0402FR-07130KL | G | PWA BOM |  |
|  |  |  | 610119C00-012-G | RES,130KOhm,+/-1%,1/16W,G,SMD0402 | WALSIN TECHNOLOGY CORPORATION | WR04X1303FTL | G | PWA BOM |  |
|  |  |  | 610119C00-044-G | RES,130KOhm,+/-1%,1/16W,G,SMD0402 | TA-I TECHNOLOGY CO., LTD | RM04FTN1303 | G | PWA BOM |  |
| 6 | PSUR5 | 1 | 610116G00-017-G | RES,150KOhm,+/-1%,1/16W,G,SMD0402 | KOA SPEER ELECTRONICS, INC. | RK73H1ETTP1503F | G | PWA BOM |  |
|  |  |  | 610116G00-011-G | RES,150KOhm,+/-1%,1/16W,G,SMD0402 | YAGEO CORPORATION COMPONENT | RC0402FR-07150KL | G | PWA BOM |  |
|  |  |  | 610116G00-012-G | RES,150KOhm,+/-1%,1/16W,G,SMD0402 | WALSIN TECHNOLOGY CORPORATION | WR04X1503FTL | G | PWA BOM |  |
|  |  |  | 610116G00-044-G | RES,150KOhm,+/-1%,1/16W,G,SMD0402 | TA-I TECHNOLOGY CO., LTD | RM04FTN1503 | G | PWA BOM |  |
| 7 | R114,R115,R117,R121 | 4 | 610102700-017-G | RES,49.9 Ohm,+/-1%,1/16W,G,SMD0402 | KOA SPEER ELECTRONICS, INC. | RK73H1ETTP49R9F | G | PWA BOM |  |
|  |  |  | 610102700-012-G | RES,49.9 Ohm,+/-1%,1/16W,G,SMD0402 | WALSIN TECHNOLOGY CORPORATION | WR04X49R9FTL | G | PWA BOM |  |
|  |  |  | 610102700-011-G | RES,49.9 Ohm,+/-1%,1/16W,G,SMD0402 | YAGEO CORPORATION COMPONENT | RC0402FR-0749R9L | G | PWA BOM |  |
|  |  |  | 610102700-044-G | RES,49.9 Ohm,+/-1%,1/16W,G,SMD0402 | TA-I TECHNOLOGY CO., LTD | RM04FTN49R9 | G | PWA BOM |  |
|  |  |  | 610102700-029-G | RES,49.9 Ohm,+/-1%,1/16W,G,SMD0402 | VISHAY ENTER TECHNO LOGY.INC | CRCW040249R9FKED | G | PWA BOM |  |
|  |  |  | 610102700-024-G | RES,49.9 Ohm,+/-1%,1/16W,G,SMD0402 | PANASONIC INDUSTRIAL CO.,LTD. | ERJ2RKF49R9X | G | PWA BOM |  |
| 8 | R470 | 1 | 61010KJ00-017-G | RES,3.3KOhm,+/-5%,1/16W,G,SMD0402 | KOA SPEER ELECTRONICS, INC. | RK73B1ETTP332J | G | PWA BOM |  |
|  |  |  | 61010KJ00-012-G | RES,3.3KOhm,+/-5%,1/16W,G,SMD0402 | WALSIN TECHNOLOGY CORPORATION | WR04X332JTL | G | PWA BOM |  |
|  |  |  | 61010KJ00-011-G | RES,3.3KOhm,+/-5%,1/16W,G,SMD0402 | YAGEO CORPORATION COMPONENT | RC0402JR-073K3L | G | PWA BOM |  |
|  |  |  | 61010KJ00-044-G | RES,3.3KOhm,+/-5%,1/16W,G,SMD0402 | TA-I TECHNOLOGY CO., LTD | RM04JTN332 | G | PWA BOM |  |
|  |  |  | 61010KJ00-024-G | RES,3.3KOhm,+/-5%,1/16W,G,SMD0402 | PANASONIC INDUSTRIAL CO.,LTD. | ERJ2GEJ332X | G | PWA BOM |  |
| 9 | R1093,R1114 | 2 | 61100QH00-017-G | RES,510 Ohm,+/-0.1%,1/16W,G,SMD0402 | KOA SPEER ELECTRONICS, INC. | RN731ETTP5100B25 | G | PWA BOM |  |
|  |  |  | 61100QH00-012-G | RES,510 Ohm,+/-0.1%,1/16W,G,SMD0402 | WALSIN TECHNOLOGY CORPORATION | WF04U5100BTL | G | PWA BOM |  |
|  |  |  | 61100QH00-011-G | RES,510 Ohm,+/-0.1%,1/16W,G,SMD0402 | YAGEO CORPORATION COMPONENT | RT0402BRD07510RL | G | PWA BOM |  |
| 10 | R1838,R1839 | 2 | 610124C00-017-G | RES,57.6 Ohm,+/-1%,1/16W,G,SMD0402 | KOA SPEER ELECTRONICS, INC. | RK73H1ETTP57R6F | G | PWA BOM |  |
|  |  |  | 610124C00-012-G | RES,57.6 Ohm,+/-1%,1/16W,G,SMD0402 | WALSIN TECHNOLOGY CORPORATION | WR04X57R6FTL | G | PWA BOM |  |
|  |  |  | 610124C00-011-G | RES,57.6 Ohm,+/-1%,1/16W,G,SMD0402 | YAGEO CORPORATION COMPONENT | RC0402FR-0757R6L | G | PWA BOM |  |
| 11 | U172 | 1 | 32050Q900-031-G | IC,LED Driver,PCA9551PW,G,TSSOP-16,SMD | NXP SEMICONDUCTORS | PCA9551PW | G | PWA BOM |  |
| 12 | U173 | 1 | 310203U00-223-G | IC,Trigger,NL17SZ14DFT2G,1.65~5.5V,G,SOT353-5,SMD | ON SEMICONDUCTOR CORP | NL17SZ14DFT2G | G | PWA BOM |  |
|  |  |  | 310200900-185-G | IC,Trigger,NC7SZ14P5X,1.65-5.5V,G,SC70-5P,SMD | FAIRCHILD SEMICONDUCTOR CORP | NC7SZ14P5X | G | PWA BOM |  |
|  |  |  | 310107000-031-G | Logic IC,Gate&Inverter,74LVC1G14GW,1.65V~5.5V,14ns,TSSOP,5P,G | NXP SEMICONDUCTORS | 74LVC1G14GW | G | PWA BOM |  |
| 13 | J3 | 1 | 34068LN00-317-G | CONN,Header,Pin Header,1X3,V/T,2.54mm,30u,G,SMD-3 | MOLEX INCORPORATED | 87898-0315 | G | PWA BOM |  |
|  |  |  | 34068HT00-245-G | CONN,Header,Pin Header,1X3,V/T,Bla,2.54mm,30u,SMD-3 | AMPHENOL SHANGHAI CORP. | G800MU305010EU | G | PWA BOM |  |
|  |  |  | 34068GU00-309-G | CONN,Header,Pin Header,1X3,V/T,Bla,2.54mm,30u,SMD-3 | SAMTEC INC. | TSM-103-01-S-SV-P-TR | G | PWA BOM |  |
| 14 | J102 | 1 | 340653G00-317-G | CONN,Header,Shrouded,2X11,V/T,Bla,2mm,30u,G,SMD-22 | MOLEX INCORPORATED | 87832-6023 | G | PWA BOM |  |
| 15 | J103 | 1 | 3406ALY00-317-G | CONN,Header,Shrouded,2X6,V/T,Bla,2mm,30u,G,SMD-12 | MOLEX INCORPORATED | 87832-5523 | G | PWA BOM |  |
| 16 | PSUSW1 | 1 | 34080F500-653-G | CONN,Switch,slide,25mA,24V,G,SMD-8 | DIPTRONICS MANUFACTURING INC. | DHN-04F-T-V-T/R | G | PWA BOM |  |
| ##### Change Parts |  |  |  |  |  |  |  |  |  |
| Item | Location | Qty | Foxconn P/N | Part Description | Manufacturer Full Name | Manufacturer P/N | RoHS | Sheet | Remark |
| 1 | PSUFS1,PBAFS1,PAAFS1,PSUFS2 | 4 | 730100M00-086-G | Fuse,Very fast acting,125V,10A,G,SMD | LITTELFUSE FAR EAST PTE LTD | 0451010.MRL | G | PWA BOM | In New BOM |
|  |  |  | 730109A00-088-G | Fuse,Fast acting,125V,10A,G,SMD | COOPER BUSSMANN, INC. | CB61F10A-TR2 | G | PWA BOM | In New BOM |
|  | PSUFS1,PBAFS1,PAAFS1,PSUFS2 | 4 | 730100M00-086-G | Fuse,Very fast acting,125V,10A,G,SMD | LITTELFUSE FAR EAST PTE LTD | 0451010.MRL | G | PWA BOM | In Old BOM |
|  |  |  | CB61F10A-TR2 | Fuse,CB61F10A-TR2 | COOPER BUSSMANN, INC. | CB61F10A-TR2 | G | PWA BOM | In Old BOM |
| 2 | PBFL1,PBEL1,PAFL1,PAEL1,PBML2,PAML2 | 6 | 63035NF00-57M-G | IND,1.5uH@100KHz,+/-10%,12A,6mOhm,SHLD,G,SMD | Eaton Corporation | HCV1206-1R5-R | G | PWA BOM | In New BOM |
|  |  |  | 630362H00-065-G | IND,1.5uH@100KHz,+/-10%,12A,6.6mOhm,SHLD,G,SMD | DELTA ELECTRONICS INDUSTRIAL CO.,LTD | HMS1360-1R5 | G | PWA BOM | In New BOM |
|  | PBFL1,PBEL1,PAFL1,PAEL1,PBML2,PAML2 | 6 | 63035NF00-57M-G | IND,1.5uH@100KHz,+/-10%,12A,6mOhm,SHLD,G,SMD | Eaton Corporation | HCV1206-1R5-R | G | PWA BOM | In Old BOM |
|  |  |  | HMS1360-1R5 | IND,1.5uH@100KHz,+/-10%,12A,6mOhm,SHLD,G,SMD | DELTA ELECTRONICS INDUSTRIAL CO.,LTD | HMS1360-1R5 | G | PWA BOM | In Old BOM |
| 3 | PBNL1,PANL1 | 2 | 630330G00-088-G | IND,300nH@100KHz,+/-10%,32.5A,304.5uOhm,SHLD,G,SMD | COOPER BUSSMANN, INC. | FP0906R1-R30-R | G | PWA BOM | In New BOM |
|  |  |  | 630332A01-051-G | Coil Ind,Shielded(SHLD),300nH@100KHz,+/-10%,33A,304.5uOhm,SMD,9.2*6.2*7.8,G | PULSE ELECTRONICS (SINGAPORE) | PA3288.301HLT | G | PWA BOM | In New BOM |
|  |  |  | 630330G00-129-G | IND,300nH@100KHz,+/-10%,32.5A,290uOhm,SHLD,G,SMD | MAG.LAYERS, SCIENTIFIC-TECHNICS (KUNSHAN) CO., LTD. | MSI-900608-R30K-E | G | PWA BOM | In New BOM |
|  | PBNL1,PANL1 | 2 | 630330G00-088-G | IND,300nH@100KHz,+/-10%,32.5A,304.5uOhm,SHLD,G,SMD | COOPER BUSSMANN, INC. | FP0906R1-R30-R | G | PWA BOM | In Old BOM |
|  |  |  | 630332A01-051-G | Coil Ind,Shielded(SHLD),300nH@100KHz,+/-10%,33A,304.5uOhm,SMD,9.2*6.2*7.8,G | PULSE ELECTRONICS (SINGAPORE) | PA3288.301HLT | G | PWA BOM | In Old BOM |
|  |  |  | MSI-900608-R30K-E | IND,300nH@100KHz,+/-10%,32.5A,290uOhm,SHLD,G,SMD | MAG.LAYERS, SCIENTIFIC-TECHNICS (KUNSHAN) CO., LTD. | MSI-900608-R30K-E | G | PWA BOM | In Old BOM |
| 4 | PCIE1,PCIE5 | 2 | 10061913-102HLF | CONN,PCIE-8X,V/T,Bla,1mm,30u,G,SMD-98 | FCI CONNECTORS HONGKONG LTD. | 10061913-102HLF | G | PWA BOM | In New BOM |
|  |  |  | 340320R00-278-G | CONN,PCIE-8X,V/T,Bla,1mm,30u,G,SMD-98 | TYCO ELECTRONICS CORPORATION | 2041366-4 | G | PWA BOM | In New BOM |
|  |  |  | APCI0282-P003A | CONN,PCIE-8X,V/T,Bla,1mm,30u,G,SMD-98 | LOTES CO LTD | APCI0282-P003A | G | PWA BOM | In New BOM |
|  | PCIE1,PCIE5 | 2 | 10061913-102HLF | CONN,PCIE-8X,V/T,Bla,1mm,30u,G,SMD-98 | FCI CONNECTORS HONGKONG LTD. | 10061913-102HLF | G | PWA BOM | In Old BOM |
|  |  |  | 2041366-4 | CONN,PCIE-8X,V/T,Bla,1mm,30u,G,SMD-98 | TYCO ELECTRONICS CORPORATION | 2041366-4 | G | PWA BOM | In Old BOM |
|  |  |  | APCI0282-P003A | CONN,PCIE-8X,V/T,Bla,1mm,30u,G,SMD-98 | LOTES CO LTD | APCI0282-P003A | G | PWA BOM | In Old BOM |
| 5 | PCIE2,PCIE3,PCIE4 | 3 | 10061913-103HLF | CONN,PCIE-16X,V/T,Bla,1mm,30u,G,SMD-164 | FCI CONNECTORS HONGKONG LTD. | 10061913-103HLF | G | PWA BOM | In New BOM |
|  |  |  | 340320Q00-278-G | CONN,PCIE-16X,V/T,Bla,1mm,30u,G,SMD-164 | TYCO ELECTRONICS CORPORATION | 2041366-6 | G | PWA BOM | In New BOM |
|  |  |  | APCI0261-P001C | CONN,PCIE-16X,V/T,Bla,1mm,30u,G,SMD-164 | LOTES CO LTD | APCI0261-P001C | G | PWA BOM | In New BOM |
|  | PCIE2,PCIE3,PCIE4 | 3 | 10061913-103HLF | CONN,PCIE-16X,V/T,Bla,1mm,30u,G,SMD-164 | FCI CONNECTORS HONGKONG LTD. | 10061913-103HLF | G | PWA BOM | In Old BOM |
|  |  |  | 2041366-6 | CONN,PCIE-16X,V/T,Bla,1mm,30u,G,SMD-164 | TYCO ELECTRONICS CORPORATION | 2041366-6 | G | PWA BOM | In Old BOM |
|  |  |  | APCI0261-P001C | CONN,PCIE-16X,V/T,Bla,1mm,30u,G,SMD-164 | LOTES CO LTD | APCI0261-P001C | G | PWA BOM | In Old BOM |
| 6 | PSPL1,PIPL1,PFPL1,PEPL1 | 4 | 63032CC00-088-G | IND,1uH@100KHz,+/-20%,11A,10mOhm,SHLD,G,SMD | COOPER BUSSMANN, INC. | HCM0703-1R0-R | G | PWA BOM | In New BOM |
|  |  |  | 63035CF00-034-G | IND,1uH@100KHz,+/-20%,10A,10mOhm,SHLD,G,SMD | CYNTEC CO. LTD | CMMS063T-1R0MS | G | PWA BOM | In New BOM |
|  |  |  | 630362F00-051-G | IND,22nH@100KHz,+/-20%,19A,368uOhm,SHLD,G,SMD | PULSE ELECTRONICS (SINGAPORE) | PA4341.102NLT | G | PWA BOM | In New BOM |
|  | PSPL1,PIPL1,PFPL1,PEPL1 | 4 | 63032CC00-088-G | IND,1uH@100KHz,+/-20%,11A,10mOhm,SHLD,G,SMD | COOPER BUSSMANN, INC. | HCM0703-1R0-R | G | PWA BOM | In Old BOM |
|  |  |  | CMMS063T1R0MS | IND,CMMS063T1R0MS | CYNTEC CO. LTD | CMMS063T1R0MS | G | PWA BOM | In Old BOM |
|  |  |  | PA4341.102NLT | IND,PA4341.102NLT | PULSE ELECTRONICS (SINGAPORE) | PA4341.102NLT | G | PWA BOM | In Old BOM |
| 7 | PSPL2,PIPL2,PFPL2,PEPL2 | 4 | 630341400-088-G | IND,22nH@1MHz,+/-20%,19A,368uOhm,SHLD,G,SMD | COOPER BUSSMANN, INC. | FP0404R1-R022-R | G | PWA BOM | In New BOM |
|  |  |  | 630362G00-065-G | IND,22nH@100KHz,+/-20%,19A,0.32mOhm,SHLD,G,SMD | DELTA ELECTRONICS INDUSTRIAL CO.,LTD | HCB0430-220 | G | PWA BOM | In New BOM |
|  | PSPL2,PIPL2,PFPL2,PEPL2 | 4 | 630341400-088-G | IND,22nH@1MHz,+/-20%,19A,368uOhm,SHLD,G,SMD | COOPER BUSSMANN, INC. | FP0404R1-R022-R | G | PWA BOM | In Old BOM |
|  |  |  | HCB0430-220 | IND,22nH@1MHz,+/-20%,19A,320uOhm,SHLD,G,SMD | DELTA ELECTRONICS INDUSTRIAL CO.,LTD | HCB0430-220 | G | PWA BOM | In Old BOM |
| 8 | PQPL2,PFRL2 | 2 | 63032PP00-088-G | IND,4.7uH@100KHz,+/-20%,5.5A,40mOhm,SHLD,G,SMD | COOPER BUSSMANN, INC. | HCM0703-4R7-R | G | PWA BOM | In New BOM |
|  |  |  | 63030PW00-034-G | Coil Ind,Shielded(SHLD),4.7uH@100KHz,+/-20%,5.5A,40mOhm,SMD,7.3*6.6*3.0,G | CYNTEC CO. LTD | PCMC063T-4R7MN | G | PWA BOM | In New BOM |
|  |  |  | 63031AD04-129-G | IND,4.7uH@100KHz,+/-20%,5.5A,40mOhm,SHLD,G,SMD | MAG.LAYERS, SCIENTIFIC-TECHNICS (KUNSHAN) CO., LTD. | SPS-06CZ-4R7M-V1 | G | PWA BOM | In New BOM |
|  | PQPL2,PFRL2 | 2 | 63032PP00-088-G | IND,4.7uH@100KHz,+/-20%,5.5A,40mOhm,SHLD,G,SMD | COOPER BUSSMANN, INC. | HCM0703-4R7-R | G | PWA BOM | In Old BOM |
|  |  |  | 63030PW00-034-G | Coil Ind,Shielded(SHLD),4.7uH@100KHz,+/-20%,5.5A,40mOhm,SMD,7.3*6.6*3.0,G | CYNTEC CO. LTD | PCMC063T-4R7MN | G | PWA BOM | In Old BOM |
|  |  |  | SPS-06CZ-4R7M-V1 | IND,SPS-06CZ-4R7M-V1 | MAG.LAYERS, SCIENTIFIC-TECHNICS (KUNSHAN) CO., LTD. | SPS-06CZ-4R7M-V1 | G | PWA BOM | In Old BOM |
| 9 | PHAQ1,PHAQ2,PHAQ3 | 3 | 51031VY00-031-G | MOS N,PSMN4R8-100BSE,100V,120A,4.8m@10V,G,SOT404-3,SMD | NXP SEMICONDUCTORS | PSMN4R8-100BSE | G | PWA BOM | In New BOM |
|  |  |  | 51032HE00-185-G | MOS N,FDB047N10,100V,120A,3.9m@10V,G,TO263-3,SMD | FAIRCHILD SEMICONDUCTOR CORP | FDB047N10 | G | PWA BOM | In New BOM |
|  |  |  | SUM70040E-GE3 | MOS N,SUM70040E-GE3,100V,120A,4.0m@10V,G,TO263-3,SMD | VISHAY ENTER TECHNO LOGY.INC | SUM70040E-GE3 | G | PWA BOM | In New BOM |
|  | PHAQ1,PHAQ2,PHAQ3 | 3 | 51031VY00-031-G | MOS N,PSMN4R8-100BSE,100V,120A,4.8m@10V,G,SOT404-3,SMD | NXP SEMICONDUCTORS | PSMN4R8-100BSE | G | PWA BOM | In Old BOM |
|  |  |  | FDB047N10 | MOS N,FDB047N10,100V,120A,3.9m@10V,G,TO263-3,SMD | FAIRCHILD SEMICONDUCTOR CORP | FDB047N10 | G | PWA BOM | In Old BOM |
|  |  |  | SUM70040E-GE3 | MOS N,SUM70040E-GE3,100V,120A,4.0m@10V,G,TO263-3,SMD | VISHAY ENTER TECHNO LOGY.INC | SUM70040E-GE3 | G | PWA BOM | In Old BOM |
| 10 | PHAQ4 | 1 | 51020A000-031-G | TRANS P,PBHV9115T,150V,1A,G,SOT23-3,SMD | NXP SEMICONDUCTORS | PBHV9115T | G | PWA BOM | In New BOM |
|  |  |  | 51020BJ00-185-G | Trans PNP,MMBT5401,-150V,-600mA,G,SOT-23-3,SMD | FAIRCHILD SEMICONDUCTOR CORP | MMBT5401 | G | PWA BOM | In New BOM |
|  |  |  | 510204N00-237-G | Trans PNP,MMBT5401-7-F,-150V,-600mA,SOT-23,3P,G | DIODES INCORPORATION | MMBT5401-7-F | G | PWA BOM | In New BOM |
|  | PHAQ4 | 1 | 51020A000-031-G | TRANS P,PBHV9115T,150V,1A,G,SOT23-3,SMD | NXP SEMICONDUCTORS | PBHV9115T | G | PWA BOM | In Old BOM |
|  |  |  | MMBT5401 | TRANS P,150V,1A,G,SOT23-3,SMD | FAIRCHILD SEMICONDUCTOR CORP | MMBT5401 | G | PWA BOM | In Old BOM |
|  |  |  | 510204N00-237-G | Trans PNP,MMBT5401-7-F,-150V,-600mA,SOT-23,3P,G | DIODES INCORPORATION | MMBT5401-7-F | G | PWA BOM | In Old BOM |
| 11 | PHAQ5,PHAQ6 | 2 | 51032D100-237-G | MOS N,DMN10H220L-7,100V,1.6A,220m@10V,G,SOT-23-3,SMD | DIODES INCORPORATION | DMN10H220L-7 | G | PWA BOM | In New BOM |
|  | PHAQ5,PHAQ6 | 2 | 51032D100-237-G | MOS N,DMN10H220L-7,100V,1.6A,220m@10V,G,SOT-23-3,SMD | DIODES INCORPORATION | DMN10H220L-7 | G | PWA BOM | In Old BOM |
|  |  |  | FQT7N10LTF | MOS N,FQT7N10LTF,100V,1.7A,220m@10V,G,SOT-23-3,SMD | FAIRCHILD SEMICONDUCTOR CORP | FQT7N10LTF | G | PWA BOM | In Old BOM |
| 12 | PSDR19 | 1 | 61100KM01-017-G | RES,15KOhm,+/-0.1%,1/16W,G,SMD0402 | KOA SPEER ELECTRONICS, INC. | RN73H1ETTP1502B25 | G | PWA BOM | In New BOM |
|  |  |  | 61100KM02-024-G | RES,15KOhm,+/-0.1%,1/16W,G,SMD0402 | PANASONIC INDUSTRIAL CO.,LTD. | ERA2AEB153X | G | PWA BOM | In New BOM |
|  | PSDR19 | 1 | 61100KM01-017-G | RES,15KOhm,+/-0.1%,1/16W,G,SMD0402 | KOA SPEER ELECTRONICS, INC. | RN73H1ETTP1502B25 | G | PWA BOM | In Old BOM |
|  |  |  | ERA2AEB153X | RES,15KOhm,+/-0.1%,1/16W,G,SMD0402 | PANASONIC INDUSTRIAL CO.,LTD. | ERA2AEB153X | G | PWA BOM | In Old BOM |
| 13 | QN2,QN3 | 2 | 510503B00-223-G | MOS N/N,NTZD3154NT1G,20V,0.54A,550m24.5V,G,SOT563-6,SMD | ON SEMICONDUCTOR CORP | NTZD3154NT1G | G | PWA BOM | In New BOM |
|  |  |  | Si1034CX-T1-GE3 | MOS N/N,Si1034CX,20V,0.5A,1ohm@4V,G,EMT-6,SMD | VISHAY ENTER TECHNO LOGY.INC | Si1034CX-T1-GE3 | G | PWA BOM | In New BOM |
|  |  |  | 51050KW00-131-G | MOS N/N,SSM6N36FE,20V,500mA,0.63@5V,G,ES6-6,SMD | TOSHIBA ELECTRONICS ASIA LTD | SSM6N36FE | G | PWA BOM | In New BOM |
|  | QN2,QN3 | 2 | 510503B00-223-G | MOS N/N,NTZD3154NT1G,20V,0.54A,550m24.5V,G,SOT563-6,SMD | ON SEMICONDUCTOR CORP | NTZD3154NT1G | G | PWA BOM | In Old BOM |
|  |  |  | Si1034CX-T1-GE3 | MOS N/N,Si1034CX,20V,0.5A,1ohm@4V,G,EMT-6,SMD | VISHAY ENTER TECHNO LOGY.INC | Si1034CX-T1-GE3 | G | PWA BOM | In Old BOM |
|  |  |  | SSM6N36FE | MOS N/N,20V,0.54A,550m24.5V,G,SOT563-6,SMD | TOSHIBA ELECTRONICS ASIA LTD | SSM6N36FE | G | PWA BOM | In Old BOM |
| 14 | R961,R962,R963,R964,R965,R967,R968,R969,R970,R975,R976,R977,R978,R985,R986,R988,R989,R992,R1003 | 19 | 61100C600-017-G | RES,1KOhm,+/-0.5%,1/16W,G,SMD0402 | KOA SPEER ELECTRONICS, INC. | RN731ETTP1001D25 | G | PWA BOM | In New BOM |
|  |  |  | 61100C603-024-G | RES,1KOhm,+/-0.5%,1/16W,G,SMD0402 | PANASONIC INDUSTRIAL CO.,LTD. | ERA2AED102X | G | PWA BOM | In New BOM |
|  |  |  | 61100C600-029-G | RES,1KOhm,+/-0.5%,1/16W,G,SMD0402 | VISHAY ENTER TECHNO LOGY.INC | MCS04020D1001DE000 | G | PWA BOM | In New BOM |
|  | R961,R962,R963,R964,R965,R967,R968,R969,R970,R975,R976,R977,R978,R985,R986,R988,R989,R992,R1003 | 19 | 61100C600-017-G | RES,1KOhm,+/-0.5%,1/16W,G,SMD0402 | KOA SPEER ELECTRONICS, INC. | RN731ETTP1001D25 | G | PWA BOM | In Old BOM |
|  |  |  | ERA2AED102X | RES,1KOhm,+/-0.5%,1/16W,G,SMD0402 | PANASONIC INDUSTRIAL CO.,LTD. | ERA2AED102X | G | PWA BOM | In Old BOM |
|  |  |  | 61100C600-029-G | RES,1KOhm,+/-0.5%,1/16W,G,SMD0402 | VISHAY ENTER TECHNO LOGY.INC | MCS04020D1001DE000 | G | PWA BOM | In Old BOM |
| 15 | R1769,R1770 | 2 | 610130300-017-G | RES,60.4 Ohm,+/-1%,1/20W,G,SMD0201 | KOA SPEER ELECTRONICS, INC. | RK73H1HTTC60R4F | G | PWA BOM | In New BOM |
|  |  |  | 610130300-029-G | RES,60.4 Ohm,+/-1%,1/20W,G,SMD0201 | VISHAY ENTER TECHNO LOGY.INC | CRCW020160R4FKED | G | PWA BOM | In New BOM |
|  |  |  | 610130300-024-G | RES,60.4 Ohm,+/-1%,1/20W,G,SMD0201 | PANASONIC INDUSTRIAL CO.,LTD. | ERJ1GNF60R4C | G | PWA BOM | In New BOM |
|  | R1769,R1770 | 2 | 610130300-017-G | RES,60.4 Ohm,+/-1%,1/20W,G,SMD0201 | KOA SPEER ELECTRONICS, INC. | RK73H1HTTC60R4F | G | PWA BOM | In Old BOM |
|  |  |  | CRCW020160R4FKED | RES,60.4 Ohm,+/-1%,1/20W,G,SMD0201 | VISHAY ENTER TECHNO LOGY.INC | CRCW020160R4FKED | G | PWA BOM | In Old BOM |
|  |  |  | 610130300-024-G | RES,60.4 Ohm,+/-1%,1/20W,G,SMD0201 | PANASONIC INDUSTRIAL CO.,LTD. | ERJ1GNF60R4C | G | PWA BOM | In Old BOM |
| 16 | U17 | 1 | 420212A00-216-G | DRAM,MT40A512M16JY-083E:B,1.2V,512M*16,1.2GHz,G,FBGA-96,SMD | MICRON SEMICONDUCTOR ASIA PTE.LTD. | MT40A512M16JY-083E:B | G | PWA BOM | In New BOM |
|  |  |  | 420214J00-220-G | DRAM,H5AN8G6NAFR-UHC,1.2V,8G,1.2GHz,G,FBGA-96,SMD | SK HYNIX | H5AN8G6NAFR-UHC | G | PWA BOM | In New BOM |
|  | U17 | 1 | 420212A00-216-G | DRAM,MT40A512M16JY-083E:B,1.2V,512M*16,1.2GHz,G,FBGA-96,SMD | MICRON SEMICONDUCTOR ASIA PTE.LTD. | MT40A512M16JY-083E:B | G | PWA BOM | In Old BOM |
|  |  |  | H5AN8G6NAFR-UHC | DRAM,1.2V,512M*16,1.2GHz,G,FBGA-96,SMD | HYNIX SEMICONDUCTOR INC | H5AN8G6NAFR-UHC | G | PWA BOM | In Old BOM |
| 17 | U24 | 1 | 41050DL00-233-G | Flash,MX25L6445EMI-10G,2.7~3.6V,64M,SPI,G,SOP-16,SMD | MACRONIX INTERNATIONAL CO.,LTD. | MX25L6445EMI-10G | G | PWA BOM | In New BOM |
|  |  |  | 41050SF00-233-G | Flash,MX25L6435EMI-10G,2.7~3.6V,64M,SPI,G,SOP-16,SMD | MACRONIX INTERNATIONAL CO.,LTD. | MX25L6435EMI-10G | G | PWA BOM | In New BOM |
|  | U24 | 1 | 41050DL00-233-G | Flash,MX25L6445EMI-10G,2.7~3.6V,64M,SPI,G,SOP-16,SMD | MACRONIX INTERNATIONAL CO.,LTD. | MX25L6445EMI-10G | G | PWA BOM | In Old BOM |
|  |  |  | 41050DW00-396-G | Flash,S25FL064P0XMFI001,2.7~3.6V,64M,SPI,G,SO-16,SMD | SPANSION INTERNATIONAL LLC | S25FL064P0XMFI001 | G | PWA BOM | In Old BOM |
|  |  |  | W25Q64JVSFIM | Flash,2.7~3.6V,64M,SPI,G,SOP-16,SMD | WINBOND | W25Q64JVSFIM | G | PWA BOM | In Old BOM |
|  |  |  | 41050SF00-233-G | Flash,MX25L6435EMI-10G,2.7~3.6V,64M,SPI,G,SOP-16,SMD | MACRONIX INTERNATIONAL CO.,LTD. | MX25L6435EMI-10G | G | PWA BOM | In Old BOM |
| 18 | U83,U101,U102 | 3 | 310500F00-031-G | IC,Buffer,74LVC07APW,1.65~5.5V,G,TSSOP-14,SMD | NXP SEMICONDUCTORS | 74LVC07APW | G | PWA BOM | In New BOM |
|  |  |  | 31050LF00-237-G | IC,Buffer,74LVC07AT14-13,1.65V~5.5V,G,TSSOP-14,SMD | DIODES INCORPORATION | 74LVC07AT14-13 | G | PWA BOM | In New BOM |
|  | U83,U101,U102 | 3 | 310500F00-031-G | IC,Buffer,74LVC07APW,1.65~5.5V,G,TSSOP-14,SMD | NXP SEMICONDUCTORS | 74LVC07APW | G | PWA BOM | In Old BOM |
|  |  |  | 74LVC07AT14-13 | IC,Buffer,74LVC07A,1.65~5.5V,G,TSSOP-14,SMD | DIODES INCORPORATION | 74LVC07AT14-13 | G | PWA BOM | In Old BOM |
| 19 | U110 | 1 | 330103N00-426-G | IC,Optocoupler,PS2811-1-F3-A,G,SSOP-4,SMD | RENESAS TECHNOLOGY AMERICA INC | PS2811-1-F3-A | G | PWA BOM | In New BOM |
|  |  |  | 330102900-289-G | OPTO-IC,ISOL,LTV-217-G,SSOP,4P,G | LITE-ON TECHNOLOGY CORPORATION | LTV-217-G | G | PWA BOM | In New BOM |
|  |  |  | 330103T00-029-G | IC,Optocoupler,VOS618A-3X001T,G,SSOP-4,SMD | VISHAY ENTER TECHNO LOGY.INC | VOS618A-3X001T | G | PWA BOM | In New BOM |
|  | U110 | 1 | 330103N00-426-G | IC,Optocoupler,PS2811-1-F3-A,G,SSOP-4,SMD | RENESAS TECHNOLOGY AMERICA INC | PS2811-1-F3-A | G | PWA BOM | In Old BOM |
|  |  |  | 330102900-289-G | OPTO-IC,ISOL,LTV-217-G,SSOP,4P,G | LITE-ON TECHNOLOGY CORPORATION | LTV-217-G | G | PWA BOM | In Old BOM |
|  |  |  | VOS618A-3X001T | OPTO-IC,VOS618A-3X001T | VISHAY ENTER TECHNO LOGY.INC | VOS618A-3X001T | G | PWA BOM | In Old BOM |
| 20 | U171 | 1 | 31050KL00-031-G | IC,Buffer,74HC75PW,2.0V~6.0V,G,TSSOP-16,SMD | NXP SEMICONDUCTORS | 74HC75PW | G | PWA BOM | In New BOM |
|  |  |  | 311007400-183-G | IC,Translator,CD74HC75PWRG4,2V~6V,G,TSSOP-16,SMD | Texas Instruments | CD74HC75PWRG4 | G | PWA BOM | In New BOM |
|  | U171 | 1 | 31050KL00-031-G | IC,Buffer,74HC75PW,2.0V~6.0V,G,TSSOP-16,SMD | NXP SEMICONDUCTORS | 74HC75PW | G | PWA BOM | In Old BOM |
|  |  |  | CD74HC75PWRG4 | IC,Buffer,CD74HC75PWRG4,2.0V~6.0V,G,TSSOP-16,SMD | Texas Instruments | CD74HC75PWRG4 | G | PWA BOM | In Old BOM |
| 21 | X2 | 1 | 71010SY00-107-G | XTAL,25MHz,+/-30ppm,20pF,G,SMD | DAISHINKU CORPORATION/DAISHINKU SINGAPORE PTE LTD/KDS | 1Y725000CC1G | G | PWA BOM | In New BOM |
|  |  |  | 71012JL00-873-G | XTAL,25MHz,+/-30ppm,20pF,G,SMD-2P | KYOCERA ELCO CORPORATION | CX5032GA25000R0KDQZ1 | G | PWA BOM | In New BOM |
|  | X2 | 1 | 71010SY00-107-G | XTAL,25MHz,+/-30ppm,20pF,G,SMD | DAISHINKU CORPORATION/DAISHINKU SINGAPORE PTE LTD/KDS | 1Y725000CC1G | G | PWA BOM | In Old BOM |
|  |  |  | CX5032GA25000R0KDQ | XTAL,25MHz,+/-30ppm,20pF,G,SMD-2P | Kyocera | CX5032GA25000R0KDQZ1 | G | PWA BOM | In Old BOM |
| 22 | X3 | 1 | 710113800-100-G | XTAL,24MHz,+/-30ppm,20pF,G,SMD | TXC CORPORATION | 7B24000038 | G | PWA BOM | In New BOM |
|  |  |  | 71012JK00-873-G | XTAL,24MHz,+/-30ppm,20pF,G,SMD | KYOCERA ELCO CORPORATION | CX5032SB24000R0KZQ01 | G | PWA BOM | In New BOM |
|  | X3 | 1 | 710113800-100-G | XTAL,24MHz,+/-30ppm,20pF,G,SMD | TXC CORPORATION | 7B24000038 | G | PWA BOM | In Old BOM |
|  |  |  | CX5032SB24000R0KZQ | XTAL,24MHz,+/-30ppm,20pF,G,SMD | Kyocera | CX5032SB24000R0KZQ01 |  | PWA BOM | In Old BOM |
| 23 | X6 | 1 | 710106900-162-G | XTAL,32.768KHz,+/-20ppm,12.5pF,G,SMD | EPSON ELECTRONICS AMERICA,INC. | Q13FC1350000400 | G | PWA BOM | In New BOM |
|  |  |  | 710110M00-873-G | XTAL,32.768KHz,+/-20ppm,12.5pF,G,SMD | KYOCERA ELCO CORPORATION | ST3215SB32768H5HPWAA | G | PWA BOM | In New BOM |
|  |  |  | 710123400-061-G | XTAL,32.768KHz,+/-20ppm,12.5pF,-40_x0003_~85_x0003_,SMD,G | TAITIEN | 06172-W-052-3 | G | PWA BOM | In New BOM |
|  | X6 | 1 | 710106900-162-G | XTAL,32.768KHz,+/-20ppm,12.5pF,G,SMD | EPSON ELECTRONICS AMERICA,INC. | Q13FC1350000400 | G | PWA BOM | In Old BOM |
|  |  |  | ST3215SB32768H5HPW | XTAL,32.768KHz,+/-20ppm,12.5pF,G,SMD | Kyocera | ST3215SB32768H5HPWAA | G | PWA BOM | In Old BOM |
|  |  |  | 710123400-061-G | XTAL,32.768KHz,+/-20ppm,12.5pF,-40℃~85℃,SMD,G | TAITIEN | 06172-W-052-3 | G | PWA BOM | In Old BOM |
| 24 | Y2 | 1 | 71020Q600-16G-G | OSC,50MHz,50ppm,3.3V,G,SMD | SiTime Corporation | SIT1602AC-23-33E-50.000000T | G | PWA BOM | In New BOM |
|  |  |  | 71012DA00-100-G | OSC,50MHz,+/-25ppm,15pF,G,SMD | TXC CORPORATION | 7X50000015 | G | PWA BOM | In New BOM |
|  |  |  | 710216Q00-098-G | OSC,50MHz,50ppm,3.3V,G,SMD | HARMONY (HELE) | SSW050000I3CHE-ST7R2 | G | PWA BOM | In New BOM |
|  |  |  | 710216P00-873-G | OSC,50MHz,50ppm,3.3V,G,SMD | Kyocera | KC3225K50.0000C1GE00 | G | PWA BOM | In New BOM |
|  | Y2 | 1 | 71020Q600-16G-G | OSC,50MHz,50ppm,3.3V,G,SMD | SiTime Corporation | SIT1602AC-23-33E-50.000000T | G | PWA BOM | In Old BOM |
|  |  |  | 71012DA00-100-G | OSC,50MHz,+/-25ppm,15pF,G,SMD | TXC CORPORATION | 7X50000015 |  | PWA BOM | In Old BOM |
|  |  |  | SSW050000I3CHE | OSC,50MHz,50ppm,3.3V,G,SMD | HARMONY (HELE) | SSW050000I3CHE-ST7R2 |  | PWA BOM | In Old BOM |
|  |  |  | KC3225K50.0000C1GE | OSC,50MHz,50ppm,3.3V,G,SMD | Kyocera | KC3225K50.0000C1GE00 |  | PWA BOM | In Old BOM |
| 25 | Y4 | 1 | 71020KL00-100-G | OSC,33MHz,+/-50ppm,3.3V,15pF,G,SMD | TXC CORPORATION | 7X33000013 | G | PWA BOM | In New BOM |
|  |  |  | 710211800-967-G | OSC,33MHz,+/-50ppm,3.3V,15pF,G,SMD | eCERA | FK3300011 | G | PWA BOM | In New BOM |
|  |  |  | 710216N00-873-G | OSC,33MHz,+/-50ppm,3.3V,15pF,G,SMD | Kyocera | KC3225K33.0000C10E00 | G | PWA BOM | In New BOM |
|  | Y4 | 1 | 71020KL00-100-G | OSC,33MHz,+/-50ppm,3.3V,15pF,G,SMD | TXC CORPORATION | 7X33000013 | G | PWA BOM | In Old BOM |
|  |  |  | 710211800-967-G | OSC,33MHz,+/-50ppm,3.3V,15pF,G,SMD | eCERA | FK3300011 | G | PWA BOM | In Old BOM |
|  |  |  | KC3225K33.0000C10E | OSC,33MHz,+/-50ppm,3.3V,15pF,G,SMD | Kyocera | KC3225K33.0000C10E00 | G | PWA BOM | In Old BOM |
| 26 | DIMM01,DIMM03,DIMM05,DIMM07,DIMM08,DIMM10,DIMM12,DIMM14,DIMM17,DIMM19,DIMM21,DIMM23,DIMM24,DIMM26,DIMM28,DIMM30 | 16 | 34021BD00-G78-G | CONN,DDR IV,V/T,1.2V,Bla,0.85mm,15u,G,SMD-288 | FCI CONNECTORS HONGKONG LTD. | 10140702-0301K11LF | G | PWA BOM | In New BOM |
|  |  |  | ADDR0245-P009C | CONN,DDR IV,V/T,1.2V,Bla,0.85mm,15u,G,SMD-288 | LOTES CO LTD | ADDR0245-P009C | G | PWA BOM | In New BOM |
|  |  |  | 34021CF00-600-G | Memory Connector,AH58897-T2B21-3F,DDR IV,288,SMD,THERMOPLASTIC,0.85mm,15u",Black,G | FOXCONN TECHNOLOGY CO.,LTD. | AH58897-T2B21-3F | G | PWA BOM | In New BOM |
|  |  |  | 34021CE00-245-G | Memory Connector,DDR4288S0511H,DDR IV,288,SMD,NYLON,0.85mm,15u",Black,G | AMPHENOL SHANGHAI CORP. | DDR4288S0511H | G | PWA BOM | In New BOM |
|  | DIMM01,DIMM03,DIMM05,DIMM07,DIMM08,DIMM10,DIMM12,DIMM14,DIMM17,DIMM19,DIMM21,DIMM23,DIMM24,DIMM26,DIMM28,DIMM30 | 16 | 34021BD00-G78-G | CONN,DDR IV,V/T,1.2V,Bla,0.85mm,15u,G,SMD-288 | FCI CONNECTORS HONGKONG LTD. | 10140702-0301K11LF | G | PWA BOM | In Old BOM |
|  |  |  | ADDR0245-P009C | CONN,DDR IV,V/T,1.2V,Bla,0.85mm,15u,G,SMD-288 | LOTES CO LTD | ADDR0245-P009C |  | PWA BOM | In Old BOM |
|  |  |  | 34021CF00-600-G | Memory Connector,AH58897-T2B21-3F,DDR IV,288,SMD,THERMOPLASTIC,0.85mm,15u",Black,G | FOXCONN TECHNOLOGY CO.,LTD. | AH58897-T2B21-3F | G | PWA BOM | In Old BOM |
|  |  |  | 34021CE00-245-G | Memory Connector,DDR4288S0511H,DDR IV,288,SMD,NYLON,0.85mm,15u",Black,G | AMPHENOL SHANGHAI CORP. | DDR4288S0511H | G | PWA BOM | In Old BOM |
| 27 | J35,J37,J39,J42,J45 | 5 | 3406AQH00-317-G | CONN,Header,Pin Header,1X6,V/T,Bla,2.54mm,G,SMD-6 | MOLEX INCORPORATED | 87898-0656 | G | PWA BOM | In New BOM |
|  |  |  | 3406BAS00-245-G | CONN,Header,Pin Header,1X6,V/T,Bla,2.54mm,G,SMD-6 | AMPHENOL SHANGHAI CORP. | G800MR302032HR | G | PWA BOM | In New BOM |
|  |  |  | 3406A9F00-GRT-G | Header&Socket Connector,212-91-06GBE2,Pin Header,6,SMD,NY6T,2.54mm,3u",Black,G | PINREX TECHNOLOGY CORP. | 212-91-06GBE2 | G | PWA BOM | In New BOM |
|  | J35,J37,J39,J42,J45 | 5 | 3406AQH00-317-G | CONN,Header,Pin Header,1X6,V/T,Bla,2.54mm,G,SMD-6 | MOLEX INCORPORATED | 87898-0656 | G | PWA BOM | In Old BOM |
|  |  |  | G800MR302032HR | Header&Socket Connector,G800MR302032HR,Pin Header,6,DIP,LCP,2.54mm,999.9999u",Black,G | AMPHENOL SHANGHAI CORP. | G800MR302032HR | G | PWA BOM | In Old BOM |
|  |  |  | 3406A9F00-GRT-G | Header&Socket Connector,212-91-06GBE2,Pin Header,6,SMD,NY6T,2.54mm,3u",Black,G | PINREX TECHNOLOGY CORP. | 212-91-06GBE2 | G | PWA BOM | In Old BOM |
| 28 | PBAR65,PAAR65 | 2 | TLRH3APTTE20L0F | RES,20mOhm,+/-1%,2W,G,SMD2512 | KOA SPEER ELECTRONICS, INC. | TLRH3APTTE20L0F | G | PWA BOM | In New BOM |
|  |  |  | LRMAP2512-R02FT4 | RES,20mOhm,+/-1%,2W,G,SMD2512 | INTERNATIONAL RESISTIVE COMPANY, INC. | LRMAP2512-R02FT4 | G | PWA BOM | In New BOM |
|  | PBAR65,PAAR65 | 2 | TLRH3APTTE20L0F | RES,20mOhm,+/-1%,2W,G,SMD2512 | KOA SPEER ELECTRONICS, INC. | TLRH3APTTE20L0F | G | PWA BOM | In Old BOM |
|  |  |  | LRMAP2512-R01FT4 | RES,20mOhm,+/-1%,2W,G,SMD2512 | INTERNATIONAL RESISTIVE COMPANY, INC. | LRMAP2512-R01FT4 | G | PWA BOM | In Old BOM |
| 29 | PCB | 1 | 0101FBQ00-000-G | PCB,Zaius-MB PVT-X04,OSP,Gre,22L,22.20*13.00,G | GOLD CIRCUIT ELECTRONICS LTD. | 0101FBQ00-000-G | G | PWA BOM | In New BOM |
|  |  |  | 0101FBQ00-000-G | PCB,Zaius-MB PVT-X04,OSP,Gre,22L,22.20*13.00,G | ZHUHAI FOUNDER PRINTED CIRCUIT BOARD（HK） DEVELOPMENT LIMITED | 0101FBQ00-000-G | G | PWA BOM | In New BOM |
|  |  |  | 0101FBQ00-000-G | PCB,Zaius-MB PVT-X04,OSP,Gre,22L,22.20*13.00,G | ISUPETASYS CO., LTD | 0101FBQ00-000-G | G | PWA BOM | In New BOM |
|  | PCB | 1 | 0101EW800-000-G | PCB,Zaius-MB DVT-X03,OSP,Blu,22L,22.20*13.00,G | GOLD CIRCUIT ELECTRONICS LTD. | 0101EW800-000-G | G | PWA BOM | In Old BOM |
|  |  |  | 0101EW800-000-G | PCB,Zaius-MB DVT-X03,OSP,Blu,22L,22.20*13.00,G | ZHUHAI FOUNDER PRINTED CIRCUIT BOARD（HK） DEVELOPMENT LIMITED | 0101EW800-000-G | G | PWA BOM | In Old BOM |
|  |  |  | 0101EW800-000-G | PCB,Zaius-MB DVT-X03,OSP,Blu,22L,22.20*13.00,G | ISUPETASYS CO., LTD | 0101EW800-000-G | G | PWA BOM | In Old BOM |
| 30 | FS5,FS8,FS11,FS14,FS17,FS19,FS20 | 7 | 0438005.WRGT | Fuse,Fast acting,32V,5A,G,SMD0603 | LITTELFUSE FAR EAST PTE LTD | 0438005.WRGT | G | PWA BOM | In New BOM |
|  |  |  | 730103M00-086-G | Fuse,Fast acting,32V,5A,G,SMD0603 | LITTELFUSE FAR EAST PTE LTD | 0438005.WR | G | PWA BOM | In New BOM |
|  |  |  | 730103M00-088-G | Fuse,Fast acting,32V,5A,SMD0603,G | COOPER BUSSMANN, INC. | CC06H5A-TR | G | PWA BOM | In New BOM |
|  | FS5,FS8,FS11,FS14,FS17,FS19,FS20 | 7 | 730103M00-086-G | Fuse,Fast acting,32V,5A,G,SMD0603 | LITTELFUSE FAR EAST PTE LTD | 0438005.WR | G | PWA BOM | In Old BOM |
|  |  |  | 730103M00-088-G | Fuse,Fast acting,32V,5A,SMD0603,G | COOPER BUSSMANN, INC. | CC06H5A-TR | G | PWA BOM | In Old BOM |
| 31 | PBMD1,PBFD1,PBED1,PBAD1,PAMD1,PAFD1,PAED1,PAAD1 | 8 | 52030DA00-237-G | DIODE,Schottky,BAT46W-7-F,100V,150mA,G,SOD123-2,SMD | DIODES INEORPORATION | BAT46W-7-F | G | PWA BOM | In New BOM |
|  | PBMD1,PBFD1,PBED1,PBAD1,PAMD1,PAFD1,PAED1,PAAD1 | 8 | 520103B00-185-G | Diode,Rectifier&Switching,MMBD1205,100V,200mA,G,SOT-23-3,SMD | FAIRCHILD SEMICONDUCTOR CORP | MMBD1205 | G | PWA BOM | In Old BOM |
|  |  |  | 52010A100-237-G | Diode,Rectifier&Switching,100V,200mA,G,SOT-23-3,SMD | DIODES INCORPORATION | MMBD3004A-7-F | G | PWA BOM | In Old BOM |
| 32 | PSUR2 | 1 | 61010G500-017-G | RES,10KOhm,+/-1%,1/16W,G,SMD0402 | KOA SPEER ELECTRONICS, INC. | RK73H1ETTP1002F | G | PWA BOM | In New BOM |
|  |  |  | 61010G500-012-G | RES,10KOhm,+/-1%,1/16W,G,SMD0402 | WALSIN TECHNOLOGY CORPORATION | WR04X1002FTL | G | PWA BOM | In New BOM |
|  |  |  | 61010G500-011-G | RES,10KOhm,+/-1%,1/16W,G,SMD0402 | YAGEO CORPORATION COMPONENT | RC0402FR-0710KL | G | PWA BOM | In New BOM |
|  |  |  | 61010G500-044-G | RES,10KOhm,+/-1%,1/16W,G,SMD0402 | TA-I TECHNOLOGY CO., LTD | RM04FTN1002 | G | PWA BOM | In New BOM |
|  |  |  | 61010G500-029-G | RES,10KOhm,+/-1%,1/16W,G,SMD0402 | VISHAY ENTER TECHNO LOGY.INC | CRCW040210K0FKED | G | PWA BOM | In New BOM |
|  |  |  | 61010G500-024-G | RES,10KOhm,+/-1%,1/16W,G,SMD0402 | PANASONIC INDUSTRIAL CO.,LTD. | ERJ2RKF1002X | G | PWA BOM | In New BOM |
|  | PSUR2 | 1 | 610116G00-017-G | RES,150KOhm,+/-1%,1/16W,G,SMD0402 | KOA SPEER ELECTRONICS, INC. | RK73H1ETTP1503F | G | PWA BOM | In Old BOM |
|  |  |  | 610116G00-011-G | RES,150KOhm,+/-1%,1/16W,G,SMD0402 | YAGEO CORPORATION COMPONENT | RC0402FR-07150KL | G | PWA BOM | In Old BOM |
|  |  |  | 610116G00-012-G | RES,150KOhm,+/-1%,1/16W,G,SMD0402 | WALSIN TECHNOLOGY CORPORATION | WR04X1503FTL | G | PWA BOM | In Old BOM |
|  |  |  | 610116G00-044-G | RES,150KOhm,+/-1%,1/16W,G,SMD0402 | TA-I TECHNOLOGY CO., LTD | RM04FTN1503 | G | PWA BOM | In Old BOM |
| 33 | PBMU1,PBFU1,PBEU1,PBAU1,PAMU1,PAFU1,PAEU1,PAAU1 | 8 | 320242200-230-G | IC,PWM Controller,ISL68137IRAZ-T,G,QFN-48,SMD | INTERSIL CORPORATION | ISL68137IRAZ-T | G | PWA BOM | In New BOM |
|  | PBMU1,PBFU1,PBEU1,PBAU1,PAMU1,PAFU1,PAEU1,PAAU1 | 8 | ISL68137IRAZ-GG04 | IC,PWM Controller,ISL68137IRAZ-T,G,QFN-48,SMD | INTERSIL CORPORATION | ISL68137IRAZ-GG04 | G | PWA BOM | In Old BOM |
| 34 | PBAU3,PAAU3 | 2 | 32014E200-53N-G | IC,Regulator,PI3753-00-LGIZ,ADJ,10.3A,G,LGA-108,SMD | Vicor Corporation | PI3753-00-LGIZ | G | PWA BOM | In New BOM |
|  | PBAU3,PAAU3 | 2 | PI3753-00-LGIZ | IC,Regulator,PI3753-00,ADJ,4A,G,LGA-71,SMD | Vicor Corporation | PI3753-00-LGIZ | G | PWA BOM | In Old BOM |
| 35 | R1226,R1502 | 2 | 61011H500-017-G | RES,22 Ohm,+/-1%,1/16W,G,SMD0402 | KOA SPEER ELECTRONICS, INC. | RK73H1ETTP22R0F | G | PWA BOM | In New BOM |
|  |  |  | 61011H500-012-G | RES,22 Ohm,+/-1%,1/16W,G,SMD0402 | WALSIN TECHNOLOGY CORPORATION | WR04X22R0FTL | G | PWA BOM | In New BOM |
|  |  |  | 61011H500-011-G | RES,22 Ohm,+/-1%,1/16W,G,SMD0402 | YAGEO CORPORATION COMPONENT | RC0402FR-0722RL | G | PWA BOM | In New BOM |
|  |  |  | 61011H500-044-G | RES,22 Ohm,+/-1%,1/16W,G,SMD0402 | TA-I TECHNOLOGY CO., LTD | RM04FTN22R0 | G | PWA BOM | In New BOM |
|  |  |  | 61011H500-024-G | RES,22 Ohm,+/-1%,1/16W,G,SMD0402 | PANASONIC INDUSTRIAL CO.,LTD. | ERJ2RKF22R0X | G | PWA BOM | In New BOM |
|  | R1226,R1502 | 2 | 610107A00-017-G | RES,0 Ohm,+/-5%,1/16W,G,SMD0402 | KOA SPEER ELECTRONICS, INC. | RK73Z1ETTP | G | PWA BOM | In Old BOM |
|  |  |  | 610107A00-012-G | RES,0 Ohm,+/-5%,1/16W,G,SMD0402 | WALSIN TECHNOLOGY CORPORATION | WR04X000PTL | G | PWA BOM | In Old BOM |
|  |  |  | 610107A00-011-G | RES,0 Ohm,+/-5%,1/16W,G,SMD0402 | YAGEO CORPORATION COMPONENT | RC0402JR-070RL | G | PWA BOM | In Old BOM |
|  |  |  | 610107A00-044-G | RES,0 Ohm,+/-5%,1/16W,G,SMD0402 | TA-I TECHNOLOGY CO., LTD | RM04JTN0 | G | PWA BOM | In Old BOM |
|  |  |  | 610107A00-024-G | RES,0 Ohm,+/-5%,1/16W,G,SMD0402 | PANASONIC INDUSTRIAL CO.,LTD. | ERJ2GE0R00X | G | PWA BOM | In Old BOM |
|  |  |  | 610107A00-029-G | RES,0 Ohm,+/-5%,1/16W,G,SMD0402 | VISHAY ENTER TECHNO LOGY.INC | CRCW04020000Z0ED | G | PWA BOM | In Old BOM |
| 36 | U5 | 1 | 320241C00-183-G | IC,Power Controller,UCD90160RGCR,G,VQFN-64,SMD | TEXAS INSTRUMENTS | UCD90160RGCR | G | PWA BOM | In New BOM |
|  | U5 | 1 | UCD90160RGCR-C10 | IC,Power Controller,UCD90160RGCR,G,VQFN-64,SMD | TEXAS INSTRUMENTS | UCD90160RGCR-C10 | G | PWA BOM | In Old BOM |
| 37 | ED2,ED3 | 2 | SRV05-4ATCT | DIODE,Array-TVS,SRV05-4.TCT,5V,12A,G,SOT23-6,SMD | SEMTECH CORPORATION. | SRV05-4ATCT | G | PWA BOM | In New BOM |
|  |  |  | 521800900-227-G | DIODE,Array-TVS,SRV05-4.TCT,5V,12A,G,SOT23-6,SMD | SEMTECH CORPORATION. | SRV05-4.TCT | G | PWA BOM | In New BOM |
|  |  |  | 52180C200-086-G | Diode,Array-TVS,SRV05-4HTG,SOT-23,6P,G | LITTELFUSE FAR EAST PTE LTD | SRV05-4HTG | G | PWA BOM | In New BOM |
|  | ED2,ED3 | 2 | 521800900-227-G | DIODE,Array-TVS,SRV05-4.TCT,5V,12A,G,SOT23-6,SMD | SEMTECH CORPORATION. | SRV05-4.TCT | G | PWA BOM | In Old BOM |
|  |  |  | 52180C200-086-G | Diode,Array-TVS,SRV05-4HTG,SOT-23,6P,G | LITTELFUSE FAR EAST PTE LTD | SRV05-4HTG | G | PWA BOM | In Old BOM |
| 38 | PBER65,PAFR65,PAER65,PBFR66 | 4 | SLW1TTE50L0F | RES,50mOhm,+/-1%,1.5W,G,SMD2512 | KOA | SLW1TTE50L0F | G | PWA BOM | In New BOM |
|  |  |  | LRMAP2512-R05FT4 | RES,50mOhm,+/-1%,1.5W,G,SMD2512 | INTERNATIONAL RESISTIVE COMPANY, INC. | LRMAP2512-R05FT4 | G | PWA BOM | In New BOM |
|  | PBER65,PAFR65,PAER65,PBFR66 | 4 | SLW1TTE50L0F | RES,50mOhm,+/-1%,1.5W,G,SMD2512 | KOA SPEER ELECTRONICS, INC. | SLW1TTE50L0F | G | PWA BOM | In Old BOM |
|  |  |  | LRMAP2512-R05FT4 | RES,50mOhm,+/-1%,1.5W,G,SMD2512 | INTERNATIONAL RESISTIVE COMPANY, INC. | LRMAP2512-R05FT4 | G | PWA BOM | In Old BOM |
| 39 | PBMR34,PAMR34 | 2 | RN731ETTP3160B25 | RES,316 Ohm,+/-0.1%,1/16W,G,SMD0402 | KOA SPEER ELECTRONICS, INC. | RN731ETTP3160B25 | G | PWA BOM | In New BOM |
|  | PBMR34,PAMR34 | 2 | 61011H300-017-G | RES,316 Ohm,+/-1%,1/16W,G,SMD0402 | KOA SPEER ELECTRONICS, INC. | RK73H1ETTP3160F | G | PWA BOM | In Old BOM |
|  |  |  | 61011H300-012-G | RES,316 Ohm,+/-1%,1/16W,G,SMD0402 | WALSIN TECHNOLOGY CORPORATION | WR04X3160FTL | G | PWA BOM | In Old BOM |
|  |  |  | 61011H300-011-G | RES,316 Ohm,+/-1%,1/16W,G,SMD0402 | YAGEO CORPORATION COMPONENT | RC0402FR-07316RL | G | PWA BOM | In Old BOM |
| 40 | PBMR65,PAMR65 | 2 | SLW1TTE75L0F | RES,75mOhm,+/-1%,1.5W,G,SMD2512 | KOA | SLW1TTE75L0F | G | PWA BOM | In New BOM |
|  |  |  | LRMAP2512-R075FT4 | RES,75mOhm,+/-1%,1.5W,G,SMD2512 | INTERNATIONAL RESISTIVE COMPANY, INC. | LRMAP2512-R075FT4 | G | PWA BOM | In New BOM |
|  | PBMR65,PAMR65 | 2 | SLW1TTE75L0F | RES,75mOhm,+/-1%,1.5W,G,SMD2512 | KOA SPEER ELECTRONICS, INC. | SLW1TTE75L0F | G | PWA BOM | In Old BOM |
|  |  |  | LRMAP2512-R075FT4 | RES,75mOhm,+/-1%,1.5W,G,SMD2512 | INTERNATIONAL RESISTIVE COMPANY, INC. | LRMAP2512-R075FT4 | G | PWA BOM | In Old BOM |
| ##### Change Revision |  |  |  |  |  |  |  |  |  |
| Sheet | REV OF BOM | CUSTOMER | CUSTOMER P/N | PWA PN | PWA DESCRIPTION | PWA REV | DATE | Remark |  |
| OOOOOOOOOOOOOOOOOOOOOOOOOOOOOOOOOOOOOOOOOOOOOOOOOOOOOOOOOOOOOOOOOOOOOOOOOOOOOOOOOOOOOOOOOO | OOOOOOOOOOOOOOOOOOOOOOOOOOOOOOOOOOOOOOOOOOOOOOOOOOOOOOOOOOOOOOOOOOOOOOOOOOOOOOOOOOOOOOOOOO | OOOOOOOOOOOOOOOOOOOOOOOOOOOOOOOOOOOOOOOOOOOOOOOOOOOOOOOOOOOOOOOOOOOOOOOOOOOOOOOOOOOOOOOOOO | OOOOOOOOOOOOOOOOOOOOOOOOOOOOOOOOOOOOOOOOOOOOOOOOOOOOOOOOOOOOOOOOOOOOOOOOOOOOOOOOOOOOOOOOOO | OOOOOOOOOOOOOOOOOOOOOOOOOOOOOOOOOOOOOOOOOOOOOOOOOOOOOOOOOOOOOOOOOOOOOOOOOOOOOOOOOOOOOOOOOO | OOOOOOOOOOOOOOOOOOOOOOOOOOOOOOOOOOOOOOOOOOOOOOOOOOOOOOOOOOOOOOOOOOOOOOOOOOOOOOOOOOOOOOOOOO | OOOOOOOOOOOOOOOOOOOOOOOOOOOOOOOOOOOOOOOOOOOOOOOOOOOOOOOOOOOOOOOOOOOOOOOOOOOOOOOOOOOOOOOOOO | OOOOOOOOOOOOOOOOOOOOOOOOOOOOOOOOOOOOOOOOOOOOOOOOOOOOOOOOOOOOOOOOOOOOOOOOOOOOOOOOOOOOOOOOOO | OOOOOOOOOOOOOOOOOOOOOOOOOOOOOOOOOOOOOOOOOOOOOOOOOOOOOOOOOOOOOOOOOOOOOOOOOOOOOOOOOOOOOOOOOO | OOOOOOOOOOOOOOOOOOOOOOOOOOOOOOOOOOOOOOOOOOOOOOOOOOOOOOOOOOOOOOOOOOOOOOOOOOOOOOOOOOOOOOOOOO |
| Second Source Change |  |  |  |  |  |  |  |  |  |
| Item | Location | Change Type | Foxconn P/N | Part Description | Manufacturer Full Name | Manufacturer P/N | RoHS | Sheet |  |
| 1 | PSUFS1,PBAFS1,PAAFS1,PSUFS2 |  | 730100M00-086-G | Fuse,Very fast acting,125V,10A,G,SMD | LITTELFUSE FAR EAST PTE LTD | 0451010.MRL | G | PWA BOM |  |
|  |  | ADD | 730109A00-088-G | Fuse,Fast acting,125V,10A,G,SMD | COOPER BUSSMANN, INC. | CB61F10A-TR2 | G | PWA BOM |  |
|  |  | Delete | CB61F10A-TR2 | Fuse,CB61F10A-TR2 | COOPER BUSSMANN, INC. | CB61F10A-TR2 | G | PWA BOM |  |
| 2 | PBFL1,PBEL1,PAFL1,PAEL1,PBML2,PAML2 |  | 63035NF00-57M-G | IND,1.5uH@100KHz,+/-10%,12A,6mOhm,SHLD,G,SMD | Eaton Corporation | HCV1206-1R5-R | G | PWA BOM |  |
|  |  | ADD | 630362H00-065-G | IND,1.5uH@100KHz,+/-10%,12A,6.6mOhm,SHLD,G,SMD | DELTA ELECTRONICS INDUSTRIAL CO.,LTD | HMS1360-1R5 | G | PWA BOM |  |
|  |  | Delete | HMS1360-1R5 | IND,1.5uH@100KHz,+/-10%,12A,6mOhm,SHLD,G,SMD | DELTA ELECTRONICS INDUSTRIAL CO.,LTD | HMS1360-1R5 | G | PWA BOM |  |
| 3 | PBNL1,PANL1 |  | 630330G00-088-G | IND,300nH@100KHz,+/-10%,32.5A,304.5uOhm,SHLD,G,SMD | COOPER BUSSMANN, INC. | FP0906R1-R30-R | G | PWA BOM |  |
|  |  | NO | 630332A01-051-G | Coil Ind,Shielded(SHLD),300nH@100KHz,+/-10%,33A,304.5uOhm,SMD,9.2*6.2*7.8,G | PULSE ELECTRONICS (SINGAPORE) | PA3288.301HLT | G | PWA BOM |  |
|  |  | ADD | 630330G00-129-G | IND,300nH@100KHz,+/-10%,32.5A,290uOhm,SHLD,G,SMD | MAG.LAYERS, SCIENTIFIC-TECHNICS (KUNSHAN) CO., LTD. | MSI-900608-R30K-E | G | PWA BOM |  |
|  |  | Delete | MSI-900608-R30K-E | IND,300nH@100KHz,+/-10%,32.5A,290uOhm,SHLD,G,SMD | MAG.LAYERS, SCIENTIFIC-TECHNICS (KUNSHAN) CO., LTD. | MSI-900608-R30K-E | G | PWA BOM |  |
| 4 | PCIE1,PCIE5 |  | 10061913-102HLF | CONN,PCIE-8X,V/T,Bla,1mm,30u,G,SMD-98 | FCI CONNECTORS HONGKONG LTD. | 10061913-102HLF | G | PWA BOM |  |
|  |  | ADD | 340320R00-278-G | CONN,PCIE-8X,V/T,Bla,1mm,30u,G,SMD-98 | TYCO ELECTRONICS CORPORATION | 2041366-4 | G | PWA BOM |  |
|  |  | NO | APCI0282-P003A | CONN,PCIE-8X,V/T,Bla,1mm,30u,G,SMD-98 | LOTES CO LTD | APCI0282-P003A | G | PWA BOM |  |
|  |  | Delete | 2041366-4 | CONN,PCIE-8X,V/T,Bla,1mm,30u,G,SMD-98 | TYCO ELECTRONICS CORPORATION | 2041366-4 | G | PWA BOM |  |
| 5 | PCIE2,PCIE3,PCIE4 |  | 10061913-103HLF | CONN,PCIE-16X,V/T,Bla,1mm,30u,G,SMD-164 | FCI CONNECTORS HONGKONG LTD. | 10061913-103HLF | G | PWA BOM |  |
|  |  | ADD | 340320Q00-278-G | CONN,PCIE-16X,V/T,Bla,1mm,30u,G,SMD-164 | TYCO ELECTRONICS CORPORATION | 2041366-6 | G | PWA BOM |  |
|  |  | NO | APCI0261-P001C | CONN,PCIE-16X,V/T,Bla,1mm,30u,G,SMD-164 | LOTES CO LTD | APCI0261-P001C | G | PWA BOM |  |
|  |  | Delete | 2041366-6 | CONN,PCIE-16X,V/T,Bla,1mm,30u,G,SMD-164 | TYCO ELECTRONICS CORPORATION | 2041366-6 | G | PWA BOM |  |
| 6 | PSPL1,PIPL1,PFPL1,PEPL1 |  | 63032CC00-088-G | IND,1uH@100KHz,+/-20%,11A,10mOhm,SHLD,G,SMD | COOPER BUSSMANN, INC. | HCM0703-1R0-R | G | PWA BOM |  |
|  |  | ADD | 63035CF00-034-G | IND,1uH@100KHz,+/-20%,10A,10mOhm,SHLD,G,SMD | CYNTEC CO. LTD | CMMS063T-1R0MS | G | PWA BOM |  |
|  |  | ADD | 630362F00-051-G | IND,22nH@100KHz,+/-20%,19A,368uOhm,SHLD,G,SMD | PULSE ELECTRONICS (SINGAPORE) | PA4341.102NLT | G | PWA BOM |  |
|  |  | Delete | CMMS063T1R0MS | IND,CMMS063T1R0MS | CYNTEC CO. LTD | CMMS063T1R0MS | G | PWA BOM |  |
|  |  | Delete | PA4341.102NLT | IND,PA4341.102NLT | PULSE ELECTRONICS (SINGAPORE) | PA4341.102NLT | G | PWA BOM |  |
| 7 | PSPL2,PIPL2,PFPL2,PEPL2 |  | 630341400-088-G | IND,22nH@1MHz,+/-20%,19A,368uOhm,SHLD,G,SMD | COOPER BUSSMANN, INC. | FP0404R1-R022-R | G | PWA BOM |  |
|  |  | ADD | 630362G00-065-G | IND,22nH@100KHz,+/-20%,19A,0.32mOhm,SHLD,G,SMD | DELTA ELECTRONICS INDUSTRIAL CO.,LTD | HCB0430-220 | G | PWA BOM |  |
|  |  | Delete | HCB0430-220 | IND,22nH@1MHz,+/-20%,19A,320uOhm,SHLD,G,SMD | DELTA ELECTRONICS INDUSTRIAL CO.,LTD | HCB0430-220 | G | PWA BOM |  |
| 8 | PQPL2,PFRL2 |  | 63032PP00-088-G | IND,4.7uH@100KHz,+/-20%,5.5A,40mOhm,SHLD,G,SMD | COOPER BUSSMANN, INC. | HCM0703-4R7-R | G | PWA BOM |  |
|  |  | NO | 63030PW00-034-G | Coil Ind,Shielded(SHLD),4.7uH@100KHz,+/-20%,5.5A,40mOhm,SMD,7.3*6.6*3.0,G | CYNTEC CO. LTD | PCMC063T-4R7MN | G | PWA BOM |  |
|  |  | ADD | 63031AD04-129-G | IND,4.7uH@100KHz,+/-20%,5.5A,40mOhm,SHLD,G,SMD | MAG.LAYERS, SCIENTIFIC-TECHNICS (KUNSHAN) CO., LTD. | SPS-06CZ-4R7M-V1 | G | PWA BOM |  |
|  |  | Delete | SPS-06CZ-4R7M-V1 | IND,SPS-06CZ-4R7M-V1 | MAG.LAYERS, SCIENTIFIC-TECHNICS (KUNSHAN) CO., LTD. | SPS-06CZ-4R7M-V1 | G | PWA BOM |  |
| 9 | PHAQ1,PHAQ2,PHAQ3 |  | 51031VY00-031-G | MOS N,PSMN4R8-100BSE,100V,120A,4.8m@10V,G,SOT404-3,SMD | NXP SEMICONDUCTORS | PSMN4R8-100BSE | G | PWA BOM |  |
|  |  | ADD | 51032HE00-185-G | MOS N,FDB047N10,100V,120A,3.9m@10V,G,TO263-3,SMD | FAIRCHILD SEMICONDUCTOR CORP | FDB047N10 | G | PWA BOM |  |
|  |  | NO | SUM70040E-GE3 | MOS N,SUM70040E-GE3,100V,120A,4.0m@10V,G,TO263-3,SMD | VISHAY ENTER TECHNO LOGY.INC | SUM70040E-GE3 | G | PWA BOM |  |
|  |  | Delete | FDB047N10 | MOS N,FDB047N10,100V,120A,3.9m@10V,G,TO263-3,SMD | FAIRCHILD SEMICONDUCTOR CORP | FDB047N10 | G | PWA BOM |  |
| 10 | PHAQ4 |  | 51020A000-031-G | TRANS P,PBHV9115T,150V,1A,G,SOT23-3,SMD | NXP SEMICONDUCTORS | PBHV9115T | G | PWA BOM |  |
|  |  | ADD | 51020BJ00-185-G | Trans PNP,MMBT5401,-150V,-600mA,G,SOT-23-3,SMD | FAIRCHILD SEMICONDUCTOR CORP | MMBT5401 | G | PWA BOM |  |
|  |  | NO | 510204N00-237-G | Trans PNP,MMBT5401-7-F,-150V,-600mA,SOT-23,3P,G | DIODES INCORPORATION | MMBT5401-7-F | G | PWA BOM |  |
|  |  | Delete | MMBT5401 | TRANS P,150V,1A,G,SOT23-3,SMD | FAIRCHILD SEMICONDUCTOR CORP | MMBT5401 | G | PWA BOM |  |
| 11 | PHAQ5,PHAQ6 |  | 51032D100-237-G | MOS N,DMN10H220L-7,100V,1.6A,220m@10V,G,SOT-23-3,SMD | DIODES INCORPORATION | DMN10H220L-7 | G | PWA BOM |  |
|  |  | Delete | FQT7N10LTF | MOS N,FQT7N10LTF,100V,1.7A,220m@10V,G,SOT-23-3,SMD | FAIRCHILD SEMICONDUCTOR CORP | FQT7N10LTF | G | PWA BOM |  |
| 12 | PSDR19 |  | 61100KM01-017-G | RES,15KOhm,+/-0.1%,1/16W,G,SMD0402 | KOA SPEER ELECTRONICS, INC. | RN73H1ETTP1502B25 | G | PWA BOM |  |
|  |  | ADD | 61100KM02-024-G | RES,15KOhm,+/-0.1%,1/16W,G,SMD0402 | PANASONIC INDUSTRIAL CO.,LTD. | ERA2AEB153X | G | PWA BOM |  |
|  |  | Delete | ERA2AEB153X | RES,15KOhm,+/-0.1%,1/16W,G,SMD0402 | PANASONIC INDUSTRIAL CO.,LTD. | ERA2AEB153X | G | PWA BOM |  |
| 13 | QN2,QN3 |  | 510503B00-223-G | MOS N/N,NTZD3154NT1G,20V,0.54A,550m24.5V,G,SOT563-6,SMD | ON SEMICONDUCTOR CORP | NTZD3154NT1G | G | PWA BOM |  |
|  |  | NO | Si1034CX-T1-GE3 | MOS N/N,Si1034CX,20V,0.5A,1ohm@4V,G,EMT-6,SMD | VISHAY ENTER TECHNO LOGY.INC | Si1034CX-T1-GE3 | G | PWA BOM |  |
|  |  | ADD | 51050KW00-131-G | MOS N/N,SSM6N36FE,20V,500mA,0.63@5V,G,ES6-6,SMD | TOSHIBA ELECTRONICS ASIA LTD | SSM6N36FE | G | PWA BOM |  |
|  |  | Delete | SSM6N36FE | MOS N/N,20V,0.54A,550m24.5V,G,SOT563-6,SMD | TOSHIBA ELECTRONICS ASIA LTD | SSM6N36FE | G | PWA BOM |  |
| 14 | R961,R962,R963,R964,R965,R967,R968,R969,R970,R975,R976,R977,R978,R985,R986,R988,R989,R992,R1003 |  | 61100C600-017-G | RES,1KOhm,+/-0.5%,1/16W,G,SMD0402 | KOA SPEER ELECTRONICS, INC. | RN731ETTP1001D25 | G | PWA BOM |  |
|  |  | ADD | 61100C603-024-G | RES,1KOhm,+/-0.5%,1/16W,G,SMD0402 | PANASONIC INDUSTRIAL CO.,LTD. | ERA2AED102X | G | PWA BOM |  |
|  |  | NO | 61100C600-029-G | RES,1KOhm,+/-0.5%,1/16W,G,SMD0402 | VISHAY ENTER TECHNO LOGY.INC | MCS04020D1001DE000 | G | PWA BOM |  |
|  |  | Delete | ERA2AED102X | RES,1KOhm,+/-0.5%,1/16W,G,SMD0402 | PANASONIC INDUSTRIAL CO.,LTD. | ERA2AED102X | G | PWA BOM |  |
| 15 | R1769,R1770 |  | 610130300-017-G | RES,60.4 Ohm,+/-1%,1/20W,G,SMD0201 | KOA SPEER ELECTRONICS, INC. | RK73H1HTTC60R4F | G | PWA BOM |  |
|  |  | ADD | 610130300-029-G | RES,60.4 Ohm,+/-1%,1/20W,G,SMD0201 | VISHAY ENTER TECHNO LOGY.INC | CRCW020160R4FKED | G | PWA BOM |  |
|  |  | NO | 610130300-024-G | RES,60.4 Ohm,+/-1%,1/20W,G,SMD0201 | PANASONIC INDUSTRIAL CO.,LTD. | ERJ1GNF60R4C | G | PWA BOM |  |
|  |  | Delete | CRCW020160R4FKED | RES,60.4 Ohm,+/-1%,1/20W,G,SMD0201 | VISHAY ENTER TECHNO LOGY.INC | CRCW020160R4FKED | G | PWA BOM |  |
| 16 | U17 |  | 420212A00-216-G | DRAM,MT40A512M16JY-083E:B,1.2V,512M*16,1.2GHz,G,FBGA-96,SMD | MICRON SEMICONDUCTOR ASIA PTE.LTD. | MT40A512M16JY-083E:B | G | PWA BOM |  |
|  |  | ADD | 420214J00-220-G | DRAM,H5AN8G6NAFR-UHC,1.2V,8G,1.2GHz,G,FBGA-96,SMD | SK HYNIX | H5AN8G6NAFR-UHC | G | PWA BOM |  |
|  |  | Delete | H5AN8G6NAFR-UHC | DRAM,1.2V,512M*16,1.2GHz,G,FBGA-96,SMD | HYNIX SEMICONDUCTOR INC | H5AN8G6NAFR-UHC | G | PWA BOM |  |
| 17 | U24 |  | 41050DL00-233-G | Flash,MX25L6445EMI-10G,2.7~3.6V,64M,SPI,G,SOP-16,SMD | MACRONIX INTERNATIONAL CO.,LTD. | MX25L6445EMI-10G | G | PWA BOM |  |
|  |  | NO | 41050SF00-233-G | Flash,MX25L6435EMI-10G,2.7~3.6V,64M,SPI,G,SOP-16,SMD | MACRONIX INTERNATIONAL CO.,LTD. | MX25L6435EMI-10G | G | PWA BOM |  |
|  |  | Delete | 41050DW00-396-G | Flash,S25FL064P0XMFI001,2.7~3.6V,64M,SPI,G,SO-16,SMD | SPANSION INTERNATIONAL LLC | S25FL064P0XMFI001 | G | PWA BOM |  |
|  |  | Delete | W25Q64JVSFIM | Flash,2.7~3.6V,64M,SPI,G,SOP-16,SMD | WINBOND | W25Q64JVSFIM | G | PWA BOM |  |
| 18 | U83,U101,U102 |  | 310500F00-031-G | IC,Buffer,74LVC07APW,1.65~5.5V,G,TSSOP-14,SMD | NXP SEMICONDUCTORS | 74LVC07APW | G | PWA BOM |  |
|  |  | ADD | 31050LF00-237-G | IC,Buffer,74LVC07AT14-13,1.65V~5.5V,G,TSSOP-14,SMD | DIODES INCORPORATION | 74LVC07AT14-13 | G | PWA BOM |  |
|  |  | Delete | 74LVC07AT14-13 | IC,Buffer,74LVC07A,1.65~5.5V,G,TSSOP-14,SMD | DIODES INCORPORATION | 74LVC07AT14-13 | G | PWA BOM |  |
| 19 | U110 |  | 330103N00-426-G | IC,Optocoupler,PS2811-1-F3-A,G,SSOP-4,SMD | RENESAS TECHNOLOGY AMERICA INC | PS2811-1-F3-A | G | PWA BOM |  |
|  |  | NO | 330102900-289-G | OPTO-IC,ISOL,LTV-217-G,SSOP,4P,G | LITE-ON TECHNOLOGY CORPORATION | LTV-217-G | G | PWA BOM |  |
|  |  | ADD | 330103T00-029-G | IC,Optocoupler,VOS618A-3X001T,G,SSOP-4,SMD | VISHAY ENTER TECHNO LOGY.INC | VOS618A-3X001T | G | PWA BOM |  |
|  |  | Delete | VOS618A-3X001T | OPTO-IC,VOS618A-3X001T | VISHAY ENTER TECHNO LOGY.INC | VOS618A-3X001T | G | PWA BOM |  |
| 20 | U171 |  | 31050KL00-031-G | IC,Buffer,74HC75PW,2.0V~6.0V,G,TSSOP-16,SMD | NXP SEMICONDUCTORS | 74HC75PW | G | PWA BOM |  |
|  |  | ADD | 311007400-183-G | IC,Translator,CD74HC75PWRG4,2V~6V,G,TSSOP-16,SMD | Texas Instruments | CD74HC75PWRG4 | G | PWA BOM |  |
|  |  | Delete | CD74HC75PWRG4 | IC,Buffer,CD74HC75PWRG4,2.0V~6.0V,G,TSSOP-16,SMD | Texas Instruments | CD74HC75PWRG4 | G | PWA BOM |  |
| 21 | X2 |  | 71010SY00-107-G | XTAL,25MHz,+/-30ppm,20pF,G,SMD | DAISHINKU CORPORATION/DAISHINKU SINGAPORE PTE LTD/KDS | 1Y725000CC1G | G | PWA BOM |  |
|  |  | ADD | 71012JL00-873-G | XTAL,25MHz,+/-30ppm,20pF,G,SMD-2P | KYOCERA ELCO CORPORATION | CX5032GA25000R0KDQZ1 | G | PWA BOM |  |
|  |  | Delete | CX5032GA25000R0KDQ | XTAL,25MHz,+/-30ppm,20pF,G,SMD-2P | Kyocera | CX5032GA25000R0KDQZ1 | G | PWA BOM |  |
| 22 | X3 |  | 710113800-100-G | XTAL,24MHz,+/-30ppm,20pF,G,SMD | TXC CORPORATION | 7B24000038 | G | PWA BOM |  |
|  |  | ADD | 71012JK00-873-G | XTAL,24MHz,+/-30ppm,20pF,G,SMD | KYOCERA ELCO CORPORATION | CX5032SB24000R0KZQ01 | G | PWA BOM |  |
|  |  | Delete | CX5032SB24000R0KZQ | XTAL,24MHz,+/-30ppm,20pF,G,SMD | Kyocera | CX5032SB24000R0KZQ01 |  | PWA BOM |  |
| 23 | X6 |  | 710106900-162-G | XTAL,32.768KHz,+/-20ppm,12.5pF,G,SMD | EPSON ELECTRONICS AMERICA,INC. | Q13FC1350000400 | G | PWA BOM |  |
|  |  | ADD | 710110M00-873-G | XTAL,32.768KHz,+/-20ppm,12.5pF,G,SMD | KYOCERA ELCO CORPORATION | ST3215SB32768H5HPWAA | G | PWA BOM |  |
|  |  | NO | 710123400-061-G | XTAL,32.768KHz,+/-20ppm,12.5pF,-40_x0003_~85_x0003_,SMD,G | TAITIEN | 06172-W-052-3 | G | PWA BOM |  |
|  |  | Delete | ST3215SB32768H5HPW | XTAL,32.768KHz,+/-20ppm,12.5pF,G,SMD | Kyocera | ST3215SB32768H5HPWAA | G | PWA BOM |  |
| 24 | Y2 |  | 71020Q600-16G-G | OSC,50MHz,50ppm,3.3V,G,SMD | SiTime Corporation | SIT1602AC-23-33E-50.000000T | G | PWA BOM |  |
|  |  | NO | 71012DA00-100-G | OSC,50MHz,+/-25ppm,15pF,G,SMD | TXC CORPORATION | 7X50000015 | G | PWA BOM |  |
|  |  | ADD | 710216Q00-098-G | OSC,50MHz,50ppm,3.3V,G,SMD | HARMONY (HELE) | SSW050000I3CHE-ST7R2 | G | PWA BOM |  |
|  |  | ADD | 710216P00-873-G | OSC,50MHz,50ppm,3.3V,G,SMD | Kyocera | KC3225K50.0000C1GE00 | G | PWA BOM |  |
|  |  | Delete | SSW050000I3CHE | OSC,50MHz,50ppm,3.3V,G,SMD | HARMONY (HELE) | SSW050000I3CHE-ST7R2 |  | PWA BOM |  |
|  |  | Delete | KC3225K50.0000C1GE | OSC,50MHz,50ppm,3.3V,G,SMD | Kyocera | KC3225K50.0000C1GE00 |  | PWA BOM |  |
| 25 | Y4 |  | 71020KL00-100-G | OSC,33MHz,+/-50ppm,3.3V,15pF,G,SMD | TXC CORPORATION | 7X33000013 | G | PWA BOM |  |
|  |  | NO | 710211800-967-G | OSC,33MHz,+/-50ppm,3.3V,15pF,G,SMD | eCERA | FK3300011 | G | PWA BOM |  |
|  |  | ADD | 710216N00-873-G | OSC,33MHz,+/-50ppm,3.3V,15pF,G,SMD | Kyocera | KC3225K33.0000C10E00 | G | PWA BOM |  |
|  |  | Delete | KC3225K33.0000C10E | OSC,33MHz,+/-50ppm,3.3V,15pF,G,SMD | Kyocera | KC3225K33.0000C10E00 | G | PWA BOM |  |
| 26 | J35,J37,J39,J42,J45 |  | 3406AQH00-317-G | CONN,Header,Pin Header,1X6,V/T,Bla,2.54mm,G,SMD-6 | MOLEX INCORPORATED | 87898-0656 | G | PWA BOM |  |
|  |  | ADD | 3406BAS00-245-G | CONN,Header,Pin Header,1X6,V/T,Bla,2.54mm,G,SMD-6 | AMPHENOL SHANGHAI CORP. | G800MR302032HR | G | PWA BOM |  |
|  |  | NO | 3406A9F00-GRT-G | Header&Socket Connector,212-91-06GBE2,Pin Header,6,SMD,NY6T,2.54mm,3u",Black,G | PINREX TECHNOLOGY CORP. | 212-91-06GBE2 | G | PWA BOM |  |
|  |  | Delete | G800MR302032HR | Header&Socket Connector,G800MR302032HR,Pin Header,6,DIP,LCP,2.54mm,999.9999u",Black,G | AMPHENOL SHANGHAI CORP. | G800MR302032HR | G | PWA BOM |  |
| 27 | PBAR65,PAAR65 |  | TLRH3APTTE20L0F | RES,20mOhm,+/-1%,2W,G,SMD2512 | KOA SPEER ELECTRONICS, INC. | TLRH3APTTE20L0F | G | PWA BOM |  |
|  |  | ADD | LRMAP2512-R02FT4 | RES,20mOhm,+/-1%,2W,G,SMD2512 | INTERNATIONAL RESISTIVE COMPANY, INC. | LRMAP2512-R02FT4 | G | PWA BOM |  |
|  |  | Delete | LRMAP2512-R01FT4 | RES,20mOhm,+/-1%,2W,G,SMD2512 | INTERNATIONAL RESISTIVE COMPANY, INC. | LRMAP2512-R01FT4 | G | PWA BOM |  |
| OOOOOOOOOOOOOOOOOOOOOOOOOOOOOOOOOOOOOOOOOOOOOOOOOOOOOOOOOOOOOOOOOOOOOOOOOOOOOOOOOOOOOOOOOO | OOOOOOOOOOOOOOOOOOOOOOOOOOOOOOOOOOOOOOOOOOOOOOOOOOOOOOOOOOOOOOOOOOOOOOOOOOOOOOOOOOOOOOOOOO | OOOOOOOOOOOOOOOOOOOOOOOOOOOOOOOOOOOOOOOOOOOOOOOOOOOOOOOOOOOOOOOOOOOOOOOOOOOOOOOOOOOOOOOOOO | OOOOOOOOOOOOOOOOOOOOOOOOOOOOOOOOOOOOOOOOOOOOOOOOOOOOOOOOOOOOOOOOOOOOOOOOOOOOOOOOOOOOOOOOOO | OOOOOOOOOOOOOOOOOOOOOOOOOOOOOOOOOOOOOOOOOOOOOOOOOOOOOOOOOOOOOOOOOOOOOOOOOOOOOOOOOOOOOOOOOO | OOOOOOOOOOOOOOOOOOOOOOOOOOOOOOOOOOOOOOOOOOOOOOOOOOOOOOOOOOOOOOOOOOOOOOOOOOOOOOOOOOOOOOOOOO | OOOOOOOOOOOOOOOOOOOOOOOOOOOOOOOOOOOOOOOOOOOOOOOOOOOOOOOOOOOOOOOOOOOOOOOOOOOOOOOOOOOOOOOOOO | OOOOOOOOOOOOOOOOOOOOOOOOOOOOOOOOOOOOOOOOOOOOOOOOOOOOOOOOOOOOOOOOOOOOOOOOOOOOOOOOOOOOOOOOOO | OOOOOOOOOOOOOOOOOOOOOOOOOOOOOOOOOOOOOOOOOOOOOOOOOOOOOOOOOOOOOOOOOOOOOOOOOOOOOOOOOOOOOOOOOO | OOOOOOOOOOOOOOOOOOOOOOOOOOOOOOOOOOOOOOOOOOOOOOOOOOOOOOOOOOOOOOOOOOOOOOOOOOOOOOOOOOOOOOOOOO |
| Master Materials Change |  |  |  |  |  |  |  |  |  |
| Item | Foxconn P/N | Orig._Usage | New_Usage | Part Description | Manufacturer Full Name | Manufacturer P/N | RoHS | Location | Sheet |
| 1 | 0101FBQ00-000-G | 0 | 1 | PCB,Zaius-MB PVT-X04,OSP,Gre,22L,22.20*13.00,G | GOLD CIRCUIT ELECTRONICS LTD. | 0101FBQ00-000-G | G | (+)PCB | PWA BOM |
|  | 0101FBQ00-000-G |  |  | PCB,Zaius-MB PVT-X04,OSP,Gre,22L,22.20*13.00,G | ZHUHAI FOUNDER PRINTED CIRCUIT BOARD（HK） DEVELOPMENT LIMITED | 0101FBQ00-000-G |  |  | PWA BOM |
|  | 0101FBQ00-000-G |  |  | PCB,Zaius-MB PVT-X04,OSP,Gre,22L,22.20*13.00,G | ISUPETASYS CO., LTD | 0101FBQ00-000-G |  |  | PWA BOM |
| 2 | 620103700-015-G | 174 | 172 | CAP,100nF,+/-10%,X7R,10V,G,SMD0402 | MURATA ELEC. NORTH AMERICA | GRM155R71A104K | G | (-)C2126,C2127 | PWA BOM |
|  | 620103700-012-G |  |  | CAP,0.1uF,+/-10%,X7R,10V,G,SMD0402 | WALSIN TECHNOLOGY CORPORATION | 0402B104K100CT |  |  | PWA BOM |
|  | 620103700-023-G |  |  | CAP,100nF,+/-10%,X7R,10V,G,SMD0402 | TAIYO ELECTRIC IND.CO.LTD | LMK105B7104KV-F |  |  | PWA BOM |
|  | 620103700-026-G |  |  | CAP,100nF,+/-10%,X7R,10V,G,SMD0402 | SAMSUNG SEMICONDUCTOR | CL05B104KP5NNNC |  |  | PWA BOM |
| 3 | 0438005.WRGT | 0 | 7 | Fuse,Fast acting,32V,5A,G,SMD0603 | LITTELFUSE FAR EAST PTE LTD | 0438005.WRGT | G | (+)FS5,FS8,FS11,FS14,FS17,FS19,FS20 | PWA BOM |
|  | 730103M00-086-G |  |  | Fuse,Fast acting,32V,5A,G,SMD0603 | LITTELFUSE FAR EAST PTE LTD | 0438005.WR |  |  | PWA BOM |
|  | 730103M00-088-G |  |  | Fuse,Fast acting,32V,5A,SMD0603,G | COOPER BUSSMANN, INC. | CC06H5A-TR |  |  | PWA BOM |
| 4 | 52030DA00-237-G | 0 | 16 | DIODE,Schottky,BAT46W-7-F,100V,150mA,G,SOD123-2,SMD | DIODES INEORPORATION | BAT46W-7-F | G | (+)PBMD1,PBFD1,PBED1,PBAD1,PAMD1,PAFD1,PAED1,PAAD1,PBMD4,PBFD4,PBED4,PAMD4,PAFD4,PAED4,PBAD5,PAAD5 | PWA BOM |
| 5 | 610107A00-017-G | 722 | 712 | RES,0 Ohm,+/-5%,1/16W,G,SMD0402 | KOA SPEER ELECTRONICS, INC. | RK73Z1ETTP | G | (-)R1226,R1472,R1502,R1554,R1556,R1815,R1816,R1817,R1818,R1819 | PWA BOM |
|  | 610107A00-012-G |  |  | RES,0 Ohm,+/-5%,1/16W,G,SMD0402 | WALSIN TECHNOLOGY CORPORATION | WR04X000PTL |  |  | PWA BOM |
|  | 610107A00-011-G |  |  | RES,0 Ohm,+/-5%,1/16W,G,SMD0402 | YAGEO CORPORATION COMPONENT | RC0402JR-070RL |  |  | PWA BOM |
|  | 610107A00-044-G |  |  | RES,0 Ohm,+/-5%,1/16W,G,SMD0402 | TA-I TECHNOLOGY CO., LTD | RM04JTN0 |  |  | PWA BOM |
|  | 610107A00-024-G |  |  | RES,0 Ohm,+/-5%,1/16W,G,SMD0402 | PANASONIC INDUSTRIAL CO.,LTD. | ERJ2GE0R00X |  |  | PWA BOM |
|  | 610107A00-029-G |  |  | RES,0 Ohm,+/-5%,1/16W,G,SMD0402 | VISHAY ENTER TECHNO LOGY.INC | CRCW04020000Z0ED |  |  | PWA BOM |
| 6 | 61010G500-017-G | 100 | 101 | RES,10KOhm,+/-1%,1/16W,G,SMD0402 | KOA SPEER ELECTRONICS, INC. | RK73H1ETTP1002F | G | (+)PSUR2 | PWA BOM |
|  | 61010G500-012-G |  |  | RES,10KOhm,+/-1%,1/16W,G,SMD0402 | WALSIN TECHNOLOGY CORPORATION | WR04X1002FTL |  |  | PWA BOM |
|  | 61010G500-011-G |  |  | RES,10KOhm,+/-1%,1/16W,G,SMD0402 | YAGEO CORPORATION COMPONENT | RC0402FR-0710KL |  |  | PWA BOM |
|  | 61010G500-044-G |  |  | RES,10KOhm,+/-1%,1/16W,G,SMD0402 | TA-I TECHNOLOGY CO., LTD | RM04FTN1002 |  |  | PWA BOM |
|  | 61010G500-029-G |  |  | RES,10KOhm,+/-1%,1/16W,G,SMD0402 | VISHAY ENTER TECHNO LOGY.INC | CRCW040210K0FKED |  |  | PWA BOM |
|  | 61010G500-024-G |  |  | RES,10KOhm,+/-1%,1/16W,G,SMD0402 | PANASONIC INDUSTRIAL CO.,LTD. | ERJ2RKF1002X |  |  | PWA BOM |
| 7 | 320242200-230-G | 0 | 8 | IC,PWM Controller,ISL68137IRAZ-T,G,QFN-48,SMD | INTERSIL CORPORATION | ISL68137IRAZ-T | G | (+)PBMU1,PBFU1,PBEU1,PBAU1,PAMU1,PAFU1,PAEU1,PAAU1 | PWA BOM |
| 8 | 32014E200-53N-G | 0 | 2 | IC,Regulator,PI3753-00-LGIZ,ADJ,10.3A,G,LGA-108,SMD | Vicor Corporation | PI3753-00-LGIZ | G | (+)PBAU3,PAAU3 | PWA BOM |
| 9 | 61011H300-017-G | 6 | 4 | RES,316 Ohm,+/-1%,1/16W,G,SMD0402 | KOA SPEER ELECTRONICS, INC. | RK73H1ETTP3160F | G | (-)PBMR34,PAMR34 | PWA BOM |
|  | 61011H300-012-G |  |  | RES,316 Ohm,+/-1%,1/16W,G,SMD0402 | WALSIN TECHNOLOGY CORPORATION | WR04X3160FTL |  |  | PWA BOM |
|  | 61011H300-011-G |  |  | RES,316 Ohm,+/-1%,1/16W,G,SMD0402 | YAGEO CORPORATION COMPONENT | RC0402FR-07316RL |  |  | PWA BOM |
| 10 | 610119C00-017-G | 2 | 1 | RES,130KOhm,+/-1%,1/16W,G,SMD0402 | KOA SPEER ELECTRONICS, INC. | RK73H1ETTP1303F | G | (-)PSUR4 | PWA BOM |
|  | 610119C00-011-G |  |  | RES,130KOhm,+/-1%,1/16W,G,SMD0402 | YAGEO CORPORATION COMPONENT | RC0402FR-07130KL |  |  | PWA BOM |
|  | 610119C00-012-G |  |  | RES,130KOhm,+/-1%,1/16W,G,SMD0402 | WALSIN TECHNOLOGY CORPORATION | WR04X1303FTL |  |  | PWA BOM |
|  | 610119C00-044-G |  |  | RES,130KOhm,+/-1%,1/16W,G,SMD0402 | TA-I TECHNOLOGY CO., LTD | RM04FTN1303 |  |  | PWA BOM |
| 11 | 610102700-017-G | 208 | 204 | RES,49.9 Ohm,+/-1%,1/16W,G,SMD0402 | KOA SPEER ELECTRONICS, INC. | RK73H1ETTP49R9F | G | (-)R114,R115,R117,R121 | PWA BOM |
|  | 610102700-012-G |  |  | RES,49.9 Ohm,+/-1%,1/16W,G,SMD0402 | WALSIN TECHNOLOGY CORPORATION | WR04X49R9FTL |  |  | PWA BOM |
|  | 610102700-011-G |  |  | RES,49.9 Ohm,+/-1%,1/16W,G,SMD0402 | YAGEO CORPORATION COMPONENT | RC0402FR-0749R9L |  |  | PWA BOM |
|  | 610102700-044-G |  |  | RES,49.9 Ohm,+/-1%,1/16W,G,SMD0402 | TA-I TECHNOLOGY CO., LTD | RM04FTN49R9 |  |  | PWA BOM |
|  | 610102700-029-G |  |  | RES,49.9 Ohm,+/-1%,1/16W,G,SMD0402 | VISHAY ENTER TECHNO LOGY.INC | CRCW040249R9FKED |  |  | PWA BOM |
|  | 610102700-024-G |  |  | RES,49.9 Ohm,+/-1%,1/16W,G,SMD0402 | PANASONIC INDUSTRIAL CO.,LTD. | ERJ2RKF49R9X |  |  | PWA BOM |
| 12 | 61010KJ00-017-G | 83 | 82 | RES,3.3KOhm,+/-5%,1/16W,G,SMD0402 | KOA SPEER ELECTRONICS, INC. | RK73B1ETTP332J | G | (-)R470 | PWA BOM |
|  | 61010KJ00-012-G |  |  | RES,3.3KOhm,+/-5%,1/16W,G,SMD0402 | WALSIN TECHNOLOGY CORPORATION | WR04X332JTL |  |  | PWA BOM |
|  | 61010KJ00-011-G |  |  | RES,3.3KOhm,+/-5%,1/16W,G,SMD0402 | YAGEO CORPORATION COMPONENT | RC0402JR-073K3L |  |  | PWA BOM |
|  | 61010KJ00-044-G |  |  | RES,3.3KOhm,+/-5%,1/16W,G,SMD0402 | TA-I TECHNOLOGY CO., LTD | RM04JTN332 |  |  | PWA BOM |
|  | 61010KJ00-024-G |  |  | RES,3.3KOhm,+/-5%,1/16W,G,SMD0402 | PANASONIC INDUSTRIAL CO.,LTD. | ERJ2GEJ332X |  |  | PWA BOM |
| 13 | 61011H500-017-G | 27 | 29 | RES,22 Ohm,+/-1%,1/16W,G,SMD0402 | KOA SPEER ELECTRONICS, INC. | RK73H1ETTP22R0F | G | (+)R1226,R1502 | PWA BOM |
|  | 61011H500-012-G |  |  | RES,22 Ohm,+/-1%,1/16W,G,SMD0402 | WALSIN TECHNOLOGY CORPORATION | WR04X22R0FTL |  |  | PWA BOM |
|  | 61011H500-011-G |  |  | RES,22 Ohm,+/-1%,1/16W,G,SMD0402 | YAGEO CORPORATION COMPONENT | RC0402FR-0722RL |  |  | PWA BOM |
|  | 61011H500-044-G |  |  | RES,22 Ohm,+/-1%,1/16W,G,SMD0402 | TA-I TECHNOLOGY CO., LTD | RM04FTN22R0 |  |  | PWA BOM |
|  | 61011H500-024-G |  |  | RES,22 Ohm,+/-1%,1/16W,G,SMD0402 | PANASONIC INDUSTRIAL CO.,LTD. | ERJ2RKF22R0X |  |  | PWA BOM |
| 14 | 61100QH00-017-G | 4 | 2 | RES,510 Ohm,+/-0.1%,1/16W,G,SMD0402 | KOA SPEER ELECTRONICS, INC. | RN731ETTP5100B25 | G | (-)R1093,R1114 | PWA BOM |
|  | 61100QH00-012-G |  |  | RES,510 Ohm,+/-0.1%,1/16W,G,SMD0402 | WALSIN TECHNOLOGY CORPORATION | WF04U5100BTL |  |  | PWA BOM |
|  | 61100QH00-011-G |  |  | RES,510 Ohm,+/-0.1%,1/16W,G,SMD0402 | YAGEO CORPORATION COMPONENT | RT0402BRD07510RL |  |  | PWA BOM |
| 15 | 320241C00-183-G | 0 | 1 | IC,Power Controller,UCD90160RGCR,G,VQFN-64,SMD | TEXAS INSTRUMENTS | UCD90160RGCR | G | (+)U5 | PWA BOM |
| 16 | 32050Q900-031-G | 2 | 1 | IC,LED Driver,PCA9551PW,G,TSSOP-16,SMD | NXP SEMICONDUCTORS | PCA9551PW | G | (-)U172 | PWA BOM |
| 17 | 310203U00-223-G | 2 | 1 | IC,Trigger,NL17SZ14DFT2G,1.65~5.5V,G,SOT353-5,SMD | ON SEMICONDUCTOR CORP | NL17SZ14DFT2G | G | (-)U173 | PWA BOM |
|  | 310200900-185-G |  |  | IC,Trigger,NC7SZ14P5X,1.65-5.5V,G,SC70-5P,SMD | FAIRCHILD SEMICONDUCTOR CORP | NC7SZ14P5X |  |  | PWA BOM |
|  | 310107000-031-G |  |  | Logic IC,Gate&Inverter,74LVC1G14GW,1.65V~5.5V,14ns,TSSOP,5P,G | NXP SEMICONDUCTORS | 74LVC1G14GW |  |  | PWA BOM |
| 18 | SRV05-4ATCT | 0 | 2 | DIODE,Array-TVS,SRV05-4.TCT,5V,12A,G,SOT23-6,SMD | SEMTECH CORPORATION. | SRV05-4ATCT | G | (+)ED2,ED3 | PWA BOM |
|  | 521800900-227-G |  |  | DIODE,Array-TVS,SRV05-4.TCT,5V,12A,G,SOT23-6,SMD | SEMTECH CORPORATION. | SRV05-4.TCT |  |  | PWA BOM |
|  | 52180C200-086-G |  |  | Diode,Array-TVS,SRV05-4HTG,SOT-23,6P,G | LITTELFUSE FAR EAST PTE LTD | SRV05-4HTG |  |  | PWA BOM |
| 19 | 34068LN00-317-G | 11 | 10 | CONN,Header,Pin Header,1X3,V/T,2.54mm,30u,G,SMD-3 | MOLEX INCORPORATED | 87898-0315 | G | (-)J3 | PWA BOM |
|  | 34068HT00-245-G |  |  | CONN,Header,Pin Header,1X3,V/T,Bla,2.54mm,30u,SMD-3 | AMPHENOL SHANGHAI CORP. | G800MU305010EU |  |  | PWA BOM |
|  | 34068GU00-309-G |  |  | CONN,Header,Pin Header,1X3,V/T,Bla,2.54mm,30u,SMD-3 | SAMTEC INC. | TSM-103-01-S-SV-P-TR |  |  | PWA BOM |
| 20 | RN731ETTP3160B25 | 0 | 2 | RES,316 Ohm,+/-0.1%,1/16W,G,SMD0402 | KOA SPEER ELECTRONICS, INC. | RN731ETTP3160B25 | G | (+)PBMR34,PAMR34 | PWA BOM |
| 21 | 0101EW800-000-G | 1 | 0 | PCB,Zaius-MB DVT-X03,OSP,Blu,22L,22.20*13.00,G | GOLD CIRCUIT ELECTRONICS LTD. | 0101EW800-000-G | G | (-)PCB | PWA BOM |
|  | 0101EW800-000-G |  |  | PCB,Zaius-MB DVT-X03,OSP,Blu,22L,22.20*13.00,G | ZHUHAI FOUNDER PRINTED CIRCUIT BOARD（HK） DEVELOPMENT LIMITED | 0101EW800-000-G |  |  | PWA BOM |
|  | 0101EW800-000-G |  |  | PCB,Zaius-MB DVT-X03,OSP,Blu,22L,22.20*13.00,G | ISUPETASYS CO., LTD | 0101EW800-000-G |  |  | PWA BOM |
| 22 | 620108B00-015-G | 2 | 0 | CAP,120pF,+/-5%,NPO(C0G),50V,G,SMD0402 | MURATA ELEC. NORTH AMERICA | GRM1555C1H121J | G | (-)C2184,C2185 | PWA BOM |
|  | 620108B00-012-G |  |  | CAP,120pF,+/-5%,NPO(C0G),50V,G,SMD0402 | WALSIN TECHNOLOGY CORPORATION | 0402N121J500LT |  |  | PWA BOM |
|  | 620108B00-026-G |  |  | CAP,120pF,+/-5%,NPO(C0G),50V,G,SMD0402 | SAMSUNG SEMICONDUCTOR | CL05C121JB5NNNC |  |  | PWA BOM |
| 23 | 521800900-227-G | 3 | 0 | DIODE,Array-TVS,SRV05-4.TCT,5V,12A,G,SOT23-6,SMD | SEMTECH CORPORATION. | SRV05-4.TCT | G | (-)ED1,ED2,ED3 | PWA BOM |
|  | 52180C200-086-G |  |  | Diode,Array-TVS,SRV05-4HTG,SOT-23,6P,G | LITTELFUSE FAR EAST PTE LTD | SRV05-4HTG |  |  | PWA BOM |
| 24 | 730103M00-086-G | 7 | 0 | Fuse,Fast acting,32V,5A,G,SMD0603 | LITTELFUSE FAR EAST PTE LTD | 0438005.WR | G | (-)FS5,FS8,FS11,FS14,FS17,FS19,FS20 | PWA BOM |
|  | 730103M00-088-G |  |  | Fuse,Fast acting,32V,5A,SMD0603,G | COOPER BUSSMANN, INC. | CC06H5A-TR |  |  | PWA BOM |
| 25 | 520103B00-185-G | 8 | 0 | Diode,Rectifier&Switching,MMBD1205,100V,200mA,G,SOT-23-3,SMD | FAIRCHILD SEMICONDUCTOR CORP | MMBD1205 | G | (-)PBMD1,PBFD1,PBED1,PBAD1,PAMD1,PAFD1,PAED1,PAAD1 | PWA BOM |
|  | 52010A100-237-G |  |  | Diode,Rectifier&Switching,100V,200mA,G,SOT-23-3,SMD | DIODES INCORPORATION | MMBD3004A-7-F |  |  | PWA BOM |
| 26 | ISL68137IRAZ-GG04 | 8 | 0 | IC,PWM Controller,ISL68137IRAZ-T,G,QFN-48,SMD | INTERSIL CORPORATION | ISL68137IRAZ-GG04 | G | (-)PBMU1,PBFU1,PBEU1,PBAU1,PAMU1,PAFU1,PAEU1,PAAU1 | PWA BOM |
| 27 | 610116G00-017-G | 2 | 0 | RES,150KOhm,+/-1%,1/16W,G,SMD0402 | KOA SPEER ELECTRONICS, INC. | RK73H1ETTP1503F | G | (-)PSUR2,PSUR5 | PWA BOM |
|  | 610116G00-011-G |  |  | RES,150KOhm,+/-1%,1/16W,G,SMD0402 | YAGEO CORPORATION COMPONENT | RC0402FR-07150KL |  |  | PWA BOM |
|  | 610116G00-012-G |  |  | RES,150KOhm,+/-1%,1/16W,G,SMD0402 | WALSIN TECHNOLOGY CORPORATION | WR04X1503FTL |  |  | PWA BOM |
|  | 610116G00-044-G |  |  | RES,150KOhm,+/-1%,1/16W,G,SMD0402 | TA-I TECHNOLOGY CO., LTD | RM04FTN1503 |  |  | PWA BOM |
| 28 | 610124C00-017-G | 2 | 0 | RES,57.6 Ohm,+/-1%,1/16W,G,SMD0402 | KOA SPEER ELECTRONICS, INC. | RK73H1ETTP57R6F | G | (-)R1838,R1839 | PWA BOM |
|  | 610124C00-012-G |  |  | RES,57.6 Ohm,+/-1%,1/16W,G,SMD0402 | WALSIN TECHNOLOGY CORPORATION | WR04X57R6FTL |  |  | PWA BOM |
|  | 610124C00-011-G |  |  | RES,57.6 Ohm,+/-1%,1/16W,G,SMD0402 | YAGEO CORPORATION COMPONENT | RC0402FR-0757R6L |  |  | PWA BOM |
| 29 | UCD90160RGCR-C10 | 1 | 0 | IC,Power Controller,UCD90160RGCR,G,VQFN-64,SMD | TEXAS INSTRUMENTS | UCD90160RGCR-C10 | G | (-)U5 | PWA BOM |
| 30 | 340653G00-317-G | 1 | 0 | CONN,Header,Shrouded,2X11,V/T,Bla,2mm,30u,G,SMD-22 | MOLEX INCORPORATED | 87832-6023 | G | (-)J102 | PWA BOM |
| 31 | 3406ALY00-317-G | 1 | 0 | CONN,Header,Shrouded,2X6,V/T,Bla,2mm,30u,G,SMD-12 | MOLEX INCORPORATED | 87832-5523 | G | (-)J103 | PWA BOM |
| 32 | PI3753-00-LGIZ | 2 | 0 | IC,Regulator,PI3753-00,ADJ,4A,G,LGA-71,SMD | Vicor Corporation | PI3753-00-LGIZ | G | (-)PBAU3,PAAU3 | PWA BOM |
| 33 | 34080F500-653-G | 1 | 0 | CONN,Switch,slide,25mA,24V,G,SMD-8 | DIPTRONICS MANUFACTURING INC. | DHN-04F-T-V-T/R | G | (-)PSUSW1 | PWA BOM |
| OOOOOOOOOOOOOOOOOOOOOOOOOOOOOOOOOOOOOOOOOOOOOOOOOOOOOOOOOOOOOOOOOOOOOOOOOOOOOOOOOOOOOOOOOO | OOOOOOOOOOOOOOOOOOOOOOOOOOOOOOOOOOOOOOOOOOOOOOOOOOOOOOOOOOOOOOOOOOOOOOOOOOOOOOOOOOOOOOOOOO | OOOOOOOOOOOOOOOOOOOOOOOOOOOOOOOOOOOOOOOOOOOOOOOOOOOOOOOOOOOOOOOOOOOOOOOOOOOOOOOOOOOOOOOOOO | OOOOOOOOOOOOOOOOOOOOOOOOOOOOOOOOOOOOOOOOOOOOOOOOOOOOOOOOOOOOOOOOOOOOOOOOOOOOOOOOOOOOOOOOOO | OOOOOOOOOOOOOOOOOOOOOOOOOOOOOOOOOOOOOOOOOOOOOOOOOOOOOOOOOOOOOOOOOOOOOOOOOOOOOOOOOOOOOOOOOO | OOOOOOOOOOOOOOOOOOOOOOOOOOOOOOOOOOOOOOOOOOOOOOOOOOOOOOOOOOOOOOOOOOOOOOOOOOOOOOOOOOOOOOOOOO | OOOOOOOOOOOOOOOOOOOOOOOOOOOOOOOOOOOOOOOOOOOOOOOOOOOOOOOOOOOOOOOOOOOOOOOOOOOOOOOOOOOOOOOOOO | OOOOOOOOOOOOOOOOOOOOOOOOOOOOOOOOOOOOOOOOOOOOOOOOOOOOOOOOOOOOOOOOOOOOOOOOOOOOOOOOOOOOOOOOOO | OOOOOOOOOOOOOOOOOOOOOOOOOOOOOOOOOOOOOOOOOOOOOOOOOOOOOOOOOOOOOOOOOOOOOOOOOOOOOOOOOOOOOOOOOO | OOOOOOOOOOOOOOOOOOOOOOOOOOOOOOOOOOOOOOOOOOOOOOOOOOOOOOOOOOOOOOOOOOOOOOOOOOOOOOOOOOOOOOOOOO |
| TLA Parts Change |  |  |  |  |  |  |  |  |  |
| Item | Foxconn P/N | Qty | Part Description | Manufacturer Full Name | Manufacturer P/N | RoHS | Location | Remark | BOM |
| BOM Change List Date:Tue Aug 08 16:09:44 CST 2017 |  |  |  |  |  |  |  |  |  |
| New BOM file : C:\<user>\0808.xls |  |  |  |  |  |  |  |  |  |
| Old BOM file : C:\<user>\0803.xls |  |  |  |  |  |  |  |  |  |
| ##### Add Parts |  |  |  |  |  |  |  |  |  |
| Item | Location | Qty | Foxconn P/N | Part Description | Manufacturer Full Name | Manufacturer P/N | RoHS | Sheet |  |
| 1 | C2126,C2127 | 2 | 620103700-015-G | CAP,100nF,+/-10%,X7R,10V,G,SMD0402 | MURATA ELEC. NORTH AMERICA | GRM155R71A104K | G | PWA BOM |  |
|  |  |  | 620103700-012-G | CAP,0.1uF,+/-10%,X7R,10V,G,SMD0402 | WALSIN TECHNOLOGY CORPORATION | 0402B104K100CT | G | PWA BOM |  |
|  |  |  | 620103700-023-G | CAP,100nF,+/-10%,X7R,10V,G,SMD0402 | TAIYO ELECTRIC IND.CO.LTD | LMK105B7104KV-F | G | PWA BOM |  |
|  |  |  | 620103700-026-G | CAP,100nF,+/-10%,X7R,10V,G,SMD0402 | SAMSUNG SEMICONDUCTOR | CL05B104KP5NNNC | G | PWA BOM |  |
| 2 | R1556 | 1 | 610107A00-017-G | RES,0 Ohm,+/-5%,1/16W,G,SMD0402 | KOA SPEER ELECTRONICS, INC. | RK73Z1ETTP | G | PWA BOM |  |
|  |  |  | 610107A00-012-G | RES,0 Ohm,+/-5%,1/16W,G,SMD0402 | WALSIN TECHNOLOGY CORPORATION | WR04X000PTL | G | PWA BOM |  |
|  |  |  | 610107A00-011-G | RES,0 Ohm,+/-5%,1/16W,G,SMD0402 | YAGEO CORPORATION COMPONENT | RC0402JR-070RL | G | PWA BOM |  |
|  |  |  | 610107A00-044-G | RES,0 Ohm,+/-5%,1/16W,G,SMD0402 | TA-I TECHNOLOGY CO., LTD | RM04JTN0 | G | PWA BOM |  |
|  |  |  | 610107A00-024-G | RES,0 Ohm,+/-5%,1/16W,G,SMD0402 | PANASONIC INDUSTRIAL CO.,LTD. | ERJ2GE0R00X | G | PWA BOM |  |
|  |  |  | 610107A00-029-G | RES,0 Ohm,+/-5%,1/16W,G,SMD0402 | VISHAY ENTER TECHNO LOGY.INC | CRCW04020000Z0ED | G | PWA BOM |  |
| 3 | R114,R115,R117,R121 | 4 | 610102700-017-G | RES,49.9 Ohm,+/-1%,1/16W,G,SMD0402 | KOA SPEER ELECTRONICS, INC. | RK73H1ETTP49R9F | G | PWA BOM |  |
|  |  |  | 610102700-012-G | RES,49.9 Ohm,+/-1%,1/16W,G,SMD0402 | WALSIN TECHNOLOGY CORPORATION | WR04X49R9FTL | G | PWA BOM |  |
|  |  |  | 610102700-011-G | RES,49.9 Ohm,+/-1%,1/16W,G,SMD0402 | YAGEO CORPORATION COMPONENT | RC0402FR-0749R9L | G | PWA BOM |  |
|  |  |  | 610102700-044-G | RES,49.9 Ohm,+/-1%,1/16W,G,SMD0402 | TA-I TECHNOLOGY CO., LTD | RM04FTN49R9 | G | PWA BOM |  |
|  |  |  | 610102700-029-G | RES,49.9 Ohm,+/-1%,1/16W,G,SMD0402 | VISHAY ENTER TECHNO LOGY.INC | CRCW040249R9FKED | G | PWA BOM |  |
|  |  |  | 610102700-024-G | RES,49.9 Ohm,+/-1%,1/16W,G,SMD0402 | PANASONIC INDUSTRIAL CO.,LTD. | ERJ2RKF49R9X | G | PWA BOM |  |
| 4 | R470 | 1 | 61010KJ00-017-G | RES,3.3KOhm,+/-5%,1/16W,G,SMD0402 | KOA SPEER ELECTRONICS, INC. | RK73B1ETTP332J | G | PWA BOM |  |
|  |  |  | 61010KJ00-012-G | RES,3.3KOhm,+/-5%,1/16W,G,SMD0402 | WALSIN TECHNOLOGY CORPORATION | WR04X332JTL | G | PWA BOM |  |
|  |  |  | 61010KJ00-011-G | RES,3.3KOhm,+/-5%,1/16W,G,SMD0402 | YAGEO CORPORATION COMPONENT | RC0402JR-073K3L | G | PWA BOM |  |
|  |  |  | 61010KJ00-044-G | RES,3.3KOhm,+/-5%,1/16W,G,SMD0402 | TA-I TECHNOLOGY CO., LTD | RM04JTN332 | G | PWA BOM |  |
|  |  |  | 61010KJ00-024-G | RES,3.3KOhm,+/-5%,1/16W,G,SMD0402 | PANASONIC INDUSTRIAL CO.,LTD. | ERJ2GEJ332X | G | PWA BOM |  |
| 5 | U172 | 1 | 32050Q900-031-G | IC,LED Driver,PCA9551PW,G,TSSOP-16,SMD | NXP SEMICONDUCTORS | PCA9551PW | G | PWA BOM |  |
| 6 | U173 | 1 | 310203U00-223-G | IC,Trigger,NL17SZ14DFT2G,1.65~5.5V,G,SOT353-5,SMD | ON SEMICONDUCTOR CORP | NL17SZ14DFT2G | G | PWA BOM |  |
|  |  |  | 310200900-185-G | IC,Trigger,NC7SZ14P5X,1.65-5.5V,G,SC70-5P,SMD | FAIRCHILD SEMICONDUCTOR CORP | NC7SZ14P5X | G | PWA BOM |  |
|  |  |  | 310107000-031-G | Logic IC,Gate&Inverter,74LVC1G14GW,1.65V~5.5V,14ns,TSSOP,5P,G | NXP SEMICONDUCTORS | 74LVC1G14GW | G | PWA BOM |  |
| 7 | J102 | 1 | 340653G00-317-G | CONN,Header,Shrouded,2X11,V/T,Bla,2mm,30u,G,SMD-22 | MOLEX INCORPORATED | 87832-6023 | G | PWA BOM |  |
| 8 | J103 | 1 | 3406ALY00-317-G | CONN,Header,Shrouded,2X6,V/T,Bla,2mm,30u,G,SMD-12 | MOLEX INCORPORATED | 87832-5523 | G | PWA BOM |  |
| ##### Remove Parts |  |  |  |  |  |  |  |  |  |
| Item | Location | Qty | Foxconn P/N | Part Description | Manufacturer Full Name | Manufacturer P/N | RoHS | Sheet |  |
| ##### Change Parts |  |  |  |  |  |  |  |  |  |
| Item | Location | Qty | Foxconn P/N | Part Description | Manufacturer Full Name | Manufacturer P/N | RoHS | Sheet | Remark |
| ##### Change Revision |  |  |  |  |  |  |  |  |  |
| Sheet | REV OF BOM | CUSTOMER | CUSTOMER P/N | PWA PN | PWA DESCRIPTION | PWA REV | DATE | Remark |  |
| OOOOOOOOOOOOOOOOOOOOOOOOOOOOOOOOOOOOOOOOOOOOOOOOOOOOOOOOOOOOOOOOOOOOOOOOOOOOOOOOOOOOOOOOOO | OOOOOOOOOOOOOOOOOOOOOOOOOOOOOOOOOOOOOOOOOOOOOOOOOOOOOOOOOOOOOOOOOOOOOOOOOOOOOOOOOOOOOOOOOO | OOOOOOOOOOOOOOOOOOOOOOOOOOOOOOOOOOOOOOOOOOOOOOOOOOOOOOOOOOOOOOOOOOOOOOOOOOOOOOOOOOOOOOOOOO | OOOOOOOOOOOOOOOOOOOOOOOOOOOOOOOOOOOOOOOOOOOOOOOOOOOOOOOOOOOOOOOOOOOOOOOOOOOOOOOOOOOOOOOOOO | OOOOOOOOOOOOOOOOOOOOOOOOOOOOOOOOOOOOOOOOOOOOOOOOOOOOOOOOOOOOOOOOOOOOOOOOOOOOOOOOOOOOOOOOOO | OOOOOOOOOOOOOOOOOOOOOOOOOOOOOOOOOOOOOOOOOOOOOOOOOOOOOOOOOOOOOOOOOOOOOOOOOOOOOOOOOOOOOOOOOO | OOOOOOOOOOOOOOOOOOOOOOOOOOOOOOOOOOOOOOOOOOOOOOOOOOOOOOOOOOOOOOOOOOOOOOOOOOOOOOOOOOOOOOOOOO | OOOOOOOOOOOOOOOOOOOOOOOOOOOOOOOOOOOOOOOOOOOOOOOOOOOOOOOOOOOOOOOOOOOOOOOOOOOOOOOOOOOOOOOOOO | OOOOOOOOOOOOOOOOOOOOOOOOOOOOOOOOOOOOOOOOOOOOOOOOOOOOOOOOOOOOOOOOOOOOOOOOOOOOOOOOOOOOOOOOOO | OOOOOOOOOOOOOOOOOOOOOOOOOOOOOOOOOOOOOOOOOOOOOOOOOOOOOOOOOOOOOOOOOOOOOOOOOOOOOOOOOOOOOOOOOO |
| Second Source Change |  |  |  |  |  |  |  |  |  |
| Item | Location | Change Type | Foxconn P/N | Part Description | Manufacturer Full Name | Manufacturer P/N | RoHS | Sheet |  |
| OOOOOOOOOOOOOOOOOOOOOOOOOOOOOOOOOOOOOOOOOOOOOOOOOOOOOOOOOOOOOOOOOOOOOOOOOOOOOOOOOOOOOOOOOO | OOOOOOOOOOOOOOOOOOOOOOOOOOOOOOOOOOOOOOOOOOOOOOOOOOOOOOOOOOOOOOOOOOOOOOOOOOOOOOOOOOOOOOOOOO | OOOOOOOOOOOOOOOOOOOOOOOOOOOOOOOOOOOOOOOOOOOOOOOOOOOOOOOOOOOOOOOOOOOOOOOOOOOOOOOOOOOOOOOOOO | OOOOOOOOOOOOOOOOOOOOOOOOOOOOOOOOOOOOOOOOOOOOOOOOOOOOOOOOOOOOOOOOOOOOOOOOOOOOOOOOOOOOOOOOOO | OOOOOOOOOOOOOOOOOOOOOOOOOOOOOOOOOOOOOOOOOOOOOOOOOOOOOOOOOOOOOOOOOOOOOOOOOOOOOOOOOOOOOOOOOO | OOOOOOOOOOOOOOOOOOOOOOOOOOOOOOOOOOOOOOOOOOOOOOOOOOOOOOOOOOOOOOOOOOOOOOOOOOOOOOOOOOOOOOOOOO | OOOOOOOOOOOOOOOOOOOOOOOOOOOOOOOOOOOOOOOOOOOOOOOOOOOOOOOOOOOOOOOOOOOOOOOOOOOOOOOOOOOOOOOOOO | OOOOOOOOOOOOOOOOOOOOOOOOOOOOOOOOOOOOOOOOOOOOOOOOOOOOOOOOOOOOOOOOOOOOOOOOOOOOOOOOOOOOOOOOOO | OOOOOOOOOOOOOOOOOOOOOOOOOOOOOOOOOOOOOOOOOOOOOOOOOOOOOOOOOOOOOOOOOOOOOOOOOOOOOOOOOOOOOOOOOO | OOOOOOOOOOOOOOOOOOOOOOOOOOOOOOOOOOOOOOOOOOOOOOOOOOOOOOOOOOOOOOOOOOOOOOOOOOOOOOOOOOOOOOOOOO |
| Master Materials Change |  |  |  |  |  |  |  |  |  |
| Item | Foxconn P/N | Orig._Usage | New_Usage | Part Description | Manufacturer Full Name | Manufacturer P/N | RoHS | Location | Sheet |
| 1 | 620103700-015-G | 172 | 174 | CAP,100nF,+/-10%,X7R,10V,G,SMD0402 | MURATA ELEC. NORTH AMERICA | GRM155R71A104K | G | (+)C2126,C2127 | PWA BOM |
|  | 620103700-012-G |  |  | CAP,0.1uF,+/-10%,X7R,10V,G,SMD0402 | WALSIN TECHNOLOGY CORPORATION | 0402B104K100CT |  |  | PWA BOM |
|  | 620103700-023-G |  |  | CAP,100nF,+/-10%,X7R,10V,G,SMD0402 | TAIYO ELECTRIC IND.CO.LTD | LMK105B7104KV-F |  |  | PWA BOM |
|  | 620103700-026-G |  |  | CAP,100nF,+/-10%,X7R,10V,G,SMD0402 | SAMSUNG SEMICONDUCTOR | CL05B104KP5NNNC |  |  | PWA BOM |
| 2 | 610107A00-017-G | 712 | 713 | RES,0 Ohm,+/-5%,1/16W,G,SMD0402 | KOA SPEER ELECTRONICS, INC. | RK73Z1ETTP | G | (+)R1556 | PWA BOM |
|  | 610107A00-012-G |  |  | RES,0 Ohm,+/-5%,1/16W,G,SMD0402 | WALSIN TECHNOLOGY CORPORATION | WR04X000PTL |  |  | PWA BOM |
|  | 610107A00-011-G |  |  | RES,0 Ohm,+/-5%,1/16W,G,SMD0402 | YAGEO CORPORATION COMPONENT | RC0402JR-070RL |  |  | PWA BOM |
|  | 610107A00-044-G |  |  | RES,0 Ohm,+/-5%,1/16W,G,SMD0402 | TA-I TECHNOLOGY CO., LTD | RM04JTN0 |  |  | PWA BOM |
|  | 610107A00-024-G |  |  | RES,0 Ohm,+/-5%,1/16W,G,SMD0402 | PANASONIC INDUSTRIAL CO.,LTD. | ERJ2GE0R00X |  |  | PWA BOM |
|  | 610107A00-029-G |  |  | RES,0 Ohm,+/-5%,1/16W,G,SMD0402 | VISHAY ENTER TECHNO LOGY.INC | CRCW04020000Z0ED |  |  | PWA BOM |
| 3 | 610102700-017-G | 204 | 208 | RES,49.9 Ohm,+/-1%,1/16W,G,SMD0402 | KOA SPEER ELECTRONICS, INC. | RK73H1ETTP49R9F | G | (+)R114,R115,R117,R121 | PWA BOM |
|  | 610102700-012-G |  |  | RES,49.9 Ohm,+/-1%,1/16W,G,SMD0402 | WALSIN TECHNOLOGY CORPORATION | WR04X49R9FTL |  |  | PWA BOM |
|  | 610102700-011-G |  |  | RES,49.9 Ohm,+/-1%,1/16W,G,SMD0402 | YAGEO CORPORATION COMPONENT | RC0402FR-0749R9L |  |  | PWA BOM |
|  | 610102700-044-G |  |  | RES,49.9 Ohm,+/-1%,1/16W,G,SMD0402 | TA-I TECHNOLOGY CO., LTD | RM04FTN49R9 |  |  | PWA BOM |
|  | 610102700-029-G |  |  | RES,49.9 Ohm,+/-1%,1/16W,G,SMD0402 | VISHAY ENTER TECHNO LOGY.INC | CRCW040249R9FKED |  |  | PWA BOM |
|  | 610102700-024-G |  |  | RES,49.9 Ohm,+/-1%,1/16W,G,SMD0402 | PANASONIC INDUSTRIAL CO.,LTD. | ERJ2RKF49R9X |  |  | PWA BOM |
| 4 | 61010KJ00-017-G | 82 | 83 | RES,3.3KOhm,+/-5%,1/16W,G,SMD0402 | KOA SPEER ELECTRONICS, INC. | RK73B1ETTP332J | G | (+)R470 | PWA BOM |
|  | 61010KJ00-012-G |  |  | RES,3.3KOhm,+/-5%,1/16W,G,SMD0402 | WALSIN TECHNOLOGY CORPORATION | WR04X332JTL |  |  | PWA BOM |
|  | 61010KJ00-011-G |  |  | RES,3.3KOhm,+/-5%,1/16W,G,SMD0402 | YAGEO CORPORATION COMPONENT | RC0402JR-073K3L |  |  | PWA BOM |
|  | 61010KJ00-044-G |  |  | RES,3.3KOhm,+/-5%,1/16W,G,SMD0402 | TA-I TECHNOLOGY CO., LTD | RM04JTN332 |  |  | PWA BOM |
|  | 61010KJ00-024-G |  |  | RES,3.3KOhm,+/-5%,1/16W,G,SMD0402 | PANASONIC INDUSTRIAL CO.,LTD. | ERJ2GEJ332X |  |  | PWA BOM |
| 5 | 32050Q900-031-G | 1 | 2 | IC,LED Driver,PCA9551PW,G,TSSOP-16,SMD | NXP SEMICONDUCTORS | PCA9551PW | G | (+)U172 | PWA BOM |
| 6 | 310203U00-223-G | 1 | 2 | IC,Trigger,NL17SZ14DFT2G,1.65~5.5V,G,SOT353-5,SMD | ON SEMICONDUCTOR CORP | NL17SZ14DFT2G | G | (+)U173 | PWA BOM |
|  | 310200900-185-G |  |  | IC,Trigger,NC7SZ14P5X,1.65-5.5V,G,SC70-5P,SMD | FAIRCHILD SEMICONDUCTOR CORP | NC7SZ14P5X |  |  | PWA BOM |
|  | 310107000-031-G |  |  | Logic IC,Gate&Inverter,74LVC1G14GW,1.65V~5.5V,14ns,TSSOP,5P,G | NXP SEMICONDUCTORS | 74LVC1G14GW |  |  | PWA BOM |
| 7 | 340653G00-317-G | 0 | 1 | CONN,Header,Shrouded,2X11,V/T,Bla,2mm,30u,G,SMD-22 | MOLEX INCORPORATED | 87832-6023 | G | (+)J102 | PWA BOM |
| 8 | 3406ALY00-317-G | 0 | 1 | CONN,Header,Shrouded,2X6,V/T,Bla,2mm,30u,G,SMD-12 | MOLEX INCORPORATED | 87832-5523 | G | (+)J103 | PWA BOM |
| OOOOOOOOOOOOOOOOOOOOOOOOOOOOOOOOOOOOOOOOOOOOOOOOOOOOOOOOOOOOOOOOOOOOOOOOOOOOOOOOOOOOOOOOOO | OOOOOOOOOOOOOOOOOOOOOOOOOOOOOOOOOOOOOOOOOOOOOOOOOOOOOOOOOOOOOOOOOOOOOOOOOOOOOOOOOOOOOOOOOO | OOOOOOOOOOOOOOOOOOOOOOOOOOOOOOOOOOOOOOOOOOOOOOOOOOOOOOOOOOOOOOOOOOOOOOOOOOOOOOOOOOOOOOOOOO | OOOOOOOOOOOOOOOOOOOOOOOOOOOOOOOOOOOOOOOOOOOOOOOOOOOOOOOOOOOOOOOOOOOOOOOOOOOOOOOOOOOOOOOOOO | OOOOOOOOOOOOOOOOOOOOOOOOOOOOOOOOOOOOOOOOOOOOOOOOOOOOOOOOOOOOOOOOOOOOOOOOOOOOOOOOOOOOOOOOOO | OOOOOOOOOOOOOOOOOOOOOOOOOOOOOOOOOOOOOOOOOOOOOOOOOOOOOOOOOOOOOOOOOOOOOOOOOOOOOOOOOOOOOOOOOO | OOOOOOOOOOOOOOOOOOOOOOOOOOOOOOOOOOOOOOOOOOOOOOOOOOOOOOOOOOOOOOOOOOOOOOOOOOOOOOOOOOOOOOOOOO | OOOOOOOOOOOOOOOOOOOOOOOOOOOOOOOOOOOOOOOOOOOOOOOOOOOOOOOOOOOOOOOOOOOOOOOOOOOOOOOOOOOOOOOOOO | OOOOOOOOOOOOOOOOOOOOOOOOOOOOOOOOOOOOOOOOOOOOOOOOOOOOOOOOOOOOOOOOOOOOOOOOOOOOOOOOOOOOOOOOOO | OOOOOOOOOOOOOOOOOOOOOOOOOOOOOOOOOOOOOOOOOOOOOOOOOOOOOOOOOOOOOOOOOOOOOOOOOOOOOOOOOOOOOOOOOO |
| TLA Parts Change |  |  |  |  |  |  |  |  |  |
| Item | Foxconn P/N | Qty | Part Description | Manufacturer Full Name | Manufacturer P/N | RoHS | Location | Remark | BOM |
| BOM Change List Date:Wed Aug 09 11:55:17 GMT+08:00 2017 |  |  |  |  |  |  |  |  |  |
| New BOM file : C:\<user>\0809.xls |  |  |  |  |  |  |  |  |  |
| Old BOM file : C:\<user>\0808.xls |  |  |  |  |  |  |  |  |  |
| ##### Add Parts |  |  |  |  |  |  |  |  |  |
| Item | Location | Qty | Foxconn P/N | Part Description | Manufacturer Full Name | Manufacturer P/N | RoHS | Sheet |  |
| ##### Remove Parts |  |  |  |  |  |  |  |  |  |
| Item | Location | Qty | Foxconn P/N | Part Description | Manufacturer Full Name | Manufacturer P/N | RoHS | Sheet |  |
| ##### Change Parts |  |  |  |  |  |  |  |  |  |
| Item | Location | Qty | Foxconn P/N | Part Description | Manufacturer Full Name | Manufacturer P/N | RoHS | Sheet | Remark |
| 1 | C1476,C1477 | 2 | 62010MU00-015-G | CAP,20pF,+/-5%,NPO(C0G),50V,G,SMD0402 | MURATA ELEC. NORTH AMERICA | GRM1555C1H200J | G | PWA BOM | In New BOM |
|  |  |  | 62012UJ00-012-G | CAP,20pF,+/-5%,NPO(C0G),50V,G,SMD0402 | WALSIN | 0402N200J500CT | G | PWA BOM | In New BOM |
|  |  |  | 62010MU00-026-G | CAP,20pF,+/-5%,NPO(C0G),50V,G,SMD0402 | SAMSUNG | CL05C200JB5NNNC | G | PWA BOM | In New BOM |
|  | C1476,C1477 | 2 | 62010MU00-015-G | CAP,20pF,+/-5%,NPO(C0G),50V,G,SMD0402 | MURATA ELEC. NORTH AMERICA | GRM1555C1H200J | G | PWA BOM | In Old BOM |
| 2 | C2081,C2082 | 2 | 62012TW00-015-G | CAP,470nF,+/-10%,X7R,16V,G,SMD0402 | MURATA ELEC. NORTH AMERICA | GRM155R71C474KE01D | G | PWA BOM | In New BOM |
|  |  |  | 62012YQ00-026-G | CAP,470nF,+/-10%,X7R,10V,G,SMD0402 | SAMSUNG SEMICONDUCTOR | CL05B474KP5NNNC | G | PWA BOM | In New BOM |
|  | C2081,C2082 | 2 | 62012TW00-015-G | CAP,470nF,+/-10%,X7R,16V,G,SMD0402 | MURATA ELEC. NORTH AMERICA | GRM155R71C474KE01D | G | PWA BOM | In Old BOM |
| 3 | PBMC6,PBFC6,PBEC6,PBAC6,PAMC6,PAFC6,PAEC6,PAAC6 | 8 | 62011DQ00-015-G | CAP,27nF,+/-10%,X7R,25V,G,SMD0402 | MURATA ELEC. NORTH AMERICA | GRM155R71E273KA88D | G | PWA BOM | In New BOM |
|  |  |  | 620136P00-012-G | CAP,MLCC,27nF,+/-10%,X7R,25V,SMD0402,G | WALSIN TECHNOLOGY CORPORATION | 0402B273K250CT | G | PWA BOM | In New BOM |
|  |  |  | 62011DQ00-011-G | CAP,MLCC,27nF,+/-10%,X7R,25V,SMD0402,G | YAGEO CORPORATION COMPONENT | CC0402KRX7R8BB273 |  | PWA BOM | In New BOM |
|  | PBMC6,PBFC6,PBEC6,PBAC6,PAMC6,PAFC6,PAEC6,PAAC6 | 8 | 62011DQ00-015-G | CAP,27nF,+/-10%,X7R,25V,G,SMD0402 | MURATA ELEC. NORTH AMERICA | GRM155R71E273KA88D | G | PWA BOM | In Old BOM |
| 4 | PAAR66,PBAR67,PBAR79,PAAR79 | 4 | 610103D00-017-G | RES,24.3KOhm,+/-1%,1/10W,G,SMD0603 | KOA SPEER ELECTRONICS, INC. | RK73H1JTTD2432F | G | PWA BOM | In New BOM |
|  |  |  | 610103D00-011-G | RES,24.3KOhm,+/-1%,1/10W,G,SMD0603 | YAGEO CORPORATION COMPONENT | RC0603FR-0724K3L | G | PWA BOM | In New BOM |
|  |  |  | 610103D00-012-G | RES,24.3KOhm,+/-1%,1/10W,G,SMD0603 | WALSIN TECHNOLOGY CORPORATION | WR06X2432FTL | G | PWA BOM | In New BOM |
|  | PAAR66,PBAR67,PBAR79,PAAR79 | 4 | 610103D00-017-G | RES,24.3KOhm,+/-1%,1/10W,G,SMD0603 | KOA SPEER ELECTRONICS, INC. | RK73H1JTTD2432F | G | PWA BOM | In Old BOM |
| 5 | PBAR80,PAAR80 | 2 | 61010DG00-017-G | RES,4.99KOhm,+/-1%,1/10W,G,SMD0603 | KOA SPEER ELECTRONICS, INC. | RK73H1JTTD4991F | G | PWA BOM | In New BOM |
|  |  |  | 61010DG00-011-G | RES,4.99KOhm,+/-1%,1/10W,G,SMD0603 | YAGEO CORPORATION COMPONENT | RC0603FR-074K99L | G | PWA BOM | In New BOM |
|  |  |  | 61010DG00-044-G | RES,4.99KOhm,+/-1%,1/10W,G,SMD0603 | TA-I TECHNOLOGY CO., LTD | RM06FTN4991 | G | PWA BOM | In New BOM |
|  |  |  | 61010DG00-012-G | RES,4.99KOhm,+/-1%,1/10W,G,SMD0603 | WALSIN TECHNOLOGY CORPORATION | WR06X4991FTL | G | PWA BOM | In New BOM |
|  | PBAR80,PAAR80 | 2 | 61010DG00-017-G | RES,4.99KOhm,+/-1%,1/10W,G,SMD0603 | KOA SPEER ELECTRONICS, INC. | RK73H1JTTD4991F | G | PWA BOM | In Old BOM |
| 6 | PBAR127,PAAR127 | 2 | 61011G600-017-G | RES,133KOhm,+/-1%,1/16W,G,SMD0402 | KOA SPEER ELECTRONICS, INC. | RK73G1ETTP1333F | G | PWA BOM | In New BOM |
|  |  |  | 61011G600-011-G | RES,133KOhm,+/-1%,1/16W,G,SMD0402 | YAGEO CORPORATION COMPONENT | RC0402FR-07133KL | G | PWA BOM | In New BOM |
|  |  |  | 61011G600-012-G | RES,133KOhm,+/-1%,1/16W,G,SMD0402 | WALSIN TECHNOLOGY CORPORATION | WR04X1333FTL | G | PWA BOM | In New BOM |
|  |  |  | 61011G600-044-G | RES,133KOhm,+/-1%,1/16W,G,SMD0402 | TA-I TECHNOLOGY CO., LTD | RM04FTN1333 | G | PWA BOM | In New BOM |
|  | PBAR127,PAAR127 | 2 | 61011G600-017-G | RES,133KOhm,+/-1%,1/16W,G,SMD0402 | KOA SPEER ELECTRONICS, INC. | RK73G1ETTP1333F | G | PWA BOM | In Old BOM |
| 7 | PBFC4,PBEC4,PAFC4,PAEC4 | 4 | 620108600-015-G | CAP,180pF,+/-5%,NPO(C0G),50V,G,SMD0402 | MURATA ELEC. NORTH AMERICA | GRM1555C1H181J | G | PWA BOM | In New BOM |
|  |  |  | 620108600-026-G | CAP,180pF,+/-5%,NPO(C0G),50V,G,SMD0402 | SAMSUNG SEMICONDUCTOR | CL05C181JB5NNNC | G | PWA BOM | In New BOM |
|  |  |  | 620108600-023-G | CAP,180pF,+/-5%,NPO(C0G),50V,G,SMD0402 | TAIYO ELECTRIC IND.CO.LTD | UMK105CG181JV-F | G | PWA BOM | In New BOM |
|  |  |  | 620108600-011-G | CAP,180pF,+/-5%,NPO(C0G),50V,G,SMD0402 | YAGEO CORPORATION COMPONENT | CC0402JRNPO9BN181 | G | PWA BOM | In New BOM |
|  | PBFC4,PBEC4,PAFC4,PAEC4 | 4 | 620108600-015-G | CAP,180pF,+/-5%,NPO(C0G),50V,G,SMD0402 | MURATA ELEC. NORTH AMERICA | GRM1555C1H181J | G | PWA BOM | In Old BOM |
| 8 | PBFR57,PBER57,PAFR57,PAER57 | 4 | 610127L00-017-G | RES,215 Ohm,+/-1%,1/16W,G,SMD0402 | KOA SPEER ELECTRONICS, INC. | RK73H1ETTP2150F | G | PWA BOM | In New BOM |
|  |  |  | 610127L00-011-G | RES,215 Ohm,+/-1%,1/16W,G,SMD0402 | YAGEO CORPORATION COMPONENT | RC0402FR-07215RL | G | PWA BOM | In New BOM |
|  |  |  | 610127L00-012-G | RES,215 Ohm,+/-1%,1/16W,G,SMD0402 | WALSIN TECHNOLOGY CORPORATION | WR04X2150FTL | G | PWA BOM | In New BOM |
|  |  |  | 610127L00-044-G | RES,215 Ohm,+/-1%,1/16W,G,SMD0402 | TA-I TECHNOLOGY CO., LTD | RM04FTN2150 | G | PWA BOM | In New BOM |
|  | PBFR57,PBER57,PAFR57,PAER57 | 4 | 610127L00-017-G | RES,215 Ohm,+/-1%,1/16W,G,SMD0402 | KOA SPEER ELECTRONICS, INC. | RK73H1ETTP2150F | G | PWA BOM | In Old BOM |
| 9 | PBER84,PAFR84,PAER84,PBFR85 | 4 | 610107K00-017-G | RES,24.9KOhm,+/-1%,1/10W,G,SMD0603 | KOA SPEER ELECTRONICS, INC. | RK73H1JTTD2492F | G | PWA BOM | In New BOM |
|  |  |  | 610107K00-011-G | RES,24.9KOhm,+/-1%,1/10W,G,SMD0603 | YAGEO CORPORATION COMPONENT | RC0603FR-0724K9L | G | PWA BOM | In New BOM |
|  |  |  | 610107K00-012-G | RES,24.9KOhm,+/-1%,1/10W,G,SMD0603 | WALSIN TECHNOLOGY CORPORATION | WR06X2492FTL | G | PWA BOM | In New BOM |
|  | PBER84,PAFR84,PAER84,PBFR85 | 4 | 610107K00-017-G | RES,24.9KOhm,+/-1%,1/10W,G,SMD0603 | KOA SPEER ELECTRONICS, INC. | RK73H1JTTD2492F | G | PWA BOM | In Old BOM |
| 10 | PBMR57,PAMR57 | 2 | 610119U00-017-G | RES,133 Ohm,+/-1%,1/16W,G,SMD0402 | KOA SPEER ELECTRONICS, INC. | RK73H1ETTP1330F | G | PWA BOM | In New BOM |
|  |  |  | 610119U00-011-G | RES,133 Ohm,+/-1%,1/16W,G,SMD0402 | YAGEO CORPORATION COMPONENT | RC0402FR-07133RL | G | PWA BOM | In New BOM |
|  |  |  | 610119U00-012-G | RES,133 Ohm,+/-1%,1/16W,G,SMD0402 | WALSIN TECHNOLOGY CORPORATION | WR04X1330FTL | G | PWA BOM | In New BOM |
|  |  |  | 610119U00-044-G | RES,133 Ohm,+/-1%,1/16W,G,SMD0402 | TA-I TECHNOLOGY CO., LTD | RM04FTN1330 | G | PWA BOM | In New BOM |
|  | PBMR57,PAMR57 | 2 | 610119U00-017-G | RES,133 Ohm,+/-1%,1/16W,G,SMD0402 | KOA SPEER ELECTRONICS, INC. | RK73H1ETTP1330F | G | PWA BOM | In Old BOM |
| 11 | PBMR77,PAMR77 | 2 | 61010A700-017-G | RES,30.9KOhm,+/-1%,1/10W,G,SMD0603 | KOA SPEER ELECTRONICS, INC. | RK73H1JTTD3092F | G | PWA BOM | In New BOM |
|  |  |  | 61010A700-011-G | RES,30.9KOhm,+/-1%,1/10W,G,SMD0603 | YAGEO CORPORATION COMPONENT | RC0603FR-0730K9L | G | PWA BOM | In New BOM |
|  |  |  | 61010A700-012-G | RES,30.9KOhm,+/-1%,1/10W,G,SMD0603 | WALSIN TECHNOLOGY CORPORATION | WR06X3092FTL | G | PWA BOM | In New BOM |
|  | PBMR77,PAMR77 | 2 | 61010A700-017-G | RES,30.9KOhm,+/-1%,1/10W,G,SMD0603 | KOA SPEER ELECTRONICS, INC. | RK73H1JTTD3092F | G | PWA BOM | In Old BOM |
| 12 | PBMR121,PAMR121 | 2 | 61011FU00-017-G | RES,115KOhm,+/-1%,1/16W,G,SMD0402 | KOA SPEER ELECTRONICS, INC. | RK73H1ETTP1153F | G | PWA BOM | In New BOM |
|  |  |  | 61011FU00-011-G | RES,115KOhm,+/-1%,1/16W,G,SMD0402 | YAGEO CORPORATION COMPONENT | RC0402FR-07115KL | G | PWA BOM | In New BOM |
|  |  |  | 61011FU00-012-G | RES,115KOhm,+/-1%,1/16W,G,SMD0402 | WALSIN TECHNOLOGY CORPORATION | WR04X1153FTL | G | PWA BOM | In New BOM |
|  |  |  | 61011FU00-044-G | RES,115KOhm,+/-1%,1/16W,G,SMD0402 | TA-I TECHNOLOGY CO., LTD | RM04FTN1153 | G | PWA BOM | In New BOM |
|  | PBMR121,PAMR121 | 2 | 61011FU00-017-G | RES,115KOhm,+/-1%,1/16W,G,SMD0402 | KOA SPEER ELECTRONICS, INC. | RK73H1ETTP1153F | G | PWA BOM | In Old BOM |
| 13 | PUAC4,PSAC4,PRAC4,PQAC4,PPAC4,PIAC4,PFAC4,PEAC4,PUAC5,PSAC5,PRAC5,PQAC5,PPAC5,PIAC5,PFAC5,PEAC5,PUAC6,PSAC6,PRAC6,PQAC6,PPAC6,PIAC6,PFAC6,PEAC6 | 24 | 62011DD00-015-G | CAP,22uF,+/-10%,X6S,6.3V,G,SMD1206 | MURATA ELEC. NORTH AMERICA | GRM31CC80J226K | G | PWA BOM | In New BOM |
|  |  |  | 62011DD00-011-G | CAP,MLCC,22uF,+/-10%,X6S,6.3V,SMD1206,G | YAGEO CORPORATION COMPONENT | CC1206KKX6S5BB226 | G | PWA BOM | In New BOM |
|  | PUAC4,PSAC4,PRAC4,PQAC4,PPAC4,PIAC4,PFAC4,PEAC4,PUAC5,PSAC5,PRAC5,PQAC5,PPAC5,PIAC5,PFAC5,PEAC5,PUAC6,PSAC6,PRAC6,PQAC6,PPAC6,PIAC6,PFAC6,PEAC6 | 24 | 62011DD00-015-G | CAP,22uF,+/-10%,X6S,6.3V,G,SMD1206 | MURATA ELEC. NORTH AMERICA | GRM31CC80J226K | G | PWA BOM | In Old BOM |
| 14 | PSRC3,PERC3 | 2 | 62011M802-015-G | CAP,62pF,+/-5%,NPO(C0G),50V,G,SMD0402 | MURATA ELEC. NORTH AMERICA | GRM1555C1H620JA01D | G | PWA BOM | In New BOM |
|  |  |  | 62011M800-011-G | CAP,62pF,+/-5%,NPO(C0G),50V,G,SMD0402 | YAGEO CORPORATION COMPONENT | CC0402JRNPO9BN620 |  | PWA BOM | In New BOM |
|  |  |  | 62011M800-026-G | CAP,MLCC,62pF,+/-5%,NPO(C0G),50V,SMD0402,G | SAMSUNG SEMICONDUCTOR | CL05C620JB5NNNC |  | PWA BOM | In New BOM |
|  | PSRC3,PERC3 | 2 | 62011M802-015-G | CAP,62pF,+/-5%,NPO(C0G),50V,G,SMD0402 | MURATA ELEC. NORTH AMERICA | GRM1555C1H620JA01D | G | PWA BOM | In Old BOM |
| 15 | PSIR10,PETR10,PERR10,R938 | 4 | 61015JF00-017-G | RES,63.4 Ohm,+/-1%,1/10W,G,SMD0402 | KOA SPEER ELECTRONICS, INC. | RK73H1ETTP63R4F | G | PWA BOM | In New BOM |
|  |  |  | 61015JF00-044-G | RES,thick film,63.4Ohm,+/-1%,1/10W,SMD0402,G | TA-I TECHNOLOGY CO., LTD | RMH04FT63R4 | G | PWA BOM | In New BOM |
|  | PSIR10,PETR10,PERR10,R938 | 4 | 61015JF00-017-G | RES,63.4 Ohm,+/-1%,1/10W,G,SMD0402 | KOA SPEER ELECTRONICS, INC. | RK73H1ETTP63R4F | G | PWA BOM | In Old BOM |
| 16 | R839,R840,R841,R842,R843,R844,R845,R846,R847,R848,R849,R850,R851,R852,R853,R854,R855,R856,R857,R858,R859,R860,R861,R862,R867,R868,R869,R870,R871,R872,R873,R874,R875,R876,R877,R878,R879,R880,R881,R882,R883,R884,R885,R887,R888,R889,R890,R891 | 48 | 61011U901-017-G | RES,120Ohm,+/-1%,1/20W,G,SMD0201 | KOA SPEER ELECTRONICS, INC. | RK73H1HTTC1200F | G | PWA BOM | In New BOM |
|  |  |  | 61011U900-011-G | RES,thick film,120Ohm,+/-1%,1/20W,SMD0201,G | YAGEO CORPORATION COMPONENT | RC0201FR-07120RL | G | PWA BOM | In New BOM |
|  |  |  | 61011U900-012-G | RES,thick film,120Ohm,+/-1%,1/20W,SMD0201,G | WALSIN TECHNOLOGY CORPORATION | WR02X1200FAL | G | PWA BOM | In New BOM |
|  |  |  | 61011U900-044-G | RES,thick film,120Ohm,+/-1%,1/20W,SMD0201,G | TA-I TECHNOLOGY CO., LTD | RM02FTN1200 | G | PWA BOM | In New BOM |
|  | R839,R840,R841,R842,R843,R844,R845,R846,R847,R848,R849,R850,R851,R852,R853,R854,R855,R856,R857,R858,R859,R860,R861,R862,R867,R868,R869,R870,R871,R872,R873,R874,R875,R876,R877,R878,R879,R880,R881,R882,R883,R884,R885,R887,R888,R889,R890,R891 | 48 | 61011U901-017-G | RES,120Ohm,+/-1%,1/20W,G,SMD0201 | KOA SPEER ELECTRONICS, INC. | RK73H1HTTC1200F | G | PWA BOM | In Old BOM |
| ##### Change Revision |  |  |  |  |  |  |  |  |  |
| Sheet | REV OF BOM | CUSTOMER | CUSTOMER P/N | PWA PN | PWA DESCRIPTION | PWA REV | DATE | Remark |  |
| OOOOOOOOOOOOOOOOOOOOOOOOOOOOOOOOOOOOOOOOOOOOOOOOOOOOOOOOOOOOOOOOOOOOOOOOOOOOOOOOOOOOOOOOOO | OOOOOOOOOOOOOOOOOOOOOOOOOOOOOOOOOOOOOOOOOOOOOOOOOOOOOOOOOOOOOOOOOOOOOOOOOOOOOOOOOOOOOOOOOO | OOOOOOOOOOOOOOOOOOOOOOOOOOOOOOOOOOOOOOOOOOOOOOOOOOOOOOOOOOOOOOOOOOOOOOOOOOOOOOOOOOOOOOOOOO | OOOOOOOOOOOOOOOOOOOOOOOOOOOOOOOOOOOOOOOOOOOOOOOOOOOOOOOOOOOOOOOOOOOOOOOOOOOOOOOOOOOOOOOOOO | OOOOOOOOOOOOOOOOOOOOOOOOOOOOOOOOOOOOOOOOOOOOOOOOOOOOOOOOOOOOOOOOOOOOOOOOOOOOOOOOOOOOOOOOOO | OOOOOOOOOOOOOOOOOOOOOOOOOOOOOOOOOOOOOOOOOOOOOOOOOOOOOOOOOOOOOOOOOOOOOOOOOOOOOOOOOOOOOOOOOO | OOOOOOOOOOOOOOOOOOOOOOOOOOOOOOOOOOOOOOOOOOOOOOOOOOOOOOOOOOOOOOOOOOOOOOOOOOOOOOOOOOOOOOOOOO | OOOOOOOOOOOOOOOOOOOOOOOOOOOOOOOOOOOOOOOOOOOOOOOOOOOOOOOOOOOOOOOOOOOOOOOOOOOOOOOOOOOOOOOOOO | OOOOOOOOOOOOOOOOOOOOOOOOOOOOOOOOOOOOOOOOOOOOOOOOOOOOOOOOOOOOOOOOOOOOOOOOOOOOOOOOOOOOOOOOOO | OOOOOOOOOOOOOOOOOOOOOOOOOOOOOOOOOOOOOOOOOOOOOOOOOOOOOOOOOOOOOOOOOOOOOOOOOOOOOOOOOOOOOOOOOO |
| Second Source Change |  |  |  |  |  |  |  |  |  |
| Item | Location | Change Type | Foxconn P/N | Part Description | Manufacturer Full Name | Manufacturer P/N | RoHS | Sheet |  |
| 1 | C1476,C1477 |  | 62010MU00-015-G | CAP,20pF,+/-5%,NPO(C0G),50V,G,SMD0402 | MURATA ELEC. NORTH AMERICA | GRM1555C1H200J | G | PWA BOM |  |
|  |  | ADD | 62012UJ00-012-G | CAP,20pF,+/-5%,NPO(C0G),50V,G,SMD0402 | WALSIN | 0402N200J500CT | G | PWA BOM |  |
|  |  | ADD | 62010MU00-026-G | CAP,20pF,+/-5%,NPO(C0G),50V,G,SMD0402 | SAMSUNG | CL05C200JB5NNNC | G | PWA BOM |  |
| 2 | C2081,C2082 |  | 62012TW00-015-G | CAP,470nF,+/-10%,X7R,16V,G,SMD0402 | MURATA ELEC. NORTH AMERICA | GRM155R71C474KE01D | G | PWA BOM |  |
|  |  | ADD | 62012YQ00-026-G | CAP,470nF,+/-10%,X7R,10V,G,SMD0402 | SAMSUNG SEMICONDUCTOR | CL05B474KP5NNNC | G | PWA BOM |  |
| 3 | PBMC6,PBFC6,PBEC6,PBAC6,PAMC6,PAFC6,PAEC6,PAAC6 |  | 62011DQ00-015-G | CAP,27nF,+/-10%,X7R,25V,G,SMD0402 | MURATA ELEC. NORTH AMERICA | GRM155R71E273KA88D | G | PWA BOM |  |
|  |  | ADD | 620136P00-012-G | CAP,MLCC,27nF,+/-10%,X7R,25V,SMD0402,G | WALSIN TECHNOLOGY CORPORATION | 0402B273K250CT | G | PWA BOM |  |
|  |  | ADD | 62011DQ00-011-G | CAP,MLCC,27nF,+/-10%,X7R,25V,SMD0402,G | YAGEO CORPORATION COMPONENT | CC0402KRX7R8BB273 |  | PWA BOM |  |
| 4 | PAAR66,PBAR67,PBAR79,PAAR79 |  | 610103D00-017-G | RES,24.3KOhm,+/-1%,1/10W,G,SMD0603 | KOA SPEER ELECTRONICS, INC. | RK73H1JTTD2432F | G | PWA BOM |  |
|  |  | ADD | 610103D00-011-G | RES,24.3KOhm,+/-1%,1/10W,G,SMD0603 | YAGEO CORPORATION COMPONENT | RC0603FR-0724K3L | G | PWA BOM |  |
|  |  | ADD | 610103D00-012-G | RES,24.3KOhm,+/-1%,1/10W,G,SMD0603 | WALSIN TECHNOLOGY CORPORATION | WR06X2432FTL | G | PWA BOM |  |
| 5 | PBAR80,PAAR80 |  | 61010DG00-017-G | RES,4.99KOhm,+/-1%,1/10W,G,SMD0603 | KOA SPEER ELECTRONICS, INC. | RK73H1JTTD4991F | G | PWA BOM |  |
|  |  | ADD | 61010DG00-011-G | RES,4.99KOhm,+/-1%,1/10W,G,SMD0603 | YAGEO CORPORATION COMPONENT | RC0603FR-074K99L | G | PWA BOM |  |
|  |  | ADD | 61010DG00-044-G | RES,4.99KOhm,+/-1%,1/10W,G,SMD0603 | TA-I TECHNOLOGY CO., LTD | RM06FTN4991 | G | PWA BOM |  |
|  |  | ADD | 61010DG00-012-G | RES,4.99KOhm,+/-1%,1/10W,G,SMD0603 | WALSIN TECHNOLOGY CORPORATION | WR06X4991FTL | G | PWA BOM |  |
| 6 | PBAR127,PAAR127 |  | 61011G600-017-G | RES,133KOhm,+/-1%,1/16W,G,SMD0402 | KOA SPEER ELECTRONICS, INC. | RK73G1ETTP1333F | G | PWA BOM |  |
|  |  | ADD | 61011G600-011-G | RES,133KOhm,+/-1%,1/16W,G,SMD0402 | YAGEO CORPORATION COMPONENT | RC0402FR-07133KL | G | PWA BOM |  |
|  |  | ADD | 61011G600-012-G | RES,133KOhm,+/-1%,1/16W,G,SMD0402 | WALSIN TECHNOLOGY CORPORATION | WR04X1333FTL | G | PWA BOM |  |
|  |  | ADD | 61011G600-044-G | RES,133KOhm,+/-1%,1/16W,G,SMD0402 | TA-I TECHNOLOGY CO., LTD | RM04FTN1333 | G | PWA BOM |  |
| 7 | PBFC4,PBEC4,PAFC4,PAEC4 |  | 620108600-015-G | CAP,180pF,+/-5%,NPO(C0G),50V,G,SMD0402 | MURATA ELEC. NORTH AMERICA | GRM1555C1H181J | G | PWA BOM |  |
|  |  | ADD | 620108600-026-G | CAP,180pF,+/-5%,NPO(C0G),50V,G,SMD0402 | SAMSUNG SEMICONDUCTOR | CL05C181JB5NNNC | G | PWA BOM |  |
|  |  | ADD | 620108600-023-G | CAP,180pF,+/-5%,NPO(C0G),50V,G,SMD0402 | TAIYO ELECTRIC IND.CO.LTD | UMK105CG181JV-F | G | PWA BOM |  |
|  |  | ADD | 620108600-011-G | CAP,180pF,+/-5%,NPO(C0G),50V,G,SMD0402 | YAGEO CORPORATION COMPONENT | CC0402JRNPO9BN181 | G | PWA BOM |  |
| 8 | PBFR57,PBER57,PAFR57,PAER57 |  | 610127L00-017-G | RES,215 Ohm,+/-1%,1/16W,G,SMD0402 | KOA SPEER ELECTRONICS, INC. | RK73H1ETTP2150F | G | PWA BOM |  |
|  |  | ADD | 610127L00-011-G | RES,215 Ohm,+/-1%,1/16W,G,SMD0402 | YAGEO CORPORATION COMPONENT | RC0402FR-07215RL | G | PWA BOM |  |
|  |  | ADD | 610127L00-012-G | RES,215 Ohm,+/-1%,1/16W,G,SMD0402 | WALSIN TECHNOLOGY CORPORATION | WR04X2150FTL | G | PWA BOM |  |
|  |  | ADD | 610127L00-044-G | RES,215 Ohm,+/-1%,1/16W,G,SMD0402 | TA-I TECHNOLOGY CO., LTD | RM04FTN2150 | G | PWA BOM |  |
| 9 | PBER84,PAFR84,PAER84,PBFR85 |  | 610107K00-017-G | RES,24.9KOhm,+/-1%,1/10W,G,SMD0603 | KOA SPEER ELECTRONICS, INC. | RK73H1JTTD2492F | G | PWA BOM |  |
|  |  | ADD | 610107K00-011-G | RES,24.9KOhm,+/-1%,1/10W,G,SMD0603 | YAGEO CORPORATION COMPONENT | RC0603FR-0724K9L | G | PWA BOM |  |
|  |  | ADD | 610107K00-012-G | RES,24.9KOhm,+/-1%,1/10W,G,SMD0603 | WALSIN TECHNOLOGY CORPORATION | WR06X2492FTL | G | PWA BOM |  |
| 10 | PBMR57,PAMR57 |  | 610119U00-017-G | RES,133 Ohm,+/-1%,1/16W,G,SMD0402 | KOA SPEER ELECTRONICS, INC. | RK73H1ETTP1330F | G | PWA BOM |  |
|  |  | ADD | 610119U00-011-G | RES,133 Ohm,+/-1%,1/16W,G,SMD0402 | YAGEO CORPORATION COMPONENT | RC0402FR-07133RL | G | PWA BOM |  |
|  |  | ADD | 610119U00-012-G | RES,133 Ohm,+/-1%,1/16W,G,SMD0402 | WALSIN TECHNOLOGY CORPORATION | WR04X1330FTL | G | PWA BOM |  |
|  |  | ADD | 610119U00-044-G | RES,133 Ohm,+/-1%,1/16W,G,SMD0402 | TA-I TECHNOLOGY CO., LTD | RM04FTN1330 | G | PWA BOM |  |
| 11 | PBMR77,PAMR77 |  | 61010A700-017-G | RES,30.9KOhm,+/-1%,1/10W,G,SMD0603 | KOA SPEER ELECTRONICS, INC. | RK73H1JTTD3092F | G | PWA BOM |  |
|  |  | ADD | 61010A700-011-G | RES,30.9KOhm,+/-1%,1/10W,G,SMD0603 | YAGEO CORPORATION COMPONENT | RC0603FR-0730K9L | G | PWA BOM |  |
|  |  | ADD | 61010A700-012-G | RES,30.9KOhm,+/-1%,1/10W,G,SMD0603 | WALSIN TECHNOLOGY CORPORATION | WR06X3092FTL | G | PWA BOM |  |
| 12 | PBMR121,PAMR121 |  | 61011FU00-017-G | RES,115KOhm,+/-1%,1/16W,G,SMD0402 | KOA SPEER ELECTRONICS, INC. | RK73H1ETTP1153F | G | PWA BOM |  |
|  |  | ADD | 61011FU00-011-G | RES,115KOhm,+/-1%,1/16W,G,SMD0402 | YAGEO CORPORATION COMPONENT | RC0402FR-07115KL | G | PWA BOM |  |
|  |  | ADD | 61011FU00-012-G | RES,115KOhm,+/-1%,1/16W,G,SMD0402 | WALSIN TECHNOLOGY CORPORATION | WR04X1153FTL | G | PWA BOM |  |
|  |  | ADD | 61011FU00-044-G | RES,115KOhm,+/-1%,1/16W,G,SMD0402 | TA-I TECHNOLOGY CO., LTD | RM04FTN1153 | G | PWA BOM |  |
| 13 | PUAC4,PSAC4,PRAC4,PQAC4,PPAC4,PIAC4,PFAC4,PEAC4,PUAC5,PSAC5,PRAC5,PQAC5,PPAC5,PIAC5,PFAC5,PEAC5,PUAC6,PSAC6,PRAC6,PQAC6,PPAC6,PIAC6,PFAC6,PEAC6 |  | 62011DD00-015-G | CAP,22uF,+/-10%,X6S,6.3V,G,SMD1206 | MURATA ELEC. NORTH AMERICA | GRM31CC80J226K | G | PWA BOM |  |
|  |  | ADD | 62011DD00-011-G | CAP,MLCC,22uF,+/-10%,X6S,6.3V,SMD1206,G | YAGEO CORPORATION COMPONENT | CC1206KKX6S5BB226 | G | PWA BOM |  |
| 14 | PSRC3,PERC3 |  | 62011M802-015-G | CAP,62pF,+/-5%,NPO(C0G),50V,G,SMD0402 | MURATA ELEC. NORTH AMERICA | GRM1555C1H620JA01D | G | PWA BOM |  |
|  |  | ADD | 62011M800-011-G | CAP,62pF,+/-5%,NPO(C0G),50V,G,SMD0402 | YAGEO CORPORATION COMPONENT | CC0402JRNPO9BN620 |  | PWA BOM |  |
|  |  | ADD | 62011M800-026-G | CAP,MLCC,62pF,+/-5%,NPO(C0G),50V,SMD0402,G | SAMSUNG SEMICONDUCTOR | CL05C620JB5NNNC |  | PWA BOM |  |
| 15 | PSIR10,PETR10,PERR10,R938 |  | 61015JF00-017-G | RES,63.4 Ohm,+/-1%,1/10W,G,SMD0402 | KOA SPEER ELECTRONICS, INC. | RK73H1ETTP63R4F | G | PWA BOM |  |
|  |  | ADD | 61015JF00-044-G | RES,thick film,63.4Ohm,+/-1%,1/10W,SMD0402,G | TA-I TECHNOLOGY CO., LTD | RMH04FT63R4 | G | PWA BOM |  |
| 16 | R839,R840,R841,R842,R843,R844,R845,R846,R847,R848,R849,R850,R851,R852,R853,R854,R855,R856,R857,R858,R859,R860,R861,R862,R867,R868,R869,R870,R871,R872,R873,R874,R875,R876,R877,R878,R879,R880,R881,R882,R883,R884,R885,R887,R888,R889,R890,R891 |  | 61011U901-017-G | RES,120Ohm,+/-1%,1/20W,G,SMD0201 | KOA SPEER ELECTRONICS, INC. | RK73H1HTTC1200F | G | PWA BOM |  |
|  |  | ADD | 61011U900-011-G | RES,thick film,120Ohm,+/-1%,1/20W,SMD0201,G | YAGEO CORPORATION COMPONENT | RC0201FR-07120RL | G | PWA BOM |  |
|  |  | ADD | 61011U900-012-G | RES,thick film,120Ohm,+/-1%,1/20W,SMD0201,G | WALSIN TECHNOLOGY CORPORATION | WR02X1200FAL | G | PWA BOM |  |
|  |  | ADD | 61011U900-044-G | RES,thick film,120Ohm,+/-1%,1/20W,SMD0201,G | TA-I TECHNOLOGY CO., LTD | RM02FTN1200 | G | PWA BOM |  |
| OOOOOOOOOOOOOOOOOOOOOOOOOOOOOOOOOOOOOOOOOOOOOOOOOOOOOOOOOOOOOOOOOOOOOOOOOOOOOOOOOOOOOOOOOO | OOOOOOOOOOOOOOOOOOOOOOOOOOOOOOOOOOOOOOOOOOOOOOOOOOOOOOOOOOOOOOOOOOOOOOOOOOOOOOOOOOOOOOOOOO | OOOOOOOOOOOOOOOOOOOOOOOOOOOOOOOOOOOOOOOOOOOOOOOOOOOOOOOOOOOOOOOOOOOOOOOOOOOOOOOOOOOOOOOOOO | OOOOOOOOOOOOOOOOOOOOOOOOOOOOOOOOOOOOOOOOOOOOOOOOOOOOOOOOOOOOOOOOOOOOOOOOOOOOOOOOOOOOOOOOOO | OOOOOOOOOOOOOOOOOOOOOOOOOOOOOOOOOOOOOOOOOOOOOOOOOOOOOOOOOOOOOOOOOOOOOOOOOOOOOOOOOOOOOOOOOO | OOOOOOOOOOOOOOOOOOOOOOOOOOOOOOOOOOOOOOOOOOOOOOOOOOOOOOOOOOOOOOOOOOOOOOOOOOOOOOOOOOOOOOOOOO | OOOOOOOOOOOOOOOOOOOOOOOOOOOOOOOOOOOOOOOOOOOOOOOOOOOOOOOOOOOOOOOOOOOOOOOOOOOOOOOOOOOOOOOOOO | OOOOOOOOOOOOOOOOOOOOOOOOOOOOOOOOOOOOOOOOOOOOOOOOOOOOOOOOOOOOOOOOOOOOOOOOOOOOOOOOOOOOOOOOOO | OOOOOOOOOOOOOOOOOOOOOOOOOOOOOOOOOOOOOOOOOOOOOOOOOOOOOOOOOOOOOOOOOOOOOOOOOOOOOOOOOOOOOOOOOO | OOOOOOOOOOOOOOOOOOOOOOOOOOOOOOOOOOOOOOOOOOOOOOOOOOOOOOOOOOOOOOOOOOOOOOOOOOOOOOOOOOOOOOOOOO |
| Master Materials Change |  |  |  |  |  |  |  |  |  |
| Item | Foxconn P/N | Orig._Usage | New_Usage | Part Description | Manufacturer Full Name | Manufacturer P/N | RoHS | Location | Sheet |
| OOOOOOOOOOOOOOOOOOOOOOOOOOOOOOOOOOOOOOOOOOOOOOOOOOOOOOOOOOOOOOOOOOOOOOOOOOOOOOOOOOOOOOOOOO | OOOOOOOOOOOOOOOOOOOOOOOOOOOOOOOOOOOOOOOOOOOOOOOOOOOOOOOOOOOOOOOOOOOOOOOOOOOOOOOOOOOOOOOOOO | OOOOOOOOOOOOOOOOOOOOOOOOOOOOOOOOOOOOOOOOOOOOOOOOOOOOOOOOOOOOOOOOOOOOOOOOOOOOOOOOOOOOOOOOOO | OOOOOOOOOOOOOOOOOOOOOOOOOOOOOOOOOOOOOOOOOOOOOOOOOOOOOOOOOOOOOOOOOOOOOOOOOOOOOOOOOOOOOOOOOO | OOOOOOOOOOOOOOOOOOOOOOOOOOOOOOOOOOOOOOOOOOOOOOOOOOOOOOOOOOOOOOOOOOOOOOOOOOOOOOOOOOOOOOOOOO | OOOOOOOOOOOOOOOOOOOOOOOOOOOOOOOOOOOOOOOOOOOOOOOOOOOOOOOOOOOOOOOOOOOOOOOOOOOOOOOOOOOOOOOOOO | OOOOOOOOOOOOOOOOOOOOOOOOOOOOOOOOOOOOOOOOOOOOOOOOOOOOOOOOOOOOOOOOOOOOOOOOOOOOOOOOOOOOOOOOOO | OOOOOOOOOOOOOOOOOOOOOOOOOOOOOOOOOOOOOOOOOOOOOOOOOOOOOOOOOOOOOOOOOOOOOOOOOOOOOOOOOOOOOOOOOO | OOOOOOOOOOOOOOOOOOOOOOOOOOOOOOOOOOOOOOOOOOOOOOOOOOOOOOOOOOOOOOOOOOOOOOOOOOOOOOOOOOOOOOOOOO | OOOOOOOOOOOOOOOOOOOOOOOOOOOOOOOOOOOOOOOOOOOOOOOOOOOOOOOOOOOOOOOOOOOOOOOOOOOOOOOOOOOOOOOOOO |
| TLA Parts Change |  |  |  |  |  |  |  |  |  |
| Item | Foxconn P/N | Qty | Part Description | Manufacturer Full Name | Manufacturer P/N | RoHS | Location | Remark | BOM |
| BOM Change List Date:Fri Aug 11 09:50:31 GMT+08:00 2017 |  |  |  |  |  |  |  |  |  |
| New BOM file : E:\barreleye g2\0810\foxbis\绝对完美new.xls |  |  |  |  |  |  |  |  |  |
| Old BOM file : E:\barreleye g2\0810\foxbis\绝对完美old.xls |  |  |  |  |  |  |  |  |  |
| ##### Add Parts |  |  |  |  |  |  |  |  |  |
| Item | Location | Qty | Foxconn P/N | Part Description | Manufacturer Full Name | Manufacturer P/N | RoHS | Sheet |  |
| ##### Remove Parts |  |  |  |  |  |  |  |  |  |
| Item | Location | Qty | Foxconn P/N | Part Description | Manufacturer Full Name | Manufacturer P/N | RoHS | Sheet |  |
| 1 | FS30 | 1 | 730101C00-086-G | Fuse,Slow blow,125V,30A,G,SMD | LITTELFUSE FAR EAST PTE LTD | 0456030.ER | G | PWA BOM |  |
| 2 | J36,J41,J43,J48 | 4 | 34068LN00-317-G | CONN,Header,Pin Header,1X3,V/T,2.54mm,30u,G,SMD-3 | MOLEX INCORPORATED | 87898-0315 | G | PWA BOM |  |
|  |  |  | 34068HT00-245-G | CONN,Header,Pin Header,1X3,V/T,Bla,2.54mm,30u,SMD-3 | AMPHENOL SHANGHAI CORP. | G800MU305010EU | G | PWA BOM |  |
|  |  |  | 34068GU00-309-G | CONN,Header,Pin Header,1X3,V/T,Bla,2.54mm,30u,SMD-3 | SAMTEC INC. | TSM-103-01-S-SV-P-TR | G | PWA BOM |  |
| 3 | J6 | 1 | 340692800-309-G | CONN,Header,Socket,2X30,V/T,Bla,0.5mm,G/F,G,SMD-60 | SAMTEC INC. | QSH-030-01-F-D-A-K-TR | G | PWA BOM |  |
| 4 | J8 | 1 | 340459T00-GRS-G | CONN,I/O,HDMI,V/T,Bla,0.5mm,1u,G,SMD-19 | LOTES CO LTD | AHDM0001-P004A | G | PWA BOM |  |
| 5 | J35,J37,J39,J42,J45 | 5 | 3406AQH00-317-G | CONN,Header,Pin Header,1X6,V/T,Bla,2.54mm,G,SMD-6 | MOLEX INCORPORATED | 87898-0656 | G | PWA BOM |  |
|  |  |  | 3406BAS00-245-G | CONN,Header,Pin Header,1X6,V/T,Bla,2.54mm,G,SMD-6 | AMPHENOL SHANGHAI CORP. | G800MR302032HR | G | PWA BOM |  |
|  |  |  | 3406A9F00-GRT-G | Header&Socket Connector,212-91-06GBE2,Pin Header,6,SMD,NY6T,2.54mm,3u",Black,G | PINREX TECHNOLOGY CORP. | 212-91-06GBE2 | G | PWA BOM |  |
| 6 | J100 | 1 | 3406ARP00-317-G | CONN,Header,Power,2X8,V/T,Whi,4.2mm,G,DIP-16 | MOLEX INCORPORATED | 46015-1602 | G | PWA BOM |  |
| ##### Change Parts |  |  |  |  |  |  |  |  |  |
| Item | Location | Qty | Foxconn P/N | Part Description | Manufacturer Full Name | Manufacturer P/N | RoHS | Sheet | Remark |
| 1 | PSUCE1,PBACE1,PAACE1,PSUCE2,PBACE2,PAACE2 | 6 | EEEFK2A680AQ | ECAP,68uF,+/-20%,100V,105C,G,SMD12.5*13.5,ESR<=320mOhm | PANASONIC INDUSTRIAL CO.,LTD. | EEEFK2A680AQ | G | PWA BOM | In New BOM |
|  | PSUCE1,PBACE1,PAACE1,PSUCE2,PBACE2,PAACE2 | 6 | 62111CS00-024-G | ECAP,68uF,+/-20%,100V,105C,G,SMD12.5*13.5,ESR<=320mOhm | PANASONIC INDUSTRIAL CO.,LTD. | EEVFK2A680Q | G | PWA BOM | In Old BOM |
|  |  |  | 62111RR00-025-G | ECAP,AL,Low ESR(LESR),68uF,+/-20%,100V,105_x0003_,500mOhm,SMD,12.5*13.5,G | KEMET ELECTRONICS CORPORATION | EXV686M100A9RAA | G | PWA BOM | In Old BOM |
|  |  |  | 62111SK00-021-G | ECAP,AL,Low ESR(LESR),68uF,+/-20%,100V,105_x0003_,330mOhm,SMD,12.5*13.5,G | NIPPON CHEMI-CON CORPORATION | EMVY101ARA680MKE0S | G | PWA BOM | In Old BOM |
| ##### Change Revision |  |  |  |  |  |  |  |  |  |
| Sheet | REV OF BOM | CUSTOMER | CUSTOMER P/N | PWA PN | PWA DESCRIPTION | PWA REV | DATE | Remark |  |
| OOOOOOOOOOOOOOOOOOOOOOOOOOOOOOOOOOOOOOOOOOOOOOOOOOOOOOOOOOOOOOOOOOOOOOOOOOOOOOOOOOOOOOOOOO | OOOOOOOOOOOOOOOOOOOOOOOOOOOOOOOOOOOOOOOOOOOOOOOOOOOOOOOOOOOOOOOOOOOOOOOOOOOOOOOOOOOOOOOOOO | OOOOOOOOOOOOOOOOOOOOOOOOOOOOOOOOOOOOOOOOOOOOOOOOOOOOOOOOOOOOOOOOOOOOOOOOOOOOOOOOOOOOOOOOOO | OOOOOOOOOOOOOOOOOOOOOOOOOOOOOOOOOOOOOOOOOOOOOOOOOOOOOOOOOOOOOOOOOOOOOOOOOOOOOOOOOOOOOOOOOO | OOOOOOOOOOOOOOOOOOOOOOOOOOOOOOOOOOOOOOOOOOOOOOOOOOOOOOOOOOOOOOOOOOOOOOOOOOOOOOOOOOOOOOOOOO | OOOOOOOOOOOOOOOOOOOOOOOOOOOOOOOOOOOOOOOOOOOOOOOOOOOOOOOOOOOOOOOOOOOOOOOOOOOOOOOOOOOOOOOOOO | OOOOOOOOOOOOOOOOOOOOOOOOOOOOOOOOOOOOOOOOOOOOOOOOOOOOOOOOOOOOOOOOOOOOOOOOOOOOOOOOOOOOOOOOOO | OOOOOOOOOOOOOOOOOOOOOOOOOOOOOOOOOOOOOOOOOOOOOOOOOOOOOOOOOOOOOOOOOOOOOOOOOOOOOOOOOOOOOOOOOO | OOOOOOOOOOOOOOOOOOOOOOOOOOOOOOOOOOOOOOOOOOOOOOOOOOOOOOOOOOOOOOOOOOOOOOOOOOOOOOOOOOOOOOOOOO | OOOOOOOOOOOOOOOOOOOOOOOOOOOOOOOOOOOOOOOOOOOOOOOOOOOOOOOOOOOOOOOOOOOOOOOOOOOOOOOOOOOOOOOOOO |
| Second Source Change |  |  |  |  |  |  |  |  |  |
| Item | Location | Change Type | Foxconn P/N | Part Description | Manufacturer Full Name | Manufacturer P/N | RoHS | Sheet |  |
| OOOOOOOOOOOOOOOOOOOOOOOOOOOOOOOOOOOOOOOOOOOOOOOOOOOOOOOOOOOOOOOOOOOOOOOOOOOOOOOOOOOOOOOOOO | OOOOOOOOOOOOOOOOOOOOOOOOOOOOOOOOOOOOOOOOOOOOOOOOOOOOOOOOOOOOOOOOOOOOOOOOOOOOOOOOOOOOOOOOOO | OOOOOOOOOOOOOOOOOOOOOOOOOOOOOOOOOOOOOOOOOOOOOOOOOOOOOOOOOOOOOOOOOOOOOOOOOOOOOOOOOOOOOOOOOO | OOOOOOOOOOOOOOOOOOOOOOOOOOOOOOOOOOOOOOOOOOOOOOOOOOOOOOOOOOOOOOOOOOOOOOOOOOOOOOOOOOOOOOOOOO | OOOOOOOOOOOOOOOOOOOOOOOOOOOOOOOOOOOOOOOOOOOOOOOOOOOOOOOOOOOOOOOOOOOOOOOOOOOOOOOOOOOOOOOOOO | OOOOOOOOOOOOOOOOOOOOOOOOOOOOOOOOOOOOOOOOOOOOOOOOOOOOOOOOOOOOOOOOOOOOOOOOOOOOOOOOOOOOOOOOOO | OOOOOOOOOOOOOOOOOOOOOOOOOOOOOOOOOOOOOOOOOOOOOOOOOOOOOOOOOOOOOOOOOOOOOOOOOOOOOOOOOOOOOOOOOO | OOOOOOOOOOOOOOOOOOOOOOOOOOOOOOOOOOOOOOOOOOOOOOOOOOOOOOOOOOOOOOOOOOOOOOOOOOOOOOOOOOOOOOOOOO | OOOOOOOOOOOOOOOOOOOOOOOOOOOOOOOOOOOOOOOOOOOOOOOOOOOOOOOOOOOOOOOOOOOOOOOOOOOOOOOOOOOOOOOOOO | OOOOOOOOOOOOOOOOOOOOOOOOOOOOOOOOOOOOOOOOOOOOOOOOOOOOOOOOOOOOOOOOOOOOOOOOOOOOOOOOOOOOOOOOOO |
| Master Materials Change |  |  |  |  |  |  |  |  |  |
| Item | Foxconn P/N | Orig._Usage | New_Usage | Part Description | Manufacturer Full Name | Manufacturer P/N | RoHS | Location | Sheet |
| 1 | EEEFK2A680AQ | 0 | 6 | ECAP,68uF,+/-20%,100V,105C,G,SMD12.5*13.5,ESR<=320mOhm | PANASONIC INDUSTRIAL CO.,LTD. | EEEFK2A680AQ | G | (+)PSUCE1,PBACE1,PAACE1,PSUCE2,PBACE2,PAACE2 | PWA BOM |
| 2 | 34068LN00-317-G | 10 | 6 | CONN,Header,Pin Header,1X3,V/T,2.54mm,30u,G,SMD-3 | MOLEX INCORPORATED | 87898-0315 | G | (-)J36,J41,J43,J48 | PWA BOM |
|  | 34068HT00-245-G |  |  | CONN,Header,Pin Header,1X3,V/T,Bla,2.54mm,30u,SMD-3 | AMPHENOL SHANGHAI CORP. | G800MU305010EU |  |  | PWA BOM |
|  | 34068GU00-309-G |  |  | CONN,Header,Pin Header,1X3,V/T,Bla,2.54mm,30u,SMD-3 | SAMTEC INC. | TSM-103-01-S-SV-P-TR |  |  | PWA BOM |
| 3 | 340692800-309-G | 2 | 1 | CONN,Header,Socket,2X30,V/T,Bla,0.5mm,G/F,G,SMD-60 | SAMTEC INC. | QSH-030-01-F-D-A-K-TR | G | (-)J6 | PWA BOM |
| 4 | 730101C00-086-G | 1 | 0 | Fuse,Slow blow,125V,30A,G,SMD | LITTELFUSE FAR EAST PTE LTD | 0456030.ER | G | (-)FS30 | PWA BOM |
| 5 | 62111CS00-024-G | 6 | 0 | ECAP,68uF,+/-20%,100V,105C,G,SMD12.5*13.5,ESR<=320mOhm | PANASONIC INDUSTRIAL CO.,LTD. | EEVFK2A680Q | G | (-)PSUCE1,PBACE1,PAACE1,PSUCE2,PBACE2,PAACE2 | PWA BOM |
|  | 62111RR00-025-G |  |  | ECAP,AL,Low ESR(LESR),68uF,+/-20%,100V,105_x0003_,500mOhm,SMD,12.5*13.5,G | KEMET ELECTRONICS CORPORATION | EXV686M100A9RAA |  |  | PWA BOM |
|  | 62111SK00-021-G |  |  | ECAP,AL,Low ESR(LESR),68uF,+/-20%,100V,105_x0003_,330mOhm,SMD,12.5*13.5,G | NIPPON CHEMI-CON CORPORATION | EMVY101ARA680MKE0S |  |  | PWA BOM |
| 6 | 340459T00-GRS-G | 1 | 0 | CONN,I/O,HDMI,V/T,Bla,0.5mm,1u,G,SMD-19 | LOTES CO LTD | AHDM0001-P004A | G | (-)J8 | PWA BOM |
| 7 | 3406AQH00-317-G | 5 | 0 | CONN,Header,Pin Header,1X6,V/T,Bla,2.54mm,G,SMD-6 | MOLEX INCORPORATED | 87898-0656 | G | (-)J35,J37,J39,J42,J45 | PWA BOM |
|  | 3406BAS00-245-G |  |  | CONN,Header,Pin Header,1X6,V/T,Bla,2.54mm,G,SMD-6 | AMPHENOL SHANGHAI CORP. | G800MR302032HR |  |  | PWA BOM |
|  | 3406A9F00-GRT-G |  |  | Header&Socket Connector,212-91-06GBE2,Pin Header,6,SMD,NY6T,2.54mm,3u",Black,G | PINREX TECHNOLOGY CORP. | 212-91-06GBE2 |  |  | PWA BOM |
| 8 | 3406ARP00-317-G | 1 | 0 | CONN,Header,Power,2X8,V/T,Whi,4.2mm,G,DIP-16 | MOLEX INCORPORATED | 46015-1602 | G | (-)J100 | PWA BOM |
| OOOOOOOOOOOOOOOOOOOOOOOOOOOOOOOOOOOOOOOOOOOOOOOOOOOOOOOOOOOOOOOOOOOOOOOOOOOOOOOOOOOOOOOOOO | OOOOOOOOOOOOOOOOOOOOOOOOOOOOOOOOOOOOOOOOOOOOOOOOOOOOOOOOOOOOOOOOOOOOOOOOOOOOOOOOOOOOOOOOOO | OOOOOOOOOOOOOOOOOOOOOOOOOOOOOOOOOOOOOOOOOOOOOOOOOOOOOOOOOOOOOOOOOOOOOOOOOOOOOOOOOOOOOOOOOO | OOOOOOOOOOOOOOOOOOOOOOOOOOOOOOOOOOOOOOOOOOOOOOOOOOOOOOOOOOOOOOOOOOOOOOOOOOOOOOOOOOOOOOOOOO | OOOOOOOOOOOOOOOOOOOOOOOOOOOOOOOOOOOOOOOOOOOOOOOOOOOOOOOOOOOOOOOOOOOOOOOOOOOOOOOOOOOOOOOOOO | OOOOOOOOOOOOOOOOOOOOOOOOOOOOOOOOOOOOOOOOOOOOOOOOOOOOOOOOOOOOOOOOOOOOOOOOOOOOOOOOOOOOOOOOOO | OOOOOOOOOOOOOOOOOOOOOOOOOOOOOOOOOOOOOOOOOOOOOOOOOOOOOOOOOOOOOOOOOOOOOOOOOOOOOOOOOOOOOOOOOO | OOOOOOOOOOOOOOOOOOOOOOOOOOOOOOOOOOOOOOOOOOOOOOOOOOOOOOOOOOOOOOOOOOOOOOOOOOOOOOOOOOOOOOOOOO | OOOOOOOOOOOOOOOOOOOOOOOOOOOOOOOOOOOOOOOOOOOOOOOOOOOOOOOOOOOOOOOOOOOOOOOOOOOOOOOOOOOOOOOOOO | OOOOOOOOOOOOOOOOOOOOOOOOOOOOOOOOOOOOOOOOOOOOOOOOOOOOOOOOOOOOOOOOOOOOOOOOOOOOOOOOOOOOOOOOOO |
| TLA Parts Change |  |  |  |  |  |  |  |  |  |
| Item | Foxconn P/N | Qty | Part Description | Manufacturer Full Name | Manufacturer P/N | RoHS | Location | Remark | BOM |
| BOM Change List Date:Fri Aug 18 18:37:30 GMT+08:00 2017 |  |  |  |  |  |  |  |  |  |
| New BOM file : C:\<user>\BARRELEYE-G2-MB-PVT-HW-EBOM-X04-20170818-2.xls |  |  |  |  |  |  |  |  |  |
| Old BOM file : C:\<user>\BARRELEYE-G2-MB-PVT-HW-EBOM-20170811.xls |  |  |  |  |  |  |  |  |  |
| ##### Add Parts |  |  |  |  |  |  |  |  |  |
| Item | Location | Qty | Foxconn P/N | Part Description | Manufacturer Full Name | Manufacturer P/N | RoHS | Sheet |  |
| 1 | J36,J41,J43,J48 | 4 | 34068LN00-317-G | CONN,Header,Pin Header,1X3,V/T,2.54mm,30u,G,SMD-3 | MOLEX INCORPORATED | 87898-0315 |  | PWA BOM |  |
| 2 | J35,J37,J39,J42,J45 | 5 | 3406AQH00-317-G | CONN,Header,Pin Header,1X6,V/T,Bla,2.54mm,G,SMD-6 | MOLEX INCORPORATED | 87898-0656 |  | PWA BOM |  |
| ##### Remove Parts |  |  |  |  |  |  |  |  |  |
| Item | Location | Qty | Foxconn P/N | Part Description | Manufacturer Full Name | Manufacturer P/N | RoHS | Sheet |  |
| 1 | PBMD4,PBFD4,PBED4,PAMD4,PAFD4,PAED4,PBAD5,PAAD5 | 8 | 52030DA00-237-G | DIODE,Schottky,BAT46W-7-F,100V,150mA,G,SOD123-2,SMD | DIODES INEORPORATION | BAT46W-7-F |  | PWA BOM |  |
| ##### Change Parts |  |  |  |  |  |  |  |  |  |
| Item | Location | Qty | Foxconn P/N | Part Description | Manufacturer Full Name | Manufacturer P/N | RoHS | Sheet | Remark |
| 1 | PSUCE1,PBACE1,PAACE1,PSUCE2,PBACE2,PAACE2 | 6 | 62111U700-024-G | ECAP,68uF,+/-20%,100V,105C,320mOhm,G,SMD12.5*13.5 | PANASONIC INDUSTRIAL CO.,LTD. | EEEFK2A680AQ |  | PWA BOM | In New BOM |
|  | PSUCE1,PBACE1,PAACE1,PSUCE2,PBACE2,PAACE2 | 6 | 62111CS00-024-G | ECAP,68uF,+/-20%,100V,105C,G,SMD12.5*13.5,ESR<=320mOhm | PANASONIC INDUSTRIAL CO.,LTD. | EEVFK2A680Q |  | PWA BOM | In Old BOM |
| 2 | PBMD1,PBFD1,PBED1,PBAD1,PAMD1,PAFD1,PAED1,PAAD1 | 8 | 520103B00-185-G | Diode,Rectifier&Switching,MMBD1205,100V,200mA,G,SOT-23-3,SMD | FAIRCHILD SEMICONDUCTOR CORP | MMBD1205 | N | PWA BOM | In New BOM |
|  | PBMD1,PBFD1,PBED1,PBAD1,PAMD1,PAFD1,PAED1,PAAD1 | 8 | 52030DA00-237-G | DIODE,Schottky,BAT46W-7-F,100V,150mA,G,SOD123-2,SMD | DIODES INEORPORATION | BAT46W-7-F |  | PWA BOM | In Old BOM |
| 3 | PCIE1,PCIE5 | 2 | 10128241-112X0LF | CONN,PCIE-8X,V/T,Bla,1mm,30u,G,SMD-98 | FCI CONNECTORS HONGKONG LTD. | 10128241-112X0LF |  | PWA BOM | In New BOM |
|  | PCIE1,PCIE5 | 2 | 10128241-112Y0LF | CONN,PCIE-8X,V/T,Bla,1mm,30u,G,SMD-98 | FCI CONNECTORS HONGKONG LTD. | 10128241-112Y0LF |  | PWA BOM | In Old BOM |
| 4 | PCIE2,PCIE3,PCIE4 | 3 | 10128241-113X0LF | CONN,PCIE-16X,V/T,Bla,1mm,30u,G,SMD-164 | FCI CONNECTORS HONGKONG LTD. | 10128241-113X0LF |  | PWA BOM | In New BOM |
|  | PCIE2,PCIE3,PCIE4 | 3 | 10128241-113Y0LF | CONN,PCIE-16X,V/T,Bla,1mm,30u,G,SMD-164 | FCI CONNECTORS HONGKONG LTD. | 10128241-113Y0LF |  | PWA BOM | In Old BOM |
| 5 | U1,U10 | 2 | PE38993-51BC1-1H | POWER9 CPU Socket for LGA3899-HYBRID | FOXCONN TECHNOLOGY CO.,LTD. | PE38993-51BC1-1H |  | PWA BOM | In New BOM |
|  | U1,U10 | 2 | 340108S00-600-G | POWER9 CPU Socket for LGA3899-HYBRID | FOXCONN TECHNOLOGY CO.,LTD. | PE38993-51BC0-1H |  | PWA BOM | In Old BOM |
| ##### Change Revision |  |  |  |  |  |  |  |  |  |
| Sheet | REV OF BOM | CUSTOMER | CUSTOMER P/N | PWA PN | PWA DESCRIPTION | PWA REV | DATE | Remark |  |
| OOOOOOOOOOOOOOOOOOOOOOOOOOOOOOOOOOOOOOOOOOOOOOOOOOOOOOOOOOOOOOOOOOOOOOOOOOOOOOOOOOOOOOOOOO | OOOOOOOOOOOOOOOOOOOOOOOOOOOOOOOOOOOOOOOOOOOOOOOOOOOOOOOOOOOOOOOOOOOOOOOOOOOOOOOOOOOOOOOOOO | OOOOOOOOOOOOOOOOOOOOOOOOOOOOOOOOOOOOOOOOOOOOOOOOOOOOOOOOOOOOOOOOOOOOOOOOOOOOOOOOOOOOOOOOOO | OOOOOOOOOOOOOOOOOOOOOOOOOOOOOOOOOOOOOOOOOOOOOOOOOOOOOOOOOOOOOOOOOOOOOOOOOOOOOOOOOOOOOOOOOO | OOOOOOOOOOOOOOOOOOOOOOOOOOOOOOOOOOOOOOOOOOOOOOOOOOOOOOOOOOOOOOOOOOOOOOOOOOOOOOOOOOOOOOOOOO | OOOOOOOOOOOOOOOOOOOOOOOOOOOOOOOOOOOOOOOOOOOOOOOOOOOOOOOOOOOOOOOOOOOOOOOOOOOOOOOOOOOOOOOOOO | OOOOOOOOOOOOOOOOOOOOOOOOOOOOOOOOOOOOOOOOOOOOOOOOOOOOOOOOOOOOOOOOOOOOOOOOOOOOOOOOOOOOOOOOOO | OOOOOOOOOOOOOOOOOOOOOOOOOOOOOOOOOOOOOOOOOOOOOOOOOOOOOOOOOOOOOOOOOOOOOOOOOOOOOOOOOOOOOOOOOO | OOOOOOOOOOOOOOOOOOOOOOOOOOOOOOOOOOOOOOOOOOOOOOOOOOOOOOOOOOOOOOOOOOOOOOOOOOOOOOOOOOOOOOOOOO | OOOOOOOOOOOOOOOOOOOOOOOOOOOOOOOOOOOOOOOOOOOOOOOOOOOOOOOOOOOOOOOOOOOOOOOOOOOOOOOOOOOOOOOOOO |
| Second Source Change |  |  |  |  |  |  |  |  |  |
| Item | Location | Change Type | Foxconn P/N | Part Description | Manufacturer Full Name | Manufacturer P/N | RoHS | Sheet |  |
| OOOOOOOOOOOOOOOOOOOOOOOOOOOOOOOOOOOOOOOOOOOOOOOOOOOOOOOOOOOOOOOOOOOOOOOOOOOOOOOOOOOOOOOOOO | OOOOOOOOOOOOOOOOOOOOOOOOOOOOOOOOOOOOOOOOOOOOOOOOOOOOOOOOOOOOOOOOOOOOOOOOOOOOOOOOOOOOOOOOOO | OOOOOOOOOOOOOOOOOOOOOOOOOOOOOOOOOOOOOOOOOOOOOOOOOOOOOOOOOOOOOOOOOOOOOOOOOOOOOOOOOOOOOOOOOO | OOOOOOOOOOOOOOOOOOOOOOOOOOOOOOOOOOOOOOOOOOOOOOOOOOOOOOOOOOOOOOOOOOOOOOOOOOOOOOOOOOOOOOOOOO | OOOOOOOOOOOOOOOOOOOOOOOOOOOOOOOOOOOOOOOOOOOOOOOOOOOOOOOOOOOOOOOOOOOOOOOOOOOOOOOOOOOOOOOOOO | OOOOOOOOOOOOOOOOOOOOOOOOOOOOOOOOOOOOOOOOOOOOOOOOOOOOOOOOOOOOOOOOOOOOOOOOOOOOOOOOOOOOOOOOOO | OOOOOOOOOOOOOOOOOOOOOOOOOOOOOOOOOOOOOOOOOOOOOOOOOOOOOOOOOOOOOOOOOOOOOOOOOOOOOOOOOOOOOOOOOO | OOOOOOOOOOOOOOOOOOOOOOOOOOOOOOOOOOOOOOOOOOOOOOOOOOOOOOOOOOOOOOOOOOOOOOOOOOOOOOOOOOOOOOOOOO | OOOOOOOOOOOOOOOOOOOOOOOOOOOOOOOOOOOOOOOOOOOOOOOOOOOOOOOOOOOOOOOOOOOOOOOOOOOOOOOOOOOOOOOOOO | OOOOOOOOOOOOOOOOOOOOOOOOOOOOOOOOOOOOOOOOOOOOOOOOOOOOOOOOOOOOOOOOOOOOOOOOOOOOOOOOOOOOOOOOOO |
| Master Materials Change |  |  |  |  |  |  |  |  |  |
| Item | Foxconn P/N | Orig._Usage | New_Usage | Part Description | Manufacturer Full Name | Manufacturer P/N | RoHS | Location | Sheet |
| 1 | 62111U700-024-G | 0 | 6 | ECAP,68uF,+/-20%,100V,105C,320mOhm,G,SMD12.5*13.5 | PANASONIC INDUSTRIAL CO.,LTD. | EEEFK2A680AQ |  | (+)PSUCE1,PBACE1,PAACE1,PSUCE2,PBACE2,PAACE2 | PWA BOM |
| 2 | 520103B00-185-G | 0 | 8 | Diode,Rectifier&Switching,MMBD1205,100V,200mA,G,SOT-23-3,SMD | FAIRCHILD SEMICONDUCTOR CORP | MMBD1205 | N | (+)PBMD1,PBFD1,PBED1,PBAD1,PAMD1,PAFD1,PAED1,PAAD1 | PWA BOM |
| 3 | 10128241-112X0LF | 0 | 2 | CONN,PCIE-8X,V/T,Bla,1mm,30u,G,SMD-98 | FCI CONNECTORS HONGKONG LTD. | 10128241-112X0LF |  | (+)PCIE1,PCIE5 | PWA BOM |
| 4 | 10128241-113X0LF | 0 | 3 | CONN,PCIE-16X,V/T,Bla,1mm,30u,G,SMD-164 | FCI CONNECTORS HONGKONG LTD. | 10128241-113X0LF |  | (+)PCIE2,PCIE3,PCIE4 | PWA BOM |
| 5 | 34068LN00-317-G | 6 | 10 | CONN,Header,Pin Header,1X3,V/T,2.54mm,30u,G,SMD-3 | MOLEX INCORPORATED | 87898-0315 |  | (+)J36,J41,J43,J48 | PWA BOM |
| 6 | 3406AQH00-317-G | 0 | 5 | CONN,Header,Pin Header,1X6,V/T,Bla,2.54mm,G,SMD-6 | MOLEX INCORPORATED | 87898-0656 |  | (+)J35,J37,J39,J42,J45 | PWA BOM |
| 7 | PE38993-51BC1-1H | 0 | 2 | POWER9 CPU Socket for LGA3899-HYBRID | FOXCONN TECHNOLOGY CO.,LTD. | PE38993-51BC1-1H |  | (+)U1,U10 | PWA BOM |
| 8 | 62111CS00-024-G | 6 | 0 | ECAP,68uF,+/-20%,100V,105C,G,SMD12.5*13.5,ESR<=320mOhm | PANASONIC INDUSTRIAL CO.,LTD. | EEVFK2A680Q |  | (-)PSUCE1,PBACE1,PAACE1,PSUCE2,PBACE2,PAACE2 | PWA BOM |
| 9 | 52030DA00-237-G | 16 | 0 | DIODE,Schottky,BAT46W-7-F,100V,150mA,G,SOD123-2,SMD | DIODES INEORPORATION | BAT46W-7-F |  | (-)PBMD1,PBFD1,PBED1,PBAD1,PAMD1,PAFD1,PAED1,PAAD1,PBMD4,PBFD4,PBED4,PAMD4,PAFD4,PAED4,PBAD5,PAAD5 | PWA BOM |
| 10 | 10128241-112Y0LF | 2 | 0 | CONN,PCIE-8X,V/T,Bla,1mm,30u,G,SMD-98 | FCI CONNECTORS HONGKONG LTD. | 10128241-112Y0LF |  | (-)PCIE1,PCIE5 | PWA BOM |
| 11 | 10128241-113Y0LF | 3 | 0 | CONN,PCIE-16X,V/T,Bla,1mm,30u,G,SMD-164 | FCI CONNECTORS HONGKONG LTD. | 10128241-113Y0LF |  | (-)PCIE2,PCIE3,PCIE4 | PWA BOM |
| 12 | 340108S00-600-G | 2 | 0 | POWER9 CPU Socket for LGA3899-HYBRID | FOXCONN TECHNOLOGY CO.,LTD. | PE38993-51BC0-1H |  | (-)U1,U10 | PWA BOM |
| OOOOOOOOOOOOOOOOOOOOOOOOOOOOOOOOOOOOOOOOOOOOOOOOOOOOOOOOOOOOOOOOOOOOOOOOOOOOOOOOOOOOOOOOOO | OOOOOOOOOOOOOOOOOOOOOOOOOOOOOOOOOOOOOOOOOOOOOOOOOOOOOOOOOOOOOOOOOOOOOOOOOOOOOOOOOOOOOOOOOO | OOOOOOOOOOOOOOOOOOOOOOOOOOOOOOOOOOOOOOOOOOOOOOOOOOOOOOOOOOOOOOOOOOOOOOOOOOOOOOOOOOOOOOOOOO | OOOOOOOOOOOOOOOOOOOOOOOOOOOOOOOOOOOOOOOOOOOOOOOOOOOOOOOOOOOOOOOOOOOOOOOOOOOOOOOOOOOOOOOOOO | OOOOOOOOOOOOOOOOOOOOOOOOOOOOOOOOOOOOOOOOOOOOOOOOOOOOOOOOOOOOOOOOOOOOOOOOOOOOOOOOOOOOOOOOOO | OOOOOOOOOOOOOOOOOOOOOOOOOOOOOOOOOOOOOOOOOOOOOOOOOOOOOOOOOOOOOOOOOOOOOOOOOOOOOOOOOOOOOOOOOO | OOOOOOOOOOOOOOOOOOOOOOOOOOOOOOOOOOOOOOOOOOOOOOOOOOOOOOOOOOOOOOOOOOOOOOOOOOOOOOOOOOOOOOOOOO | OOOOOOOOOOOOOOOOOOOOOOOOOOOOOOOOOOOOOOOOOOOOOOOOOOOOOOOOOOOOOOOOOOOOOOOOOOOOOOOOOOOOOOOOOO | OOOOOOOOOOOOOOOOOOOOOOOOOOOOOOOOOOOOOOOOOOOOOOOOOOOOOOOOOOOOOOOOOOOOOOOOOOOOOOOOOOOOOOOOOO |  |
| TLA Parts Change |  |  |  |  |  |  |  |  |  |
| Item | Foxconn P/N | Qty | Part Description | Manufacturer Full Name | Manufacturer P/N | RoHS | Location | Remark |  |
| BOM Change List Date:Wed Aug 23 16:35:15 GMT+08:00 2017 |  |  |  |  |  |  |  |  |  |
| New BOM file : E:\barreleye g2\0822\\BG2 FOXBIS\BG2 MB 20170821.xls |  |  |  |  |  |  |  |  |  |
| Old BOM file : E:\barreleye g2\0822\\BG2 FOXBIS\BG2 MB 20170810.xls |  |  |  |  |  |  |  |  |  |
| ##### Add Parts |  |  |  |  |  |  |  |  |  |
| Item | Location | Qty | Foxconn P/N | Part Description | Manufacturer Full Name | Manufacturer P/N | RoHS | Sheet |  |
| 1 | ED1 | 1 | 52180BC00-223-G | DIODE,Array-TVS,ESD8004MUTAG,G,UDFN-10,SMD | ON SEMICONDUCTOR CORP | ESD8004MUTAG | G | PWA BOM |  |
| 2 | R910,R917 | 2 | 61010G500-017-G | RES,10KOhm,+/-1%,1/16W,G,SMD0402 | KOA SPEER ELECTRONICS, INC. | RK73H1ETTP1002F | G | PWA BOM |  |
|  |  |  | 61010G500-012-G | RES,10KOhm,+/-1%,1/16W,G,SMD0402 | WALSIN TECHNOLOGY CORPORATION | WR04X1002FTL | G | PWA BOM |  |
|  |  |  | 61010G500-011-G | RES,10KOhm,+/-1%,1/16W,G,SMD0402 | YAGEO CORPORATION COMPONENT | RC0402FR-0710KL | G | PWA BOM |  |
|  |  |  | 61010G500-044-G | RES,10KOhm,+/-1%,1/16W,G,SMD0402 | TA-I TECHNOLOGY CO., LTD | RM04FTN1002 | G | PWA BOM |  |
|  |  |  | 61010G500-029-G | RES,10KOhm,+/-1%,1/16W,G,SMD0402 | VISHAY ENTER TECHNO LOGY.INC | CRCW040210K0FKED | G | PWA BOM |  |
|  |  |  | 61010G500-024-G | RES,10KOhm,+/-1%,1/16W,G,SMD0402 | PANASONIC INDUSTRIAL CO.,LTD. | ERJ2RKF1002X | G | PWA BOM |  |
| 3 | J36,J41,J43,J48 | 4 | 34068LN00-317-G | CONN,Header,Pin Header,1X3,V/T,2.54mm,30u,G,SMD-3 | MOLEX INCORPORATED | 87898-0315 | G | PWA BOM |  |
|  |  |  | 34068HT00-245-G | CONN,Header,Pin Header,1X3,V/T,Bla,2.54mm,30u,SMD-3 | AMPHENOL SHANGHAI CORP. | G800MU305010EU | G | PWA BOM |  |
|  |  |  | 34068GU00-309-G | CONN,Header,Pin Header,1X3,V/T,Bla,2.54mm,30u,SMD-3 | SAMTEC INC. | TSM-103-01-S-SV-P-TR | G | PWA BOM |  |
| 4 | J35,J37,J39,J42,J45 | 5 | 3406AQH00-317-G | CONN,Header,Pin Header,1X6,V/T,Bla,2.54mm,G,SMD-6 | MOLEX INCORPORATED | 87898-0656 | G | PWA BOM |  |
| ##### Remove Parts |  |  |  |  |  |  |  |  |  |
| Item | Location | Qty | Foxconn P/N | Part Description | Manufacturer Full Name | Manufacturer P/N | RoHS | Sheet |  |
| 1 | PBMD4,PBFD4,PBED4,PAMD4,PAFD4,PAED4,PBAD5,PAAD5 | 8 | 52030DA00-237-G | DIODE,Schottky,BAT46W-7-F,100V,150mA,G,SOD123-2,SMD | DIODES INEORPORATION | BAT46W-7-F | G | PWA BOM |  |
| 2 | R908,R920 | 2 | 61010G500-017-G | RES,10KOhm,+/-1%,1/16W,G,SMD0402 | KOA SPEER ELECTRONICS, INC. | RK73H1ETTP1002F | G | PWA BOM |  |
|  |  |  | 61010G500-012-G | RES,10KOhm,+/-1%,1/16W,G,SMD0402 | WALSIN TECHNOLOGY CORPORATION | WR04X1002FTL | G | PWA BOM |  |
|  |  |  | 61010G500-011-G | RES,10KOhm,+/-1%,1/16W,G,SMD0402 | YAGEO CORPORATION COMPONENT | RC0402FR-0710KL | G | PWA BOM |  |
|  |  |  | 61010G500-044-G | RES,10KOhm,+/-1%,1/16W,G,SMD0402 | TA-I TECHNOLOGY CO., LTD | RM04FTN1002 | G | PWA BOM |  |
|  |  |  | 61010G500-029-G | RES,10KOhm,+/-1%,1/16W,G,SMD0402 | VISHAY ENTER TECHNO LOGY.INC | CRCW040210K0FKED | G | PWA BOM |  |
|  |  |  | 61010G500-024-G | RES,10KOhm,+/-1%,1/16W,G,SMD0402 | PANASONIC INDUSTRIAL CO.,LTD. | ERJ2RKF1002X | G | PWA BOM |  |
| ##### Change Parts |  |  |  |  |  |  |  |  |  |
| Item | Location | Qty | Foxconn P/N | Part Description | Manufacturer Full Name | Manufacturer P/N | RoHS | Sheet | Remark |
| 1 | C1476,C1477 | 2 | 62010MU00-015-G | CAP,20pF,+/-5%,NPO(C0G),50V,G,SMD0402 | MURATA ELEC. NORTH AMERICA | GRM1555C1H200J | G | PWA BOM | In New BOM |
|  |  |  | 62012UJ00-012-G | CAP,20pF,+/-5%,NPO(C0G),50V,G,SMD0402 | WALSIN TECHNOLOGY CORPORATION | 0402N200J500CT | G | PWA BOM | In New BOM |
|  |  |  | 62010MU00-026-G | CAP,20pF,+/-5%,NPO(C0G),50V,G,SMD0402 | SAMSUNG SEMICONDUCTOR | CL05C200JB5NNNC | G | PWA BOM | In New BOM |
|  | C1476,C1477 | 2 | 62010MU00-015-G | CAP,20pF,+/-5%,NPO(C0G),50V,G,SMD0402 | MURATA ELEC. NORTH AMERICA | GRM1555C1H200J | G | PWA BOM | In Old BOM |
|  |  |  | 62012UJ00-012-G | CAP,20pF,+/-5%,NPO(C0G),50V,G,SMD0402 | WALSIN | 0402N200J500CT | G | PWA BOM | In Old BOM |
|  |  |  | 62010MU00-026-G | CAP,20pF,+/-5%,NPO(C0G),50V,G,SMD0402 | SAMSUNG | CL05C200JB5NNNC | G | PWA BOM | In Old BOM |
| 2 | L34,L36 | 2 | 72010A400-023-G | FB,80Ohm@100MHz,+/-25%,4A,10mOhm,G,SMD1206 | TAIYO ELECTRIC IND.CO.LTD | FBMJ3216HS800-T | G | PWA BOM | In New BOM |
|  |  |  | 72010A400-025-G | FB,Multilayer,10mOhm,80Ohm@100MHz,+/-25%,4A,,SMD1206,G | KEMET ELECTRONICS CORPORATION | Z1206C800APWST | G | PWA BOM | In New BOM |
|  | L34,L36 | 2 | 72010A400-023-G | FB,80Ohm@100MHz,+/-25%,4A,10mOhm,G,SMD1206 | TAIYO ELECTRIC IND.CO.LTD | FBMJ3216HS800-T | G | PWA BOM | In Old BOM |
|  |  |  | Z1206C800APWST | FB,80Ohm@100MHz,+/-25%,4A,10mOhm,G,SMD1206 | KEMET ELECTRONICS CORPORATION | Z1206C800APWST | G | PWA BOM | In Old BOM |
| 3 | PBMC6,PBFC6,PBEC6,PBAC6,PAMC6,PAFC6,PAEC6,PAAC6 | 8 | 62011DQ00-015-G | CAP,27nF,+/-10%,X7R,25V,G,SMD0402 | MURATA ELEC. NORTH AMERICA | GRM155R71E273KA88D | G | PWA BOM | In New BOM |
|  |  |  | 620136P00-012-G | CAP,MLCC,27nF,+/-10%,X7R,25V,SMD0402,G | WALSIN TECHNOLOGY CORPORATION | 0402B273K250CT | G | PWA BOM | In New BOM |
|  |  |  | 62011DQ00-011-G | CAP,MLCC,27nF,+/-10%,X7R,25V,SMD0402,G | YAGEO CORPORATION COMPONENT | CC0402KRX7R8BB273 | G | PWA BOM | In New BOM |
|  | PBMC6,PBFC6,PBEC6,PBAC6,PAMC6,PAFC6,PAEC6,PAAC6 | 8 | 62011DQ00-015-G | CAP,27nF,+/-10%,X7R,25V,G,SMD0402 | MURATA ELEC. NORTH AMERICA | GRM155R71E273KA88D | G | PWA BOM | In Old BOM |
|  |  |  | 620136P00-012-G | CAP,MLCC,27nF,+/-10%,X7R,25V,SMD0402,G | WALSIN TECHNOLOGY CORPORATION | 0402B273K250CT | G | PWA BOM | In Old BOM |
|  |  |  | 62011DQ00-011-G | CAP,MLCC,27nF,+/-10%,X7R,25V,SMD0402,G | YAGEO CORPORATION COMPONENT | CC0402KRX7R8BB273 |  | PWA BOM | In Old BOM |
| 4 | PBMQ10,PBAQ10,PAMQ10,PAAQ10,PBFQ11,PBEQ11,PAFQ11,PAEQ11 | 8 | 51032DL00-237-G | MOS N,DMT10H014LSS-13,100V,8.9A,15m@10V,G,SO-8,SMD | DIODES INCORPORATION | DMT10H014LSS-13 | G | PWA BOM | In New BOM |
|  |  |  | 51032FL00-029-G | MOS N,Si4190ADY-T1-GE3,100V,18.4A,8.8m@10V,G,SO-8,SMD | VISHAY ENTER TECHNO LOGY.INC | Si4190ADY-T1-GE3 | G | PWA BOM | In New BOM |
|  | PBMQ10,PBAQ10,PAMQ10,PAAQ10,PBFQ11,PBEQ11,PAFQ11,PAEQ11 | 8 | 51032DL00-237-G | MOS N,DMT10H014LSS-13,100V,8.9A,15m@10V,G,SO-8,SMD | DIODES INCORPORATION | DMT10H014LSS-13 | G | PWA BOM | In Old BOM |
|  |  |  | Si4190ADY-T1-GE3 | MOS N,Si4190ADY-T1-GE3,100V,18.4A,8.8m@10V,G,SO-8,SMD | VISHAY ENTER TECHNO LOGY.INC | Si4190ADY-T1-GE3 | G | PWA BOM | In Old BOM |
| 5 | PBNR11,PANR11 | 2 | 610114B00-017-G | RES,2.49KOhm,+/-1%,1/16W,G,SMD0402 | KOA SPEER ELECTRONICS, INC. | RK73H1ETTP2491F | G | PWA BOM | In New BOM |
|  |  |  | 610114B00-012-G | RES,2.49KOhm,+/-1%,1/16W,G,SMD0402 | WALSIN TECHNOLOGY CORPORATION | WR04X2491FTL | G | PWA BOM | In New BOM |
|  |  |  | 610114B00-011-G | RES,2.49KOhm,+/-1%,1/16W,G,SMD0402 | YAGEO CORPORATION COMPONENT | RC0402FR-072K49L | G | PWA BOM | In New BOM |
|  |  |  | 610114B00-024-G | RES,2.49KOhm,+/-1%,1/16W,G,SMD0402 | PANASONIC INDUSTRIAL CO.,LTD. | ERJ2RKF2491X | G | PWA BOM | In New BOM |
|  |  |  | 610114B00-029-G | RES,2.49KOhm,+/-1%,1/16W,G,SMD0402 | VISHAY ENTER TECHNO LOGY.INC | CRCW04022K49FKED | G | PWA BOM | In New BOM |
|  | PBNR11,PANR11 | 2 | 610114B00-017-G | RES,2.49KOhm,+/-1%,1/16W,G,SMD0402 | KOA SPEER ELECTRONICS, INC. | RK73H1ETTP2491F | G | PWA BOM | In Old BOM |
|  |  |  | 610114B00-012-G | RES,2.49KOhm,+/-1%,1/16W,G,SMD0402 | WALSIN TECHNOLOGY CORPORATION | WR04X2491FTL | G | PWA BOM | In Old BOM |
|  |  |  | 610114B00-011-G | RES,2.49KOhm,+/-1%,1/16W,G,SMD0402 | YAGEO CORPORATION COMPONENT | RC0402FR-072K49L | G | PWA BOM | In Old BOM |
|  |  |  | 610114B00-024-G | RES,2.49KOhm,+/-1%,1/16W,G,SMD0402 | PANASONIC | ERJ2RKF2491X | G | PWA BOM | In Old BOM |
|  |  |  | 610114B00-029-G | RES,2.49KOhm,+/-1%,1/16W,G,SMD0402 | VISHAY ENTER TECHNO LOGY.INC | CRCW04022K49FKED | G | PWA BOM | In Old BOM |
| 6 | PBNR14,PANR14 | 2 | 61011CJ00-017-G | RES,365 Ohm,+/-1%,1/16W,G,SMD0402 | KOA SPEER ELECTRONICS, INC. | RK73H1ETTP3650F | G | PWA BOM | In New BOM |
|  |  |  | 61011CJ00-012-G | RES,365 Ohm,+/-1%,1/16W,G,SMD0402 | WALSIN TECHNOLOGY CORPORATION | WR04X3650FTL | G | PWA BOM | In New BOM |
|  |  |  | 61011CJ00-011-G | RES,365 Ohm,+/-1%,1/16W,G,SMD0402 | YAGEO CORPORATION COMPONENT | RC0402FR-07365RL | G | PWA BOM | In New BOM |
|  |  |  | 61011CJ00-024-G | RES,365 Ohm,+/-1%,1/16W,G,SMD0402 | PANASONIC INDUSTRIAL CO.,LTD. | ERJ2RKF3650X | G | PWA BOM | In New BOM |
|  |  |  | 61011CJ00-029-G | RES,365 Ohm,+/-1%,1/16W,G,SMD0402 | VISHAY ENTER TECHNO LOGY.INC | CRCW0402365RFKEDC | G | PWA BOM | In New BOM |
|  | PBNR14,PANR14 | 2 | 61011CJ00-017-G | RES,365 Ohm,+/-1%,1/16W,G,SMD0402 | KOA SPEER ELECTRONICS, INC. | RK73H1ETTP3650F | G | PWA BOM | In Old BOM |
|  |  |  | 61011CJ00-012-G | RES,365 Ohm,+/-1%,1/16W,G,SMD0402 | WALSIN TECHNOLOGY CORPORATION | WR04X3650FTL | G | PWA BOM | In Old BOM |
|  |  |  | 61011CJ00-011-G | RES,365 Ohm,+/-1%,1/16W,G,SMD0402 | YAGEO CORPORATION COMPONENT | RC0402FR-07365RL | G | PWA BOM | In Old BOM |
|  |  |  | 61011CJ00-024-G | RES,365 Ohm,+/-1%,1/16W,G,SMD0402 | PANASONIC | ERJ2RKF3650X | G | PWA BOM | In Old BOM |
|  |  |  | 61011CJ00-029-G | RES,365 Ohm,+/-1%,1/16W,G,SMD0402 | VISHAY ENTER TECHNO LOGY.INC | CRCW0402365RFKEDC | G | PWA BOM | In Old BOM |
| 7 | PSTC4,PSLC4,PSFC4,PSEC4,PSDC4,PQPC4,PFRC4,PEEC4,PEDC4,PSPC3003,PIPC3003,PFPC3003,PEPC3003,PSRC3010 | 14 | 62012T300-015-G | CAP,1uF,+/-10%,X7S,25V,G,SMD0402 | MURATA ELEC. NORTH AMERICA | GRM155C71E105KE11D | G | PWA BOM | In New BOM |
|  |  |  | 620138700-026-G | CAP,1uF,+/-10%,X6S,25V,G,SMD0402 | SAMSUNG SEMICONDUCTOR | CL05X105KA5NQNC | G | PWA BOM | In New BOM |
|  |  |  | 620138700-015-G | CAP,1uF,+/-10%,X6S,25V,G,SMD0402 | MURATA | GRM155C81E105KE11D | G | PWA BOM | In New BOM |
|  | PSTC4,PSLC4,PSFC4,PSEC4,PSDC4,PQPC4,PFRC4,PEEC4,PEDC4,PSPC3003,PIPC3003,PFPC3003,PEPC3003,PSRC3010 | 14 | 62012T300-015-G | CAP,1uF,+/-10%,X7S,25V,G,SMD0402 | MURATA ELEC. NORTH AMERICA | GRM155C71E105KE11D | G | PWA BOM | In Old BOM |
|  |  |  | 620138700-026-G | CAP,1uF,+/-10%,X6S,25V,G,SMD0402 | SAMSUNG | CL05X105KA5NQNC | G | PWA BOM | In Old BOM |
|  |  |  | GRM155C81E105KE11D | CAP,1uF,+/-10%,X6S,25V,G,SMD0402 | MURATA | GRM155C81E105KE11D | G | PWA BOM | In Old BOM |
| 8 | PSLR17,PSFR17,PSER17,PSDR17,PQPR17,PFRR17,PEER17,PEDR17,PEDR19 | 9 | 611004M00-017-G | RES,16.5KOhm,+/-0.1%,1/16W,G,SMD0402 | KOA SPEER ELECTRONICS, INC. | RN731ETTP1652B25 | G | PWA BOM | In New BOM |
|  |  |  | 611004M00-024-G | RES,16.5KOhm,+/-0.1%,1/16W,G,SMD0402 | PANASONIC INDUSTRIAL CO.,LTD. | ERA2AEB1652X | G | PWA BOM | In New BOM |
|  | PSLR17,PSFR17,PSER17,PSDR17,PQPR17,PFRR17,PEER17,PEDR17,PEDR19 | 9 | 611004M00-017-G | RES,16.5KOhm,+/-0.1%,1/16W,G,SMD0402 | KOA SPEER ELECTRONICS, INC. | RN731ETTP1652B25 | G | PWA BOM | In Old BOM |
|  |  |  | 611004M00-024-G | RES,16.5KOhm,+/-0.1%,1/16W,G,SMD0402 | PANASONIC | ERA2AEB1652X | G | PWA BOM | In Old BOM |
| 9 | PSRC3,PERC3 | 2 | 62011M802-015-G | CAP,62pF,+/-5%,NPO(C0G),50V,G,SMD0402 | MURATA ELEC. NORTH AMERICA | GRM1555C1H620JA01D | G | PWA BOM | In New BOM |
|  |  |  | 62011M800-011-G | CAP,62pF,+/-5%,NPO(C0G),50V,G,SMD0402 | YAGEO CORPORATION COMPONENT | CC0402JRNPO9BN620 | G | PWA BOM | In New BOM |
|  |  |  | 62011M800-026-G | CAP,MLCC,62pF,+/-5%,NPO(C0G),50V,SMD0402,G | SAMSUNG SEMICONDUCTOR | CL05C620JB5NNNC | G | PWA BOM | In New BOM |
|  | PSRC3,PERC3 | 2 | 62011M802-015-G | CAP,62pF,+/-5%,NPO(C0G),50V,G,SMD0402 | MURATA ELEC. NORTH AMERICA | GRM1555C1H620JA01D | G | PWA BOM | In Old BOM |
|  |  |  | 62011M800-011-G | CAP,62pF,+/-5%,NPO(C0G),50V,G,SMD0402 | YAGEO CORPORATION COMPONENT | CC0402JRNPO9BN620 |  | PWA BOM | In Old BOM |
|  |  |  | 62011M800-026-G | CAP,MLCC,62pF,+/-5%,NPO(C0G),50V,SMD0402,G | SAMSUNG SEMICONDUCTOR | CL05C620JB5NNNC |  | PWA BOM | In Old BOM |
| 10 | PHAQ1,PHAQ2,PHAQ3 | 3 | 51031VY00-031-G | MOS N,PSMN4R8-100BSE,100V,120A,4.8m@10V,G,SOT404-3,SMD | NXP SEMICONDUCTORS | PSMN4R8-100BSE | G | PWA BOM | In New BOM |
|  |  |  | 51032HE00-185-G | MOS N,FDB047N10,100V,120A,3.9m@10V,G,TO263-3,SMD | FAIRCHILD SEMICONDUCTOR CORP | FDB047N10 | G | PWA BOM | In New BOM |
|  |  |  | 51032JY00-029-G | MOS N,SUM70040E-GE3,100V,120A,G,TO-263-3,SMD | VISHAY ENTER TECHNO LOGY.INC | SUM70040E-GE3 | G | PWA BOM | In New BOM |
|  | PHAQ1,PHAQ2,PHAQ3 | 3 | 51031VY00-031-G | MOS N,PSMN4R8-100BSE,100V,120A,4.8m@10V,G,SOT404-3,SMD | NXP SEMICONDUCTORS | PSMN4R8-100BSE | G | PWA BOM | In Old BOM |
|  |  |  | 51032HE00-185-G | MOS N,FDB047N10,100V,120A,3.9m@10V,G,TO263-3,SMD | FAIRCHILD SEMICONDUCTOR CORP | FDB047N10 | G | PWA BOM | In Old BOM |
|  |  |  | SUM70040E-GE3 | MOS N,SUM70040E-GE3,100V,120A,4.0m@10V,G,TO263-3,SMD | VISHAY ENTER TECHNO LOGY.INC | SUM70040E-GE3 | G | PWA BOM | In Old BOM |
| 11 | PHAR20 | 1 | 610119P00-017-G | RES,5.11KOhm,+/-1%,1/16W,G,SMD0402 | KOA SPEER ELECTRONICS, INC. | RK73H1ETTP5111F | G | PWA BOM | In New BOM |
|  |  |  | 610119P00-012-G | RES,5.11KOhm,+/-1%,1/16W,G,SMD0402 | WALSIN TECHNOLOGY CORPORATION | WR04X5111FTL | G | PWA BOM | In New BOM |
|  |  |  | 610119P00-011-G | RES,5.11KOhm,+/-1%,1/16W,G,SMD0402 | YAGEO CORPORATION COMPONENT | RC0402FR-075K11L | G | PWA BOM | In New BOM |
|  |  |  | 610119P00-024-G | RES,5.11KOhm,+/-1%,1/16W,G,SMD0402 | PANASONIC INDUSTRIAL CO.,LTD. | ERJ2RKF5111X | G | PWA BOM | In New BOM |
|  |  |  | 610119P00-029-G | RES,5.11KOhm,+/-1%,1/16W,G,SMD0402 | VISHAY ENTER TECHNO LOGY.INC | CRCW04025K11FKED | G | PWA BOM | In New BOM |
|  | PHAR20 | 1 | 610119P00-017-G | RES,5.11KOhm,+/-1%,1/16W,G,SMD0402 | KOA SPEER ELECTRONICS, INC. | RK73H1ETTP5111F | G | PWA BOM | In Old BOM |
|  |  |  | 610119P00-012-G | RES,5.11KOhm,+/-1%,1/16W,G,SMD0402 | WALSIN TECHNOLOGY CORPORATION | WR04X5111FTL | G | PWA BOM | In Old BOM |
|  |  |  | 610119P00-011-G | RES,5.11KOhm,+/-1%,1/16W,G,SMD0402 | YAGEO CORPORATION COMPONENT | RC0402FR-075K11L | G | PWA BOM | In Old BOM |
|  |  |  | 610119P00-024-G | RES,5.11KOhm,+/-1%,1/16W,G,SMD0402 | PANASONIC | ERJ2RKF5111X | G | PWA BOM | In Old BOM |
|  |  |  | 610119P00-029-G | RES,5.11KOhm,+/-1%,1/16W,G,SMD0402 | VISHAY ENTER TECHNO LOGY.INC | CRCW04025K11FKED | G | PWA BOM | In Old BOM |
| 12 | PSRL2 | 1 | 63034GW00-088-G | IND,680nH@100KHz,+/-20%,34A,1.33mOhm,SHLD,G,SMD | COOPER BUSSMANN, INC. | HCM1305-R68-R | G | PWA BOM | In New BOM |
|  |  |  | 630365H00-034-G | IND,680nH@100KHz,+/-20%,29.5A,1.55mOhm,SHLD,G,SMD | CYNTEC CO. LTD | CMLB135T-R68MS | G | PWA BOM | In New BOM |
|  | PSRL2 | 1 | 63034GW00-088-G | IND,680nH@100KHz,+/-20%,34A,1.33mOhm,SHLD,G,SMD | COOPER BUSSMANN, INC. | HCM1305-R68-R | G | PWA BOM | In Old BOM |
|  |  |  | CMLB135T-R68MS | IND,680nH@100KHz,+/-20%,34A,1.33mOhm,SHLD,G,SMD | CYNTEC CO. LTD | CMLB135T-R68MS | G | PWA BOM | In Old BOM |
| 13 | PSRR13 | 1 | 610114A00-017-G | RES,24.9KOhm,+/-1%,1/16W,G,SMD0402 | KOA SPEER ELECTRONICS, INC. | RK73H1ETTP2492F | G | PWA BOM | In New BOM |
|  |  |  | 610114A00-012-G | RES,24.9KOhm,+/-1%,1/16W,G,SMD0402 | WALSIN TECHNOLOGY CORPORATION | WR04X2492FTL | G | PWA BOM | In New BOM |
|  |  |  | 610114A00-011-G | RES,24.9KOhm,+/-1%,1/16W,G,SMD0402 | YAGEO CORPORATION COMPONENT | RC0402FR-0724K9L | G | PWA BOM | In New BOM |
|  |  |  | 610114A00-024-G | RES,24.9KOhm,+/-1%,1/16W,G,SMD0402 | PANASONIC INDUSTRIAL CO.,LTD. | ERJ2RKF2492X | G | PWA BOM | In New BOM |
|  |  |  | 610114A00-029-G | RES,24.9KOhm,+/-1%,1/16W,G,SMD0402 | VISHAY ENTER TECHNO LOGY.INC | CRCW040224K9FKED | G | PWA BOM | In New BOM |
|  | PSRR13 | 1 | 610114A00-017-G | RES,24.9KOhm,+/-1%,1/16W,G,SMD0402 | KOA SPEER ELECTRONICS, INC. | RK73H1ETTP2492F | G | PWA BOM | In Old BOM |
|  |  |  | 610114A00-012-G | RES,24.9KOhm,+/-1%,1/16W,G,SMD0402 | WALSIN TECHNOLOGY CORPORATION | WR04X2492FTL | G | PWA BOM | In Old BOM |
|  |  |  | 610114A00-011-G | RES,24.9KOhm,+/-1%,1/16W,G,SMD0402 | YAGEO CORPORATION COMPONENT | RC0402FR-0724K9L | G | PWA BOM | In Old BOM |
|  |  |  | 610114A00-024-G | RES,24.9KOhm,+/-1%,1/16W,G,SMD0402 | PANASONIC | ERJ2RKF2492X | G | PWA BOM | In Old BOM |
|  |  |  | 610114A00-029-G | RES,24.9KOhm,+/-1%,1/16W,G,SMD0402 | VISHAY ENTER TECHNO LOGY.INC | CRCW040224K9FKED | G | PWA BOM | In Old BOM |
| 14 | PSTR17 | 1 | 61100QA00-017-G | RES,16KOhm,+/-0.1%,1/16W,G,SMD0402 | KOA SPEER ELECTRONICS, INC. | RN731ETTP1602B25 | G | PWA BOM | In New BOM |
|  |  |  | 61100QA01-024-G | RES,16KOhm,+/-0.1%,1/16W,G,SMD0402 | PANASONIC INDUSTRIAL CO.,LTD. | ERA2AEB163X | G | PWA BOM | In New BOM |
|  |  |  | 61100QA00-029-G | RES,16KOhm,+/-0.1%,1/16W,G,SMD0402 | VISHAY ENTER TECHNO LOGY.INC | TNPW040216K0BEED | G | PWA BOM | In New BOM |
|  | PSTR17 | 1 | 61100QA00-017-G | RES,16KOhm,+/-0.1%,1/16W,G,SMD0402 | KOA SPEER ELECTRONICS, INC. | RN731ETTP1602B25 | G | PWA BOM | In Old BOM |
|  |  |  | ERA2AEB163X | RES,16KOhm,+/-0.1%,1/16W,G,SMD0402 | PANASONIC INDUSTRIAL CO.,LTD. | ERA2AEB163X | G | PWA BOM | In Old BOM |
|  |  |  | 61100QA00-029-G | RES,16KOhm,+/-0.1%,1/16W,G,SMD0402 | VISHAY ENTER TECHNO LOGY.INC | TNPW040216K0BEED | G | PWA BOM | In Old BOM |
| 15 | PSTR19 | 1 | 61100J401-017-G | RES,1.78KOhm,+/-0.1%,1/16W,G,SMD0402 | KOA SPEER ELECTRONICS, INC. | RN73H1ETTP1781B25 | G | PWA BOM | In New BOM |
|  |  |  | 61100J400-024-G | RES,1.78KOhm,+/-0.1%,1/16W,G,SMD0402 | PANASONIC INDUSTRIAL CO.,LTD. | ERA2AEB1781X | G | PWA BOM | In New BOM |
|  |  |  | 61100J400-029-G | RES,1.78KOhm,+/-0.1%,1/16W,G,SMD0402 | VISHAY ENTER TECHNO LOGY.INC | MCS0402MD1781BE000 | G | PWA BOM | In New BOM |
|  | PSTR19 | 1 | 61100J401-017-G | RES,1.78KOhm,+/-0.1%,1/16W,G,SMD0402 | KOA SPEER ELECTRONICS, INC. | RN73H1ETTP1781B25 | G | PWA BOM | In Old BOM |
|  |  |  | 61100J400-024-G | RES,1.78KOhm,+/-0.1%,1/16W,G,SMD0402 | PANASONIC INDUSTRIAL CO.,LTD. | ERA2AEB1781X | G | PWA BOM | In Old BOM |
|  |  |  | MCS0402MD1781BE000 | RES,1.78KOhm,+/-0.1%,1/16W,G,SMD0402 | VISHAY ENTER TECHNO LOGY.INC | MCS0402MD1781BE000 | G | PWA BOM | In Old BOM |
| 16 | QN2,QN3 | 2 | 510503B00-223-G | MOS N/N,NTZD3154NT1G,20V,0.54A,550m24.5V,G,SOT563-6,SMD | ON SEMICONDUCTOR CORP | NTZD3154NT1G | G | PWA BOM | In New BOM |
|  |  |  | 51050L500-029-G | MOS,N/N,Si1034CX-T1-GE3,20V,0.61A,G,SC-89-6,SMD | VISHAY ENTER TECHNO LOGY.INC | Si1034CX-T1-GE3 | G | PWA BOM | In New BOM |
|  |  |  | 51050KW00-131-G | MOS N/N,SSM6N36FE,20V,500mA,0.63@5V,G,ES6-6,SMD | TOSHIBA ELECTRONICS ASIA LTD | SSM6N36FE | G | PWA BOM | In New BOM |
|  | QN2,QN3 | 2 | 510503B00-223-G | MOS N/N,NTZD3154NT1G,20V,0.54A,550m24.5V,G,SOT563-6,SMD | ON SEMICONDUCTOR CORP | NTZD3154NT1G | G | PWA BOM | In Old BOM |
|  |  |  | Si1034CX-T1-GE3 | MOS N/N,Si1034CX,20V,0.5A,1ohm@4V,G,EMT-6,SMD | VISHAY ENTER TECHNO LOGY.INC | Si1034CX-T1-GE3 | G | PWA BOM | In Old BOM |
|  |  |  | 51050KW00-131-G | MOS N/N,SSM6N36FE,20V,500mA,0.63@5V,G,ES6-6,SMD | TOSHIBA ELECTRONICS ASIA LTD | SSM6N36FE | G | PWA BOM | In Old BOM |
| 17 | Q5,Q7 | 2 | 510406000-185-G | MOS P,FDD6685,30V,11A,30m@4.5V,G,TO252-3,SMD | FAIRCHILD SEMICONDUCTOR CORP | FDD6685 | G | PWA BOM | In New BOM |
|  |  |  | 510410800-221-G | MOS P,IPD042P03L3G,-30V,-70A,4.2m@-10V,G,TO-252-3,SMD | INFINEON TECHNOLOGIES CORP. | IPD042P03L3G | G | PWA BOM | In New BOM |
|  |  |  | 51040WQ00-131-G | MOSFET-P,TJ40S04M3L,-40V,-40A,9.1mOhm@Vgs=-10V,13mOhm@Vgs=-6V,SMD,3P,G | TOSHIBA ELECTRONICS ASIA LTD | TJ40S04M3L | G | PWA BOM | In New BOM |
|  | Q5,Q7 | 2 | 510406000-185-G | MOS P,FDD6685,30V,11A,30m@4.5V,G,TO252-3,SMD | FAIRCHILD SEMICONDUCTOR CORP | FDD6685 | G | PWA BOM | In Old BOM |
|  |  |  | IPD042P03L3 | MOS P,30V,11A,30m@4.5V,G,TO252-3,SMD | INFINEON TECHNOLOGIES CORP. | IPD042P03L3 | G | PWA BOM | In Old BOM |
|  |  |  | 51040WQ00-131-G | MOSFET-P,TJ40S04M3L,-40V,-40A,9.1mOhm@Vgs=-10V,13mOhm@Vgs=-6V,SMD,3P,G | TOSHIBA ELECTRONICS ASIA LTD | TJ40S04M3L | G | PWA BOM | In Old BOM |
| 18 | R123,R124,R125,R126,R127,R128,R327,R829,R835,R836,R1125,R1513,R1542,R1543,R1544,R1545,R1546,R1547 | 18 | 610102C00-017-G | RES,15KOhm,+/-5%,1/16W,G,SMD0402 | KOA SPEER ELECTRONICS, INC. | RK73B1ETTP153J | G | PWA BOM | In New BOM |
|  |  |  | 610102C00-011-G | RES,15KOhm,+/-5%,1/16W,G,SMD0402 | YAGEO CORPORATION COMPONENT | RC0402JR-0715KL | G | PWA BOM | In New BOM |
|  |  |  | 610102C00-012-G | RES,15KOhm,+/-5%,1/16W,G,SMD0402 | WALSIN TECHNOLOGY CORPORATION | WR04X153JTL | G | PWA BOM | In New BOM |
|  |  |  | 610102C00-024-G | RES,15KOhm,+/-5%,1/16W,G,SMD0402 | PANASONIC INDUSTRIAL CO.,LTD. | ERJ2GEJ153X | G | PWA BOM | In New BOM |
|  |  |  | 610102C00-029-G | RES,15KOhm,+/-5%,1/16W,G,SMD0402 | VISHAY ENTER TECHNO LOGY.INC | CRCW040215K0JNED | G | PWA BOM | In New BOM |
|  |  |  | 610102C00-044-G | RES,15KOhm,+/-5%,1/16W,G,SMD0402 | TA-I TECHNOLOGY CO., LTD | RM04JTN153 | G | PWA BOM | In New BOM |
|  | R123,R124,R125,R126,R127,R128,R327,R829,R835,R836,R1125,R1513,R1542,R1543,R1544,R1545,R1546,R1547 | 18 | 610102C00-017-G | RES,15KOhm,+/-5%,1/16W,G,SMD0402 | KOA SPEER ELECTRONICS, INC. | RK73B1ETTP153J | G | PWA BOM | In Old BOM |
|  |  |  | 610102C00-011-G | RES,15KOhm,+/-5%,1/16W,G,SMD0402 | YAGEO CORPORATION COMPONENT | RC0402JR-0715KL | G | PWA BOM | In Old BOM |
|  |  |  | 610102C00-012-G | RES,15KOhm,+/-5%,1/16W,G,SMD0402 | WALSIN TECHNOLOGY CORPORATION | WR04X153JTL | G | PWA BOM | In Old BOM |
|  |  |  | 610102C00-024-G | RES,15KOhm,+/-5%,1/16W,G,SMD0402 | PANASONIC | ERJ2GEJ153X | G | PWA BOM | In Old BOM |
|  |  |  | 610102C00-029-G | RES,15KOhm,+/-5%,1/16W,G,SMD0402 | VISHAY ENTER TECHNO LOGY.INC | CRCW040215K0JNED | G | PWA BOM | In Old BOM |
|  |  |  | 610102C00-044-G | RES,15KOhm,+/-5%,1/16W,G,SMD0402 | TA-I TECHNOLOGY CO., LTD | RM04JTN153 | G | PWA BOM | In Old BOM |
| 19 | Y1 | 1 | 71020SC00-107-G | OSC,24MHz,+/-25ppm,3.3V,15pF,G,SMD | DAISHINKU CORPORATION/DAISHINKU SINGAPORE PTE LTD/KDS | 1XSE024000AR40 | G | PWA BOM | In New BOM |
|  |  |  | SIT1602BI-22-33E | OSC,24MHz,+/-25ppm,3.3V,15pF,G,SMD | SiTime Corporation | SIT1602BI-22-33E-24.000000 |  | PWA BOM | In New BOM |
|  | Y1 | 1 | 71020SC00-107-G | OSC,24MHz,+/-25ppm,3.3V,15pF,G,SMD | DAISHINKU CORPORATION/DAISHINKU SINGAPORE PTE LTD/KDS | 1XSE024000AR40 | G | PWA BOM | In Old BOM |
| 20 | DIMM02,DIMM04,DIMM06,DIMM09,DIMM11,DIMM13,DIMM15,DIMM16,DIMM18,DIMM20,DIMM22,DIMM25,DIMM27,DIMM29,DIMM31,DIMM00 | 16 | 34021BC00-G78-G | CONN,DDR IV,V/T,1.2V,Blu,0.85mm,15u,G,SMD-288 | FCI CONNECTORS HONGKONG LTD. | 10140702-0302K11LF | G | PWA BOM | In New BOM |
|  |  |  | 34021CD00-600-G | Memory Connector,AH58897-T2L31-3F,DDR IV,288,SMD,THERMOPLASTIC,0.85mm,15u",Blue,G | FOXCONN TECHNOLOGY CO.,LTD. | AH58897-T2L31-3F | G | PWA BOM | In New BOM |
|  |  |  | ADDR0245-K010C | CONN,DDR IV,V/T,1.2V,Blu,0.85mm,15u,G,SMD-288 | LOTES CO LTD | ADDR0245-K010C | G | PWA BOM | In New BOM |
|  |  |  | 2042451004 | CONN,2042451004,DDR IV,V/T,1.2V,288,SMD | MOLEX INCORPORATED | 2042451004 |  | PWA BOM | In New BOM |
|  | DIMM02,DIMM04,DIMM06,DIMM09,DIMM11,DIMM13,DIMM15,DIMM16,DIMM18,DIMM20,DIMM22,DIMM25,DIMM27,DIMM29,DIMM31,DIMM00 | 16 | 34021BC00-G78-G | CONN,DDR IV,V/T,1.2V,Blu,0.85mm,15u,G,SMD-288 | FCI CONNECTORS HONGKONG LTD. | 10140702-0302K11LF | G | PWA BOM | In Old BOM |
|  |  |  | 34021CD00-600-G | Memory Connector,AH58897-T2L31-3F,DDR IV,288,SMD,THERMOPLASTIC,0.85mm,15u",Blue,G | FOXCONN TECHNOLOGY CO.,LTD. | AH58897-T2L31-3F | G | PWA BOM | In Old BOM |
|  |  |  | ADDR0245-K010C | CONN,DDR IV,V/T,1.2V,Blu,0.85mm,15u,G,SMD-288 | LOTES CO LTD | ADDR0245-K010C | G | PWA BOM | In Old BOM |
|  |  |  | 34021CC00-245-G | Memory Connector,DDR4288S05A1H,DDR IV,288,SMD,NYLON,0.85mm,15u",Blue,G | AMPHENOL SHANGHAI CORP. | DDR4288S05A1H | G | PWA BOM | In Old BOM |
| 21 | DIMM01,DIMM03,DIMM05,DIMM07,DIMM08,DIMM10,DIMM12,DIMM14,DIMM17,DIMM19,DIMM21,DIMM23,DIMM24,DIMM26,DIMM28,DIMM30 | 16 | 34021BD00-G78-G | CONN,DDR IV,V/T,1.2V,Bla,0.85mm,15u,G,SMD-288 | FCI CONNECTORS HONGKONG LTD. | 10140702-0301K11LF | G | PWA BOM | In New BOM |
|  |  |  | ADDR0245-P009C | CONN,DDR IV,V/T,1.2V,Bla,0.85mm,15u,G,SMD-288 | LOTES CO LTD | ADDR0245-P009C | G | PWA BOM | In New BOM |
|  |  |  | 34021CF00-600-G | Memory Connector,AH58897-T2B21-3F,DDR IV,288,SMD,THERMOPLASTIC,0.85mm,15u",Black,G | FOXCONN TECHNOLOGY CO.,LTD. | AH58897-T2B21-3F | G | PWA BOM | In New BOM |
|  |  |  | 2042451003 | CONN,2042451004,DDR IV,V/T,1.2V,288,SMD | MOLEX INCORPORATED | 2042451004 |  | PWA BOM | In New BOM |
|  | DIMM01,DIMM03,DIMM05,DIMM07,DIMM08,DIMM10,DIMM12,DIMM14,DIMM17,DIMM19,DIMM21,DIMM23,DIMM24,DIMM26,DIMM28,DIMM30 | 16 | 34021BD00-G78-G | CONN,DDR IV,V/T,1.2V,Bla,0.85mm,15u,G,SMD-288 | FCI CONNECTORS HONGKONG LTD. | 10140702-0301K11LF | G | PWA BOM | In Old BOM |
|  |  |  | ADDR0245-P009C | CONN,DDR IV,V/T,1.2V,Bla,0.85mm,15u,G,SMD-288 | LOTES CO LTD | ADDR0245-P009C | G | PWA BOM | In Old BOM |
|  |  |  | 34021CF00-600-G | Memory Connector,AH58897-T2B21-3F,DDR IV,288,SMD,THERMOPLASTIC,0.85mm,15u",Black,G | FOXCONN TECHNOLOGY CO.,LTD. | AH58897-T2B21-3F | G | PWA BOM | In Old BOM |
|  |  |  | 34021CE00-245-G | Memory Connector,DDR4288S0511H,DDR IV,288,SMD,NYLON,0.85mm,15u",Black,G | AMPHENOL SHANGHAI CORP. | DDR4288S0511H | G | PWA BOM | In Old BOM |
| 22 | LAN1 | 1 | 34050PV00-48U-G | CONN,Modular Jack,RJ45X2,R/A,Bla,1.27mm,50u,G,DIP-28 | TRP CONNECTOR B.V. | 1840855-5 | G | PWA BOM | In New BOM |
|  |  |  | 34051E700-609-G | CONN,Modular Jack,RJ45X2,R/A,Bla,1.27mm,50u,G,DIP-28 | U.D. Electronic Corp. | MA-FN-0003 | G | PWA BOM | In New BOM |
|  |  |  | 34050BF00-245-G | CONN,RJ45,Multi port,R/A,Bla,1.27mm,30u,G,DIP-28 | AMPHENOL SHANGHAI CORP. | RJMG221031470NR | G | PWA BOM | In New BOM |
|  | LAN1 | 1 | 34050PV00-48U-G | CONN,Modular Jack,RJ45X2,R/A,Bla,1.27mm,50u,G,DIP-28 | TRP CONNECTOR B.V. | 1840855-5 | G | PWA BOM | In Old BOM |
|  |  |  | 34051E700-609-G | CONN,Modular Jack,RJ45X2,R/A,Bla,1.27mm,50u,G,DIP-28 | U.D. Electronic Corp. | MA-FN-0003 | G | PWA BOM | In Old BOM |
|  |  |  | 34050BF00-245-G | CONN,RJ45,Multi port,R/A,Bla,1.27mm,30u,G,DIP-28 | AMPHENOL | RJMG221031470NR | G | PWA BOM | In Old BOM |
| 23 | C2011 | 1 | 62012P100-015-G | CAP,2.2uF,+/-20%,X7S,10V,G,SMD0402 | MURATA ELEC. NORTH AMERICA | GRM155C71A225M | G | PWA BOM | In New BOM |
|  |  |  | 62012P100-012-G | CAP,2.2uF,+/-20%,X7S,10V,G,SMD0402 | WALSIN TECHNOLOGY CORPORATION | 0402A225M100CT | G | PWA BOM | In New BOM |
|  | C2011 | 1 | 620101T02-015-G | CAP,100nF,+/-10%,X7R,16V,G,SMD0402 | MURATA ELEC. NORTH AMERICA | GRM155R71C104K | G | PWA BOM | In Old BOM |
|  |  |  | 620101T00-012-G | CAP,100nF,+/-10%,X7R,16V,G,SMD0402 | WALSIN TECHNOLOGY CORPORATION | 0402B104K160CT | G | PWA BOM | In Old BOM |
|  |  |  | 620101T00-026-G | CAP,100nF,+/-10%,X7R,16V,G,SMD0402 | SAMSUNG SEMICONDUCTOR | CL05B104KO5NNNC | G | PWA BOM | In Old BOM |
|  |  |  | 620101T00-015-G | CAP,100nF,+/-10%,X7R,16V,G,SMD0402 | MURATA ELEC. NORTH AMERICA | GRM155R71C104KA88D | G | PWA BOM | In Old BOM |
| 24 | PSUCE1,PBACE1,PAACE1,PSUCE2,PBACE2,PAACE2 | 6 | 62111U700-024-G | ECAP,68uF,+/-20%,100V,105C,320mOhm,G,SMD12.5*13.5 | PANASONIC INDUSTRIAL CO.,LTD. | EEEFK2A680AQ | G | PWA BOM | In New BOM |
|  | PSUCE1,PBACE1,PAACE1,PSUCE2,PBACE2,PAACE2 | 6 | EEEFK2A680AQ | ECAP,68uF,+/-20%,100V,105C,G,SMD12.5*13.5,ESR<=320mOhm | PANASONIC INDUSTRIAL CO.,LTD. | EEEFK2A680AQ | G | PWA BOM | In Old BOM |
| 25 | PBMD1,PBFD1,PBED1,PBAD1,PAMD1,PAFD1,PAED1,PAAD1 | 8 | 520103B00-185-G | Diode,Rectifier&Switching,MMBD1205,100V,200mA,G,SOT-23-3,SMD | FAIRCHILD SEMICONDUCTOR CORP | MMBD1205 | G | PWA BOM | In New BOM |
|  |  |  | 52010A100-237-G | Diode,Rectifier&Switching,100V,200mA,G,SOT-23-3,SMD | DIODES INCORPORATION | MMBD3004A-7-F |  | PWA BOM | In New BOM |
|  | PBMD1,PBFD1,PBED1,PBAD1,PAMD1,PAFD1,PAED1,PAAD1 | 8 | 52030DA00-237-G | DIODE,Schottky,BAT46W-7-F,100V,150mA,G,SOD123-2,SMD | DIODES INEORPORATION | BAT46W-7-F | G | PWA BOM | In Old BOM |
| 26 | PCIE1,PCIE5 | 2 | 10128241-112X0LF | CONN,PCIE-8X,V/T,Bla,1mm,30u,G,SMD-98 | FCI CONNECTORS HONGKONG LTD. | 10128241-112X0LF | G | PWA BOM | In New BOM |
|  | PCIE1,PCIE5 | 2 | 10061913-102HLF | CONN,PCIE-8X,V/T,Bla,1mm,30u,G,SMD-98 | FCI CONNECTORS HONGKONG LTD. | 10061913-102HLF | G | PWA BOM | In Old BOM |
|  |  |  | 340320R00-278-G | CONN,PCIE-8X,V/T,Bla,1mm,30u,G,SMD-98 | TYCO ELECTRONICS CORPORATION | 2041366-4 | G | PWA BOM | In Old BOM |
|  |  |  | APCI0282-P003A | CONN,PCIE-8X,V/T,Bla,1mm,30u,G,SMD-98 | LOTES CO LTD | APCI0282-P003A | G | PWA BOM | In Old BOM |
| 27 | PCIE2,PCIE3,PCIE4 | 3 | 10128241-113X0LF | CONN,PCIE-16X,V/T,Bla,1mm,30u,G,SMD-164 | FCI CONNECTORS HONGKONG LTD. | 10128241-113X0LF | G | PWA BOM | In New BOM |
|  | PCIE2,PCIE3,PCIE4 | 3 | 10061913-103HLF | CONN,PCIE-16X,V/T,Bla,1mm,30u,G,SMD-164 | FCI CONNECTORS HONGKONG LTD. | 10061913-103HLF | G | PWA BOM | In Old BOM |
|  |  |  | 340320Q00-278-G | CONN,PCIE-16X,V/T,Bla,1mm,30u,G,SMD-164 | TYCO ELECTRONICS CORPORATION | 2041366-6 | G | PWA BOM | In Old BOM |
|  |  |  | APCI0261-P001C | CONN,PCIE-16X,V/T,Bla,1mm,30u,G,SMD-164 | LOTES CO LTD | APCI0261-P001C | G | PWA BOM | In Old BOM |
| 28 | PBAR65,PAAR65 | 2 | 610606G00-017-G | RES,20mOhm,+/-1%,5W,G,SMD2512 | KOA SPEER ELECTRONICS, INC. | TLRH3APTTE20L0F | G | PWA BOM | In New BOM |
|  |  |  | 610605400-125-G | RES,20mOhm,+/-1%,1W,G,SMD2512 | INTERNATIONAL RESISTIVE COMPANY, INC. | LRMAP2512-R02FT4 | G | PWA BOM | In New BOM |
|  | PBAR65,PAAR65 | 2 | TLRH3APTTE20L0F | RES,20mOhm,+/-1%,2W,G,SMD2512 | KOA SPEER ELECTRONICS, INC. | TLRH3APTTE20L0F | G | PWA BOM | In Old BOM |
|  |  |  | LRMAP2512-R02FT4 | RES,20mOhm,+/-1%,2W,G,SMD2512 | INTERNATIONAL RESISTIVE COMPANY, INC. | LRMAP2512-R02FT4 | G | PWA BOM | In Old BOM |
| 29 | PBER65,PAFR65,PAER65,PBFR66 | 4 | 610606H00-017-G | RES,50mOhm,+/-1%,1.5W,G,SMD2512 | KOA SPEER ELECTRONICS, INC. | SLW1TTE50L0F | G | PWA BOM | In New BOM |
|  |  |  | 610606E00-125-G | RES,50mOhm,+/-1%,1W,G,SMD2512 | INTERNATIONAL RESISTIVE COMPANY, INC. | LRMAP2512-R05FT4 | G | PWA BOM | In New BOM |
|  | PBER65,PAFR65,PAER65,PBFR66 | 4 | SLW1TTE50L0F | RES,50mOhm,+/-1%,1.5W,G,SMD2512 | KOA | SLW1TTE50L0F | G | PWA BOM | In Old BOM |
|  |  |  | LRMAP2512-R05FT4 | RES,50mOhm,+/-1%,1.5W,G,SMD2512 | INTERNATIONAL RESISTIVE COMPANY, INC. | LRMAP2512-R05FT4 | G | PWA BOM | In Old BOM |
| 30 | PBMR34,PAMR34 | 2 | 61100YW00-017-G | RES,316 Ohm,+/-0.1%,1/16W,G,SMD0402 | KOA SPEER ELECTRONICS, INC. | RN731ETTP3160B25 | G | PWA BOM | In New BOM |
|  | PBMR34,PAMR34 | 2 | RN731ETTP3160B25 | RES,316 Ohm,+/-0.1%,1/16W,G,SMD0402 | KOA SPEER ELECTRONICS, INC. | RN731ETTP3160B25 | G | PWA BOM | In Old BOM |
| 31 | PBMR65,PAMR65 | 2 | 610606J00-017-G | RES,75mOhm,+/-1%,1.5W,G,SMD2512 | KOA SPEER ELECTRONICS, INC. | SLW1TTE75L0F | G | PWA BOM | In New BOM |
|  |  |  | 610606D00-125-G | RES,75mOhm,+/-1%,1W,G,SMD2512 | INTERNATIONAL RESISTIVE COMPANY, INC. | LRMAP2512-R075FT4 | G | PWA BOM | In New BOM |
|  | PBMR65,PAMR65 | 2 | SLW1TTE75L0F | RES,75mOhm,+/-1%,1.5W,G,SMD2512 | KOA | SLW1TTE75L0F | G | PWA BOM | In Old BOM |
|  |  |  | LRMAP2512-R075FT4 | RES,75mOhm,+/-1%,1.5W,G,SMD2512 | INTERNATIONAL RESISTIVE COMPANY, INC. | LRMAP2512-R075FT4 | G | PWA BOM | In Old BOM |
| 32 | U1,U10 | 2 | PE38993-51BC1-1H | POWER9 CPU Socket for LGA3899-HYBRID | FOXCONN TECHNOLOGY CO.,LTD. | PE38993-51BC1-1H | G | PWA BOM | In New BOM |
|  | U1,U10 | 2 | 340108S00-600-G | POWER9 CPU Socket for LGA3899-HYBRID | FOXCONN TECHNOLOGY CO.,LTD. | PE38993-51BC0-1H | G | PWA BOM | In Old BOM |
| ##### Change Revision |  |  |  |  |  |  |  |  |  |
| Sheet | REV OF BOM | CUSTOMER | CUSTOMER P/N | PWA PN | PWA DESCRIPTION | PWA REV | DATE | Remark |  |
| OOOOOOOOOOOOOOOOOOOOOOOOOOOOOOOOOOOOOOOOOOOOOOOOOOOOOOOOOOOOOOOOOOOOOOOOOOOOOOOOOOOOOOOOOO | OOOOOOOOOOOOOOOOOOOOOOOOOOOOOOOOOOOOOOOOOOOOOOOOOOOOOOOOOOOOOOOOOOOOOOOOOOOOOOOOOOOOOOOOOO | OOOOOOOOOOOOOOOOOOOOOOOOOOOOOOOOOOOOOOOOOOOOOOOOOOOOOOOOOOOOOOOOOOOOOOOOOOOOOOOOOOOOOOOOOO | OOOOOOOOOOOOOOOOOOOOOOOOOOOOOOOOOOOOOOOOOOOOOOOOOOOOOOOOOOOOOOOOOOOOOOOOOOOOOOOOOOOOOOOOOO | OOOOOOOOOOOOOOOOOOOOOOOOOOOOOOOOOOOOOOOOOOOOOOOOOOOOOOOOOOOOOOOOOOOOOOOOOOOOOOOOOOOOOOOOOO | OOOOOOOOOOOOOOOOOOOOOOOOOOOOOOOOOOOOOOOOOOOOOOOOOOOOOOOOOOOOOOOOOOOOOOOOOOOOOOOOOOOOOOOOOO | OOOOOOOOOOOOOOOOOOOOOOOOOOOOOOOOOOOOOOOOOOOOOOOOOOOOOOOOOOOOOOOOOOOOOOOOOOOOOOOOOOOOOOOOOO | OOOOOOOOOOOOOOOOOOOOOOOOOOOOOOOOOOOOOOOOOOOOOOOOOOOOOOOOOOOOOOOOOOOOOOOOOOOOOOOOOOOOOOOOOO | OOOOOOOOOOOOOOOOOOOOOOOOOOOOOOOOOOOOOOOOOOOOOOOOOOOOOOOOOOOOOOOOOOOOOOOOOOOOOOOOOOOOOOOOOO | OOOOOOOOOOOOOOOOOOOOOOOOOOOOOOOOOOOOOOOOOOOOOOOOOOOOOOOOOOOOOOOOOOOOOOOOOOOOOOOOOOOOOOOOOO |
| Second Source Change |  |  |  |  |  |  |  |  |  |
| Item | Location | Change Type | Foxconn P/N | Part Description | Manufacturer Full Name | Manufacturer P/N | RoHS | Sheet |  |
| 1 | L34,L36 |  | 72010A400-023-G | FB,80Ohm@100MHz,+/-25%,4A,10mOhm,G,SMD1206 | TAIYO ELECTRIC IND.CO.LTD | FBMJ3216HS800-T | G | PWA BOM |  |
|  |  | ADD | 72010A400-025-G | FB,Multilayer,10mOhm,80Ohm@100MHz,+/-25%,4A,,SMD1206,G | KEMET ELECTRONICS CORPORATION | Z1206C800APWST | G | PWA BOM |  |
|  |  | Delete | Z1206C800APWST | FB,80Ohm@100MHz,+/-25%,4A,10mOhm,G,SMD1206 | KEMET ELECTRONICS CORPORATION | Z1206C800APWST | G | PWA BOM |  |
| 2 | PBMQ10,PBAQ10,PAMQ10,PAAQ10,PBFQ11,PBEQ11,PAFQ11,PAEQ11 |  | 51032DL00-237-G | MOS N,DMT10H014LSS-13,100V,8.9A,15m@10V,G,SO-8,SMD | DIODES INCORPORATION | DMT10H014LSS-13 | G | PWA BOM |  |
|  |  | ADD | 51032FL00-029-G | MOS N,Si4190ADY-T1-GE3,100V,18.4A,8.8m@10V,G,SO-8,SMD | VISHAY ENTER TECHNO LOGY.INC | Si4190ADY-T1-GE3 | G | PWA BOM |  |
|  |  | Delete | Si4190ADY-T1-GE3 | MOS N,Si4190ADY-T1-GE3,100V,18.4A,8.8m@10V,G,SO-8,SMD | VISHAY ENTER TECHNO LOGY.INC | Si4190ADY-T1-GE3 | G | PWA BOM |  |
| 3 | PHAQ1,PHAQ2,PHAQ3 |  | 51031VY00-031-G | MOS N,PSMN4R8-100BSE,100V,120A,4.8m@10V,G,SOT404-3,SMD | NXP SEMICONDUCTORS | PSMN4R8-100BSE | G | PWA BOM |  |
|  |  | NO | 51032HE00-185-G | MOS N,FDB047N10,100V,120A,3.9m@10V,G,TO263-3,SMD | FAIRCHILD SEMICONDUCTOR CORP | FDB047N10 | G | PWA BOM |  |
|  |  | ADD | 51032JY00-029-G | MOS N,SUM70040E-GE3,100V,120A,G,TO-263-3,SMD | VISHAY ENTER TECHNO LOGY.INC | SUM70040E-GE3 | G | PWA BOM |  |
|  |  | Delete | SUM70040E-GE3 | MOS N,SUM70040E-GE3,100V,120A,4.0m@10V,G,TO263-3,SMD | VISHAY ENTER TECHNO LOGY.INC | SUM70040E-GE3 | G | PWA BOM |  |
| 4 | PSRL2 |  | 63034GW00-088-G | IND,680nH@100KHz,+/-20%,34A,1.33mOhm,SHLD,G,SMD | COOPER BUSSMANN, INC. | HCM1305-R68-R | G | PWA BOM |  |
|  |  | ADD | 630365H00-034-G | IND,680nH@100KHz,+/-20%,29.5A,1.55mOhm,SHLD,G,SMD | CYNTEC CO. LTD | CMLB135T-R68MS | G | PWA BOM |  |
|  |  | Delete | CMLB135T-R68MS | IND,680nH@100KHz,+/-20%,34A,1.33mOhm,SHLD,G,SMD | CYNTEC CO. LTD | CMLB135T-R68MS | G | PWA BOM |  |
| 5 | PSTR17 |  | 61100QA00-017-G | RES,16KOhm,+/-0.1%,1/16W,G,SMD0402 | KOA SPEER ELECTRONICS, INC. | RN731ETTP1602B25 | G | PWA BOM |  |
|  |  | ADD | 61100QA01-024-G | RES,16KOhm,+/-0.1%,1/16W,G,SMD0402 | PANASONIC INDUSTRIAL CO.,LTD. | ERA2AEB163X | G | PWA BOM |  |
|  |  | NO | 61100QA00-029-G | RES,16KOhm,+/-0.1%,1/16W,G,SMD0402 | VISHAY ENTER TECHNO LOGY.INC | TNPW040216K0BEED | G | PWA BOM |  |
|  |  | Delete | ERA2AEB163X | RES,16KOhm,+/-0.1%,1/16W,G,SMD0402 | PANASONIC INDUSTRIAL CO.,LTD. | ERA2AEB163X | G | PWA BOM |  |
| 6 | PSTR19 |  | 61100J401-017-G | RES,1.78KOhm,+/-0.1%,1/16W,G,SMD0402 | KOA SPEER ELECTRONICS, INC. | RN73H1ETTP1781B25 | G | PWA BOM |  |
|  |  | NO | 61100J400-024-G | RES,1.78KOhm,+/-0.1%,1/16W,G,SMD0402 | PANASONIC INDUSTRIAL CO.,LTD. | ERA2AEB1781X | G | PWA BOM |  |
|  |  | ADD | 61100J400-029-G | RES,1.78KOhm,+/-0.1%,1/16W,G,SMD0402 | VISHAY ENTER TECHNO LOGY.INC | MCS0402MD1781BE000 | G | PWA BOM |  |
|  |  | Delete | MCS0402MD1781BE000 | RES,1.78KOhm,+/-0.1%,1/16W,G,SMD0402 | VISHAY ENTER TECHNO LOGY.INC | MCS0402MD1781BE000 | G | PWA BOM |  |
| 7 | QN2,QN3 |  | 510503B00-223-G | MOS N/N,NTZD3154NT1G,20V,0.54A,550m24.5V,G,SOT563-6,SMD | ON SEMICONDUCTOR CORP | NTZD3154NT1G | G | PWA BOM |  |
|  |  | ADD | 51050L500-029-G | MOS,N/N,Si1034CX-T1-GE3,20V,0.61A,G,SC-89-6,SMD | VISHAY ENTER TECHNO LOGY.INC | Si1034CX-T1-GE3 | G | PWA BOM |  |
|  |  | NO | 51050KW00-131-G | MOS N/N,SSM6N36FE,20V,500mA,0.63@5V,G,ES6-6,SMD | TOSHIBA ELECTRONICS ASIA LTD | SSM6N36FE | G | PWA BOM |  |
|  |  | Delete | Si1034CX-T1-GE3 | MOS N/N,Si1034CX,20V,0.5A,1ohm@4V,G,EMT-6,SMD | VISHAY ENTER TECHNO LOGY.INC | Si1034CX-T1-GE3 | G | PWA BOM |  |
| 8 | Q5,Q7 |  | 510406000-185-G | MOS P,FDD6685,30V,11A,30m@4.5V,G,TO252-3,SMD | FAIRCHILD SEMICONDUCTOR CORP | FDD6685 | G | PWA BOM |  |
|  |  | ADD | 510410800-221-G | MOS P,IPD042P03L3G,-30V,-70A,4.2m@-10V,G,TO-252-3,SMD | INFINEON TECHNOLOGIES CORP. | IPD042P03L3G | G | PWA BOM |  |
|  |  | NO | 51040WQ00-131-G | MOSFET-P,TJ40S04M3L,-40V,-40A,9.1mOhm@Vgs=-10V,13mOhm@Vgs=-6V,SMD,3P,G | TOSHIBA ELECTRONICS ASIA LTD | TJ40S04M3L | G | PWA BOM |  |
|  |  | Delete | IPD042P03L3 | MOS P,30V,11A,30m@4.5V,G,TO252-3,SMD | INFINEON TECHNOLOGIES CORP. | IPD042P03L3 | G | PWA BOM |  |
| 9 | Y1 |  | 71020SC00-107-G | OSC,24MHz,+/-25ppm,3.3V,15pF,G,SMD | DAISHINKU CORPORATION/DAISHINKU SINGAPORE PTE LTD/KDS | 1XSE024000AR40 | G | PWA BOM |  |
|  |  | ADD | SIT1602BI-22-33E | OSC,24MHz,+/-25ppm,3.3V,15pF,G,SMD | SiTime Corporation | SIT1602BI-22-33E-24.000000 |  | PWA BOM |  |
| 10 | DIMM02,DIMM04,DIMM06,DIMM09,DIMM11,DIMM13,DIMM15,DIMM16,DIMM18,DIMM20,DIMM22,DIMM25,DIMM27,DIMM29,DIMM31,DIMM00 |  | 34021BC00-G78-G | CONN,DDR IV,V/T,1.2V,Blu,0.85mm,15u,G,SMD-288 | FCI CONNECTORS HONGKONG LTD. | 10140702-0302K11LF | G | PWA BOM |  |
|  |  | NO | 34021CD00-600-G | Memory Connector,AH58897-T2L31-3F,DDR IV,288,SMD,THERMOPLASTIC,0.85mm,15u",Blue,G | FOXCONN TECHNOLOGY CO.,LTD. | AH58897-T2L31-3F | G | PWA BOM |  |
|  |  | NO | ADDR0245-K010C | CONN,DDR IV,V/T,1.2V,Blu,0.85mm,15u,G,SMD-288 | LOTES CO LTD | ADDR0245-K010C | G | PWA BOM |  |
|  |  | ADD | 2042451004 | CONN,2042451004,DDR IV,V/T,1.2V,288,SMD | MOLEX INCORPORATED | 2042451004 |  | PWA BOM |  |
|  |  | Delete | 34021CC00-245-G | Memory Connector,DDR4288S05A1H,DDR IV,288,SMD,NYLON,0.85mm,15u",Blue,G | AMPHENOL SHANGHAI CORP. | DDR4288S05A1H | G | PWA BOM |  |
| 11 | DIMM01,DIMM03,DIMM05,DIMM07,DIMM08,DIMM10,DIMM12,DIMM14,DIMM17,DIMM19,DIMM21,DIMM23,DIMM24,DIMM26,DIMM28,DIMM30 |  | 34021BD00-G78-G | CONN,DDR IV,V/T,1.2V,Bla,0.85mm,15u,G,SMD-288 | FCI CONNECTORS HONGKONG LTD. | 10140702-0301K11LF | G | PWA BOM |  |
|  |  | NO | ADDR0245-P009C | CONN,DDR IV,V/T,1.2V,Bla,0.85mm,15u,G,SMD-288 | LOTES CO LTD | ADDR0245-P009C | G | PWA BOM |  |
|  |  | NO | 34021CF00-600-G | Memory Connector,AH58897-T2B21-3F,DDR IV,288,SMD,THERMOPLASTIC,0.85mm,15u",Black,G | FOXCONN TECHNOLOGY CO.,LTD. | AH58897-T2B21-3F | G | PWA BOM |  |
|  |  | ADD | 2042451003 | CONN,2042451004,DDR IV,V/T,1.2V,288,SMD | MOLEX INCORPORATED | 2042451004 |  | PWA BOM |  |
|  |  | Delete | 34021CE00-245-G | Memory Connector,DDR4288S0511H,DDR IV,288,SMD,NYLON,0.85mm,15u",Black,G | AMPHENOL SHANGHAI CORP. | DDR4288S0511H | G | PWA BOM |  |
| OOOOOOOOOOOOOOOOOOOOOOOOOOOOOOOOOOOOOOOOOOOOOOOOOOOOOOOOOOOOOOOOOOOOOOOOOOOOOOOOOOOOOOOOOO | OOOOOOOOOOOOOOOOOOOOOOOOOOOOOOOOOOOOOOOOOOOOOOOOOOOOOOOOOOOOOOOOOOOOOOOOOOOOOOOOOOOOOOOOOO | OOOOOOOOOOOOOOOOOOOOOOOOOOOOOOOOOOOOOOOOOOOOOOOOOOOOOOOOOOOOOOOOOOOOOOOOOOOOOOOOOOOOOOOOOO | OOOOOOOOOOOOOOOOOOOOOOOOOOOOOOOOOOOOOOOOOOOOOOOOOOOOOOOOOOOOOOOOOOOOOOOOOOOOOOOOOOOOOOOOOO | OOOOOOOOOOOOOOOOOOOOOOOOOOOOOOOOOOOOOOOOOOOOOOOOOOOOOOOOOOOOOOOOOOOOOOOOOOOOOOOOOOOOOOOOOO | OOOOOOOOOOOOOOOOOOOOOOOOOOOOOOOOOOOOOOOOOOOOOOOOOOOOOOOOOOOOOOOOOOOOOOOOOOOOOOOOOOOOOOOOOO | OOOOOOOOOOOOOOOOOOOOOOOOOOOOOOOOOOOOOOOOOOOOOOOOOOOOOOOOOOOOOOOOOOOOOOOOOOOOOOOOOOOOOOOOOO | OOOOOOOOOOOOOOOOOOOOOOOOOOOOOOOOOOOOOOOOOOOOOOOOOOOOOOOOOOOOOOOOOOOOOOOOOOOOOOOOOOOOOOOOOO | OOOOOOOOOOOOOOOOOOOOOOOOOOOOOOOOOOOOOOOOOOOOOOOOOOOOOOOOOOOOOOOOOOOOOOOOOOOOOOOOOOOOOOOOOO | OOOOOOOOOOOOOOOOOOOOOOOOOOOOOOOOOOOOOOOOOOOOOOOOOOOOOOOOOOOOOOOOOOOOOOOOOOOOOOOOOOOOOOOOOO |
| Master Materials Change |  |  |  |  |  |  |  |  |  |
| Item | Foxconn P/N | Orig._Usage | New_Usage | Part Description | Manufacturer Full Name | Manufacturer P/N | RoHS | Location | Sheet |
| 1 | 62012P100-015-G | 27 | 28 | CAP,2.2uF,+/-20%,X7S,10V,G,SMD0402 | MURATA ELEC. NORTH AMERICA | GRM155C71A225M | G | (+)C2011 | PWA BOM |
|  | 62012P100-012-G |  |  | CAP,2.2uF,+/-20%,X7S,10V,G,SMD0402 | WALSIN TECHNOLOGY CORPORATION | 0402A225M100CT |  |  | PWA BOM |
| 2 | 620101T02-015-G | 234 | 233 | CAP,100nF,+/-10%,X7R,16V,G,SMD0402 | MURATA ELEC. NORTH AMERICA | GRM155R71C104K | G | (-)C2011 | PWA BOM |
|  | 620101T00-012-G |  |  | CAP,100nF,+/-10%,X7R,16V,G,SMD0402 | WALSIN TECHNOLOGY CORPORATION | 0402B104K160CT |  |  | PWA BOM |
|  | 620101T00-026-G |  |  | CAP,100nF,+/-10%,X7R,16V,G,SMD0402 | SAMSUNG SEMICONDUCTOR | CL05B104KO5NNNC |  |  | PWA BOM |
|  | 620101T00-015-G |  |  | CAP,100nF,+/-10%,X7R,16V,G,SMD0402 | MURATA ELEC. NORTH AMERICA | GRM155R71C104KA88D |  |  | PWA BOM |
| 3 | 52180BC00-223-G | 0 | 1 | DIODE,Array-TVS,ESD8004MUTAG,G,UDFN-10,SMD | ON SEMICONDUCTOR CORP | ESD8004MUTAG | G | (+)ED1 | PWA BOM |
| 4 | 62111U700-024-G | 0 | 6 | ECAP,68uF,+/-20%,100V,105C,320mOhm,G,SMD12.5*13.5 | PANASONIC INDUSTRIAL CO.,LTD. | EEEFK2A680AQ | G | (+)PSUCE1,PBACE1,PAACE1,PSUCE2,PBACE2,PAACE2 | PWA BOM |
| 5 | 520103B00-185-G | 0 | 8 | Diode,Rectifier&Switching,MMBD1205,100V,200mA,G,SOT-23-3,SMD | FAIRCHILD SEMICONDUCTOR CORP | MMBD1205 | G | (+)PBMD1,PBFD1,PBED1,PBAD1,PAMD1,PAFD1,PAED1,PAAD1 | PWA BOM |
|  | 52010A100-237-G |  |  | Diode,Rectifier&Switching,100V,200mA,G,SOT-23-3,SMD | DIODES INCORPORATION | MMBD3004A-7-F |  |  | PWA BOM |
| 6 | 10128241-112X0LF | 0 | 2 | CONN,PCIE-8X,V/T,Bla,1mm,30u,G,SMD-98 | FCI CONNECTORS HONGKONG LTD. | 10128241-112X0LF | G | (+)PCIE1,PCIE5 | PWA BOM |
| 7 | 10128241-113X0LF | 0 | 3 | CONN,PCIE-16X,V/T,Bla,1mm,30u,G,SMD-164 | FCI CONNECTORS HONGKONG LTD. | 10128241-113X0LF | G | (+)PCIE2,PCIE3,PCIE4 | PWA BOM |
| 8 | 34068LN00-317-G | 6 | 10 | CONN,Header,Pin Header,1X3,V/T,2.54mm,30u,G,SMD-3 | MOLEX INCORPORATED | 87898-0315 | G | (+)J36,J41,J43,J48 | PWA BOM |
|  | 34068HT00-245-G |  |  | CONN,Header,Pin Header,1X3,V/T,Bla,2.54mm,30u,SMD-3 | AMPHENOL SHANGHAI CORP. | G800MU305010EU |  |  | PWA BOM |
|  | 34068GU00-309-G |  |  | CONN,Header,Pin Header,1X3,V/T,Bla,2.54mm,30u,SMD-3 | SAMTEC INC. | TSM-103-01-S-SV-P-TR |  |  | PWA BOM |
| 9 | 3406AQH00-317-G | 0 | 5 | CONN,Header,Pin Header,1X6,V/T,Bla,2.54mm,G,SMD-6 | MOLEX INCORPORATED | 87898-0656 | G | (+)J35,J37,J39,J42,J45 | PWA BOM |
| 10 | 610606G00-017-G | 0 | 2 | RES,20mOhm,+/-1%,5W,G,SMD2512 | KOA SPEER ELECTRONICS, INC. | TLRH3APTTE20L0F | G | (+)PBAR65,PAAR65 | PWA BOM |
|  | 610605400-125-G |  |  | RES,20mOhm,+/-1%,1W,G,SMD2512 | INTERNATIONAL RESISTIVE COMPANY, INC. | LRMAP2512-R02FT4 |  |  | PWA BOM |
| 11 | 610606H00-017-G | 0 | 4 | RES,50mOhm,+/-1%,1.5W,G,SMD2512 | KOA SPEER ELECTRONICS, INC. | SLW1TTE50L0F | G | (+)PBER65,PAFR65,PAER65,PBFR66 | PWA BOM |
|  | 610606E00-125-G |  |  | RES,50mOhm,+/-1%,1W,G,SMD2512 | INTERNATIONAL RESISTIVE COMPANY, INC. | LRMAP2512-R05FT4 |  |  | PWA BOM |
| 12 | 61100YW00-017-G | 0 | 2 | RES,316 Ohm,+/-0.1%,1/16W,G,SMD0402 | KOA SPEER ELECTRONICS, INC. | RN731ETTP3160B25 | G | (+)PBMR34,PAMR34 | PWA BOM |
| 13 | 610606J00-017-G | 0 | 2 | RES,75mOhm,+/-1%,1.5W,G,SMD2512 | KOA SPEER ELECTRONICS, INC. | SLW1TTE75L0F | G | (+)PBMR65,PAMR65 | PWA BOM |
|  | 610606D00-125-G |  |  | RES,75mOhm,+/-1%,1W,G,SMD2512 | INTERNATIONAL RESISTIVE COMPANY, INC. | LRMAP2512-R075FT4 |  |  | PWA BOM |
| 14 | PE38993-51BC1-1H | 0 | 2 | POWER9 CPU Socket for LGA3899-HYBRID | FOXCONN TECHNOLOGY CO.,LTD. | PE38993-51BC1-1H | G | (+)U1,U10 | PWA BOM |
| 15 | EEEFK2A680AQ | 6 | 0 | ECAP,68uF,+/-20%,100V,105C,G,SMD12.5*13.5,ESR<=320mOhm | PANASONIC INDUSTRIAL CO.,LTD. | EEEFK2A680AQ | G | (-)PSUCE1,PBACE1,PAACE1,PSUCE2,PBACE2,PAACE2 | PWA BOM |
| 16 | 52030DA00-237-G | 16 | 0 | DIODE,Schottky,BAT46W-7-F,100V,150mA,G,SOD123-2,SMD | DIODES INEORPORATION | BAT46W-7-F | G | (-)PBMD1,PBFD1,PBED1,PBAD1,PAMD1,PAFD1,PAED1,PAAD1,PBMD4,PBFD4,PBED4,PAMD4,PAFD4,PAED4,PBAD5,PAAD5 | PWA BOM |
| 17 | 10061913-102HLF | 2 | 0 | CONN,PCIE-8X,V/T,Bla,1mm,30u,G,SMD-98 | FCI CONNECTORS HONGKONG LTD. | 10061913-102HLF | G | (-)PCIE1,PCIE5 | PWA BOM |
|  | 340320R00-278-G |  |  | CONN,PCIE-8X,V/T,Bla,1mm,30u,G,SMD-98 | TYCO ELECTRONICS CORPORATION | 2041366-4 |  |  | PWA BOM |
|  | APCI0282-P003A |  |  | CONN,PCIE-8X,V/T,Bla,1mm,30u,G,SMD-98 | LOTES CO LTD | APCI0282-P003A |  |  | PWA BOM |
| 18 | 10061913-103HLF | 3 | 0 | CONN,PCIE-16X,V/T,Bla,1mm,30u,G,SMD-164 | FCI CONNECTORS HONGKONG LTD. | 10061913-103HLF | G | (-)PCIE2,PCIE3,PCIE4 | PWA BOM |
|  | 340320Q00-278-G |  |  | CONN,PCIE-16X,V/T,Bla,1mm,30u,G,SMD-164 | TYCO ELECTRONICS CORPORATION | 2041366-6 |  |  | PWA BOM |
|  | APCI0261-P001C |  |  | CONN,PCIE-16X,V/T,Bla,1mm,30u,G,SMD-164 | LOTES CO LTD | APCI0261-P001C |  |  | PWA BOM |
| 19 | TLRH3APTTE20L0F | 2 | 0 | RES,20mOhm,+/-1%,2W,G,SMD2512 | KOA SPEER ELECTRONICS, INC. | TLRH3APTTE20L0F | G | (-)PBAR65,PAAR65 | PWA BOM |
|  | LRMAP2512-R02FT4 |  |  | RES,20mOhm,+/-1%,2W,G,SMD2512 | INTERNATIONAL RESISTIVE COMPANY, INC. | LRMAP2512-R02FT4 |  |  | PWA BOM |
| 20 | SLW1TTE50L0F | 4 | 0 | RES,50mOhm,+/-1%,1.5W,G,SMD2512 | KOA | SLW1TTE50L0F | G | (-)PBER65,PAFR65,PAER65,PBFR66 | PWA BOM |
|  | LRMAP2512-R05FT4 |  |  | RES,50mOhm,+/-1%,1.5W,G,SMD2512 | INTERNATIONAL RESISTIVE COMPANY, INC. | LRMAP2512-R05FT4 |  |  | PWA BOM |
| 21 | RN731ETTP3160B25 | 2 | 0 | RES,316 Ohm,+/-0.1%,1/16W,G,SMD0402 | KOA SPEER ELECTRONICS, INC. | RN731ETTP3160B25 | G | (-)PBMR34,PAMR34 | PWA BOM |
| 22 | SLW1TTE75L0F | 2 | 0 | RES,75mOhm,+/-1%,1.5W,G,SMD2512 | KOA | SLW1TTE75L0F | G | (-)PBMR65,PAMR65 | PWA BOM |
|  | LRMAP2512-R075FT4 |  |  | RES,75mOhm,+/-1%,1.5W,G,SMD2512 | INTERNATIONAL RESISTIVE COMPANY, INC. | LRMAP2512-R075FT4 |  |  | PWA BOM |
| 23 | 340108S00-600-G | 2 | 0 | POWER9 CPU Socket for LGA3899-HYBRID | FOXCONN TECHNOLOGY CO.,LTD. | PE38993-51BC0-1H | G | (-)U1,U10 | PWA BOM |
| OOOOOOOOOOOOOOOOOOOOOOOOOOOOOOOOOOOOOOOOOOOOOOOOOOOOOOOOOOOOOOOOOOOOOOOOOOOOOOOOOOOOOOOOOO | OOOOOOOOOOOOOOOOOOOOOOOOOOOOOOOOOOOOOOOOOOOOOOOOOOOOOOOOOOOOOOOOOOOOOOOOOOOOOOOOOOOOOOOOOO | OOOOOOOOOOOOOOOOOOOOOOOOOOOOOOOOOOOOOOOOOOOOOOOOOOOOOOOOOOOOOOOOOOOOOOOOOOOOOOOOOOOOOOOOOO | OOOOOOOOOOOOOOOOOOOOOOOOOOOOOOOOOOOOOOOOOOOOOOOOOOOOOOOOOOOOOOOOOOOOOOOOOOOOOOOOOOOOOOOOOO | OOOOOOOOOOOOOOOOOOOOOOOOOOOOOOOOOOOOOOOOOOOOOOOOOOOOOOOOOOOOOOOOOOOOOOOOOOOOOOOOOOOOOOOOOO | OOOOOOOOOOOOOOOOOOOOOOOOOOOOOOOOOOOOOOOOOOOOOOOOOOOOOOOOOOOOOOOOOOOOOOOOOOOOOOOOOOOOOOOOOO | OOOOOOOOOOOOOOOOOOOOOOOOOOOOOOOOOOOOOOOOOOOOOOOOOOOOOOOOOOOOOOOOOOOOOOOOOOOOOOOOOOOOOOOOOO | OOOOOOOOOOOOOOOOOOOOOOOOOOOOOOOOOOOOOOOOOOOOOOOOOOOOOOOOOOOOOOOOOOOOOOOOOOOOOOOOOOOOOOOOOO | OOOOOOOOOOOOOOOOOOOOOOOOOOOOOOOOOOOOOOOOOOOOOOOOOOOOOOOOOOOOOOOOOOOOOOOOOOOOOOOOOOOOOOOOOO | OOOOOOOOOOOOOOOOOOOOOOOOOOOOOOOOOOOOOOOOOOOOOOOOOOOOOOOOOOOOOOOOOOOOOOOOOOOOOOOOOOOOOOOOOO |
| TLA Parts Change |  |  |  |  |  |  |  |  |  |
| Item | Foxconn P/N | Qty | Part Description | Manufacturer Full Name | Manufacturer P/N | RoHS | Location | Remark | BOM |
| BOM Change List Date:Thu Aug 31 10:34:13 GMT+08:00 2017 |  |  |  |  |  |  |  |  |  |
| New BOM file : E:\barreleye g2\0830\foxbis\BG2 0831.xls |  |  |  |  |  |  |  |  |  |
| Old BOM file : E:\barreleye g2\0830\foxbis\BG2 0825.xls |  |  |  |  |  |  |  |  |  |
| ##### Add Parts |  |  |  |  |  |  |  |  |  |
| Item | Location | Qty | Foxconn P/N | Part Description | Manufacturer Full Name | Manufacturer P/N | RoHS | Sheet |  |
| ##### Remove Parts |  |  |  |  |  |  |  |  |  |
| Item | Location | Qty | Foxconn P/N | Part Description | Manufacturer Full Name | Manufacturer P/N | RoHS | Sheet |  |
| ##### Change Parts |  |  |  |  |  |  |  |  |  |
| Item | Location | Qty | Foxconn P/N | Part Description | Manufacturer Full Name | Manufacturer P/N | RoHS | Sheet | Remark |
| 1 | DIMM01,DIMM03,DIMM05,DIMM07,DIMM08,DIMM10,DIMM12,DIMM14,DIMM17,DIMM19,DIMM21,DIMM23,DIMM24,DIMM26,DIMM28,DIMM30 | 16 | 34021BD00-G78-G | CONN,DDR IV,V/T,1.2V,Bla,0.85mm,15u,G,SMD-288 | FCI CONNECTORS HONGKONG LTD. | 10140702-0301K11LF | G | PWA BOM | In New BOM |
|  |  |  | ADDR0245-P009C | CONN,DDR IV,V/T,1.2V,Bla,0.85mm,15u,G,SMD-288 | LOTES CO LTD | ADDR0245-P009C | G | PWA BOM | In New BOM |
|  |  |  | 34021CF00-600-G | Memory Connector,AH58897-T2B21-3F,DDR IV,288,SMD,THERMOPLASTIC,0.85mm,15u",Black,G | FOXCONN TECHNOLOGY CO.,LTD. | AH58897-T2B21-3F | G | PWA BOM | In New BOM |
|  |  |  | 2042451003 | CONN,2042451003,DDR IV,V/T,1.2V,288,SMD | MOLEX INCORPORATED | 2042451003 | G | PWA BOM | In New BOM |
|  | DIMM01,DIMM03,DIMM05,DIMM07,DIMM08,DIMM10,DIMM12,DIMM14,DIMM17,DIMM19,DIMM21,DIMM23,DIMM24,DIMM26,DIMM28,DIMM30 | 16 | 34021BD00-G78-G | CONN,DDR IV,V/T,1.2V,Bla,0.85mm,15u,G,SMD-288 | FCI CONNECTORS HONGKONG LTD. | 10140702-0301K11LF | G | PWA BOM | In Old BOM |
|  |  |  | ADDR0245-P009C | CONN,DDR IV,V/T,1.2V,Bla,0.85mm,15u,G,SMD-288 | LOTES CO LTD | ADDR0245-P009C | G | PWA BOM | In Old BOM |
|  |  |  | 34021CF00-600-G | Memory Connector,AH58897-T2B21-3F,DDR IV,288,SMD,THERMOPLASTIC,0.85mm,15u",Black,G | FOXCONN TECHNOLOGY CO.,LTD. | AH58897-T2B21-3F | G | PWA BOM | In Old BOM |
|  |  |  | 2042451003 | CONN,2042451004,DDR IV,V/T,1.2V,288,SMD | MOLEX INCORPORATED | 2042451004 | G | PWA BOM | In Old BOM |
| 2 | PHAR35 | 1 | 610113D00-017-G | RES,10.5KOhm,+/-1%,1/16W,G,SMD0402 | KOA SPEER ELECTRONICS, INC. | RK73H1ETTP1052F | G | PWA BOM | In New BOM |
|  |  |  | 610113D00-011-G | RES,10.5KOhm,+/-1%,1/16W,G,SMD0402 | YAGEO CORPORATION COMPONENT | RC0402FR-0710K5L | G | PWA BOM | In New BOM |
|  |  |  | 610113D00-012-G | RES,10.5KOhm,+/-1%,1/16W,G,SMD0402 | WALSIN TECHNOLOGY CORPORATION | WR04X1052FTL | G | PWA BOM | In New BOM |
|  |  |  | 610113D00-044-G | RES,10.5KOhm,+/-1%,1/16W,G,SMD0402 | TA-I TECHNOLOGY CO., LTD | RM04FTN1052 | G | PWA BOM | In New BOM |
|  | PHAR35 | 1 | 61011PE00-017-G | RES,8.87KOhm,+/-1%,1/16W,G,SMD0402 | KOA SPEER ELECTRONICS, INC. | RK73H1ETTP8871F | G | PWA BOM | In Old BOM |
|  |  |  | 61011PE00-012-G | RES,8.87KOhm,+/-1%,1/16W,G,SMD0402 | WALSIN TECHNOLOGY CORPORATION | WR04X8871FTL | G | PWA BOM | In Old BOM |
|  |  |  | 61011PE00-011-G | RES,8.87KOhm,+/-1%,1/16W,G,SMD0402 | YAGEO CORPORATION COMPONENT | RC0402FR-078K87L | G | PWA BOM | In Old BOM |
|  |  |  | 61011PE00-044-G | RES,8.87KOhm,+/-1%,1/16W,G,SMD0402 | TA-I TECHNOLOGY CO., LTD | RM04FTN8871 | G | PWA BOM | In Old BOM |
| ##### Change Revision |  |  |  |  |  |  |  |  |  |
| Sheet | REV OF BOM | CUSTOMER | CUSTOMER P/N | PWA PN | PWA DESCRIPTION | PWA REV | DATE | Remark |  |
| OOOOOOOOOOOOOOOOOOOOOOOOOOOOOOOOOOOOOOOOOOOOOOOOOOOOOOOOOOOOOOOOOOOOOOOOOOOOOOOOOOOOOOOOOO | OOOOOOOOOOOOOOOOOOOOOOOOOOOOOOOOOOOOOOOOOOOOOOOOOOOOOOOOOOOOOOOOOOOOOOOOOOOOOOOOOOOOOOOOOO | OOOOOOOOOOOOOOOOOOOOOOOOOOOOOOOOOOOOOOOOOOOOOOOOOOOOOOOOOOOOOOOOOOOOOOOOOOOOOOOOOOOOOOOOOO | OOOOOOOOOOOOOOOOOOOOOOOOOOOOOOOOOOOOOOOOOOOOOOOOOOOOOOOOOOOOOOOOOOOOOOOOOOOOOOOOOOOOOOOOOO | OOOOOOOOOOOOOOOOOOOOOOOOOOOOOOOOOOOOOOOOOOOOOOOOOOOOOOOOOOOOOOOOOOOOOOOOOOOOOOOOOOOOOOOOOO | OOOOOOOOOOOOOOOOOOOOOOOOOOOOOOOOOOOOOOOOOOOOOOOOOOOOOOOOOOOOOOOOOOOOOOOOOOOOOOOOOOOOOOOOOO | OOOOOOOOOOOOOOOOOOOOOOOOOOOOOOOOOOOOOOOOOOOOOOOOOOOOOOOOOOOOOOOOOOOOOOOOOOOOOOOOOOOOOOOOOO | OOOOOOOOOOOOOOOOOOOOOOOOOOOOOOOOOOOOOOOOOOOOOOOOOOOOOOOOOOOOOOOOOOOOOOOOOOOOOOOOOOOOOOOOOO | OOOOOOOOOOOOOOOOOOOOOOOOOOOOOOOOOOOOOOOOOOOOOOOOOOOOOOOOOOOOOOOOOOOOOOOOOOOOOOOOOOOOOOOOOO | OOOOOOOOOOOOOOOOOOOOOOOOOOOOOOOOOOOOOOOOOOOOOOOOOOOOOOOOOOOOOOOOOOOOOOOOOOOOOOOOOOOOOOOOOO |
| Second Source Change |  |  |  |  |  |  |  |  |  |
| Item | Location | Change Type | Foxconn P/N | Part Description | Manufacturer Full Name | Manufacturer P/N | RoHS | Sheet |  |
| OOOOOOOOOOOOOOOOOOOOOOOOOOOOOOOOOOOOOOOOOOOOOOOOOOOOOOOOOOOOOOOOOOOOOOOOOOOOOOOOOOOOOOOOOO | OOOOOOOOOOOOOOOOOOOOOOOOOOOOOOOOOOOOOOOOOOOOOOOOOOOOOOOOOOOOOOOOOOOOOOOOOOOOOOOOOOOOOOOOOO | OOOOOOOOOOOOOOOOOOOOOOOOOOOOOOOOOOOOOOOOOOOOOOOOOOOOOOOOOOOOOOOOOOOOOOOOOOOOOOOOOOOOOOOOOO | OOOOOOOOOOOOOOOOOOOOOOOOOOOOOOOOOOOOOOOOOOOOOOOOOOOOOOOOOOOOOOOOOOOOOOOOOOOOOOOOOOOOOOOOOO | OOOOOOOOOOOOOOOOOOOOOOOOOOOOOOOOOOOOOOOOOOOOOOOOOOOOOOOOOOOOOOOOOOOOOOOOOOOOOOOOOOOOOOOOOO | OOOOOOOOOOOOOOOOOOOOOOOOOOOOOOOOOOOOOOOOOOOOOOOOOOOOOOOOOOOOOOOOOOOOOOOOOOOOOOOOOOOOOOOOOO | OOOOOOOOOOOOOOOOOOOOOOOOOOOOOOOOOOOOOOOOOOOOOOOOOOOOOOOOOOOOOOOOOOOOOOOOOOOOOOOOOOOOOOOOOO | OOOOOOOOOOOOOOOOOOOOOOOOOOOOOOOOOOOOOOOOOOOOOOOOOOOOOOOOOOOOOOOOOOOOOOOOOOOOOOOOOOOOOOOOOO | OOOOOOOOOOOOOOOOOOOOOOOOOOOOOOOOOOOOOOOOOOOOOOOOOOOOOOOOOOOOOOOOOOOOOOOOOOOOOOOOOOOOOOOOOO | OOOOOOOOOOOOOOOOOOOOOOOOOOOOOOOOOOOOOOOOOOOOOOOOOOOOOOOOOOOOOOOOOOOOOOOOOOOOOOOOOOOOOOOOOO |
| Master Materials Change |  |  |  |  |  |  |  |  |  |
| Item | Foxconn P/N | Orig._Usage | New_Usage | Part Description | Manufacturer Full Name | Manufacturer P/N | RoHS | Location | Sheet |
| 1 | 61011PE00-017-G | 2 | 1 | RES,8.87KOhm,+/-1%,1/16W,G,SMD0402 | KOA SPEER ELECTRONICS, INC. | RK73H1ETTP8871F | G | (-)PHAR35 | PWA BOM |
|  | 61011PE00-012-G |  |  | RES,8.87KOhm,+/-1%,1/16W,G,SMD0402 | WALSIN TECHNOLOGY CORPORATION | WR04X8871FTL |  |  | PWA BOM |
|  | 61011PE00-011-G |  |  | RES,8.87KOhm,+/-1%,1/16W,G,SMD0402 | YAGEO CORPORATION COMPONENT | RC0402FR-078K87L |  |  | PWA BOM |
|  | 61011PE00-044-G |  |  | RES,8.87KOhm,+/-1%,1/16W,G,SMD0402 | TA-I TECHNOLOGY CO., LTD | RM04FTN8871 |  |  | PWA BOM |
| 2 | 610113D00-017-G | 0 | 1 | RES,10.5KOhm,+/-1%,1/16W,G,SMD0402 | KOA SPEER ELECTRONICS, INC. | RK73H1ETTP1052F | G | (+)PHAR35 | PWA BOM |
|  | 610113D00-011-G |  |  | RES,10.5KOhm,+/-1%,1/16W,G,SMD0402 | YAGEO CORPORATION COMPONENT | RC0402FR-0710K5L |  |  | PWA BOM |
|  | 610113D00-012-G |  |  | RES,10.5KOhm,+/-1%,1/16W,G,SMD0402 | WALSIN TECHNOLOGY CORPORATION | WR04X1052FTL |  |  | PWA BOM |
|  | 610113D00-044-G |  |  | RES,10.5KOhm,+/-1%,1/16W,G,SMD0402 | TA-I TECHNOLOGY CO., LTD | RM04FTN1052 |  |  | PWA BOM |
| OOOOOOOOOOOOOOOOOOOOOOOOOOOOOOOOOOOOOOOOOOOOOOOOOOOOOOOOOOOOOOOOOOOOOOOOOOOOOOOOOOOOOOOOOO | OOOOOOOOOOOOOOOOOOOOOOOOOOOOOOOOOOOOOOOOOOOOOOOOOOOOOOOOOOOOOOOOOOOOOOOOOOOOOOOOOOOOOOOOOO | OOOOOOOOOOOOOOOOOOOOOOOOOOOOOOOOOOOOOOOOOOOOOOOOOOOOOOOOOOOOOOOOOOOOOOOOOOOOOOOOOOOOOOOOOO | OOOOOOOOOOOOOOOOOOOOOOOOOOOOOOOOOOOOOOOOOOOOOOOOOOOOOOOOOOOOOOOOOOOOOOOOOOOOOOOOOOOOOOOOOO | OOOOOOOOOOOOOOOOOOOOOOOOOOOOOOOOOOOOOOOOOOOOOOOOOOOOOOOOOOOOOOOOOOOOOOOOOOOOOOOOOOOOOOOOOO | OOOOOOOOOOOOOOOOOOOOOOOOOOOOOOOOOOOOOOOOOOOOOOOOOOOOOOOOOOOOOOOOOOOOOOOOOOOOOOOOOOOOOOOOOO | OOOOOOOOOOOOOOOOOOOOOOOOOOOOOOOOOOOOOOOOOOOOOOOOOOOOOOOOOOOOOOOOOOOOOOOOOOOOOOOOOOOOOOOOOO | OOOOOOOOOOOOOOOOOOOOOOOOOOOOOOOOOOOOOOOOOOOOOOOOOOOOOOOOOOOOOOOOOOOOOOOOOOOOOOOOOOOOOOOOOO | OOOOOOOOOOOOOOOOOOOOOOOOOOOOOOOOOOOOOOOOOOOOOOOOOOOOOOOOOOOOOOOOOOOOOOOOOOOOOOOOOOOOOOOOOO | OOOOOOOOOOOOOOOOOOOOOOOOOOOOOOOOOOOOOOOOOOOOOOOOOOOOOOOOOOOOOOOOOOOOOOOOOOOOOOOOOOOOOOOOOO |
| TLA Parts Change |  |  |  |  |  |  |  |  |  |
| Item | Foxconn P/N | Qty | Part Description | Manufacturer Full Name | Manufacturer P/N | RoHS | Location | Remark | BOM |
|  | 610118800-024-G | 需要再看看 |  |  |  |  |  |  |  |
| BOM Change List Date:Fri Sep 08 17:04:55 GMT+08:00 2017 |  |  |  |  |  |  |  |  |  |
| New BOM file : E:\barreleye g2\0905\MB FOXBIS\BG2 0906.xls |  |  |  |  |  |  |  |  |  |
| Old BOM file : E:\barreleye g2\0905\MB FOXBIS\BG2 0831.xls |  |  |  |  |  |  |  |  |  |
| ##### Add Parts |  |  |  |  |  |  |  |  |  |
| Item | Location | Qty | Foxconn P/N | Part Description | Manufacturer Full Name | Manufacturer P/N | RoHS | Sheet |  |
| ##### Remove Parts |  |  |  |  |  |  |  |  |  |
| Item | Location | Qty | Foxconn P/N | Part Description | Manufacturer Full Name | Manufacturer P/N | RoHS | Sheet |  |
| ##### Change Parts |  |  |  |  |  |  |  |  |  |
| Item | Location | Qty | Foxconn P/N | Part Description | Manufacturer Full Name | Manufacturer P/N | RoHS | Sheet | Remark |
| 1 | PCB | 1 | 0101FBQ00-000-G | PCB,Zaius-MB PVT-X04,OSP,Gre,22L,22.20*13.00,G | GOLD CIRCUIT ELECTRONICS LTD. | 0101FBQ00-000-G | G | PWA BOM | In New BOM |
|  |  |  | 0101FBQ00-000-G | PCB,Zaius-MB PVT-X04,OSP,Gre,22L,22.20*13.00,G | ZHUHAI FOUNDER PRINTED CIRCUIT BOARD（HK） DEVELOPMENT LIMITED | 0101FBQ00-000-G | G | PWA BOM | In New BOM |
|  | PCB | 1 | 0101FBQ00-000-G | PCB,Zaius-MB PVT-X04,OSP,Gre,22L,22.20*13.00,G | GOLD CIRCUIT ELECTRONICS LTD. | 0101FBQ00-000-G | G | PWA BOM | In Old BOM |
|  |  |  | 0101FBQ00-000-G | PCB,Zaius-MB PVT-X04,OSP,Gre,22L,22.20*13.00,G | ZHUHAI FOUNDER PRINTED CIRCUIT BOARD（HK） DEVELOPMENT LIMITED | 0101FBQ00-000-G | G | PWA BOM | In Old BOM |
|  |  |  | 0101FBQ00-000-G | PCB,Zaius-MB PVT-X04,OSP,Gre,22L,22.20*13.00,G | ISUPETASYS CO., LTD | 0101FBQ00-000-G | G | PWA BOM | In Old BOM |
| 3 | PBMR54,PBFR54,PBER54,PBAR54,PAMR54,PAFR54,PAER54,PAAR54 | 8 | 61011MC02-017-G | Res,374 Ohm,+/-1%,1/16W,G,SMD0402 | KOA SPEER ELECTRONICS, INC. | RK73H1ETTP3740F | G | PWA BOM | In New BOM |
|  |  |  | 61011MC00-011-G | RES,374 Ohm,+/-1%,1/16W,G,SMD0402 | YAGEO CORPORATION COMPONENT | RC0402FR-07374RL | G | PWA BOM | In New BOM |
|  |  |  | 61011MC00-024-G | RES,thick film,374Ohm,+/-1%,1/16W,SMD0402,G | PANASONIC INDUSTRIAL CO.,LTD. | ERJ2RKF3740X | G | PWA BOM | In New BOM |
|  |  |  | 61011MC00-029-G | RES,thick film,374Ohm,+/-1%,1/16W,SMD0402,G | VISHAY ENTER TECHNO LOGY.INC | CRCW0402374RFKED | G | PWA BOM | In New BOM |
|  | PBMR54,PBFR54,PBER54,PBAR54,PAMR54,PAFR54,PAER54,PAAR54 | 8 | 61011MC02-017-G | Res,374 Ohm,+/-1%,1/16W,G,SMD0402 | KOA SPEER ELECTRONICS, INC. | RK73H1ETTP3740F | G | PWA BOM | In Old BOM |
|  |  |  | 61011MC00-024-G | RES,thick film,374Ohm,+/-1%,1/16W,SMD0402,G | PANASONIC INDUSTRIAL CO.,LTD. | ERJ2RKF3740X | G | PWA BOM | In Old BOM |
|  |  |  | 61011MC00-029-G | RES,thick film,374Ohm,+/-1%,1/16W,SMD0402,G | VISHAY ENTER TECHNO LOGY.INC | CRCW0402374RFKED | G | PWA BOM | In Old BOM |
| 4 | PUAC4,PSAC4,PRAC4,PQAC4,PPAC4,PIAC4,PFAC4,PEAC4,PUAC5,PSAC5,PRAC5,PQAC5,PPAC5,PIAC5,PFAC5,PEAC5,PUAC6,PSAC6,PRAC6,PQAC6,PPAC6,PIAC6,PFAC6,PEAC6 | 24 | 62011DD00-015-G | CAP,22uF,+/-10%,X6S,6.3V,G,SMD1206 | MURATA ELEC. NORTH AMERICA | GRM31CC80J226K | G | PWA BOM | In New BOM |
|  | PUAC4,PSAC4,PRAC4,PQAC4,PPAC4,PIAC4,PFAC4,PEAC4,PUAC5,PSAC5,PRAC5,PQAC5,PPAC5,PIAC5,PFAC5,PEAC5,PUAC6,PSAC6,PRAC6,PQAC6,PPAC6,PIAC6,PFAC6,PEAC6 | 24 | 62011DD00-015-G | CAP,22uF,+/-10%,X6S,6.3V,G,SMD1206 | MURATA ELEC. NORTH AMERICA | GRM31CC80J226K | G | PWA BOM | In Old BOM |
|  |  |  | 62011DD00-011-G | CAP,MLCC,22uF,+/-10%,X6S,6.3V,SMD1206,G | YAGEO CORPORATION COMPONENT | CC1206KKX6S5BB226 | G | PWA BOM | In Old BOM |
| 5 | Q5,Q7 | 2 | 510406000-185-G | MOS P,FDD6685,30V,11A,30m@4.5V,G,TO252-3,SMD | FAIRCHILD SEMICONDUCTOR CORP | FDD6685 | G | PWA BOM | In New BOM |
|  |  |  | 510410G00-221-G | MOS P,IPD042P03L3 G,-30V,-70A,TO-252-3,SMD | INFINEON TECHNOLOGIES CORP. | IPD042P03L3 G | G | PWA BOM | In New BOM |
|  |  |  | 51040WQ00-131-G | MOSFET-P,TJ40S04M3L,-40V,-40A,9.1mOhm@Vgs=-10V,13mOhm@Vgs=-6V,SMD,3P,G | TOSHIBA ELECTRONICS ASIA LTD | TJ40S04M3L | G | PWA BOM | In New BOM |
|  | Q5,Q7 | 2 | 510406000-185-G | MOS P,FDD6685,30V,11A,30m@4.5V,G,TO252-3,SMD | FAIRCHILD SEMICONDUCTOR CORP | FDD6685 | G | PWA BOM | In Old BOM |
|  |  |  | 510410800-221-G | MOS P,IPD042P03L3G,-30V,-70A,4.2m@-10V,G,TO-252-3,SMD | INFINEON TECHNOLOGIES CORP. | IPD042P03L3G | G | PWA BOM | In Old BOM |
|  |  |  | 51040WQ00-131-G | MOSFET-P,TJ40S04M3L,-40V,-40A,9.1mOhm@Vgs=-10V,13mOhm@Vgs=-6V,SMD,3P,G | TOSHIBA ELECTRONICS ASIA LTD | TJ40S04M3L | G | PWA BOM | In Old BOM |
| 6 | R31,R40,R53,R393,R402,R416 | 6 | 61100V600-017-G | RES,200 Ohm,+/-0.1%,1/16W,G,SMD0402 | KOA SPEER ELECTRONICS, INC. | RN731ETTP2000B25 | G | PWA BOM | In New BOM |
|  |  |  | 61100V600-011-G | RES,200 Ohm,+/-0.1%,1/16W,G,SMD0402 | YAGEO CORPORATION COMPONENT | RT0402BRD07200RL | G | PWA BOM | In New BOM |
|  |  |  | 61100V600-044-G | RES,200 Ohm,+/-0.1%,1/16W,G,SMD0402 | TA-I TECHNOLOGY CO., LTD | RB04BTP2000 | G | PWA BOM | In New BOM |
|  |  |  | 61100V600-012-G | RES,200 Ohm,+/-0.1%,1/16W,G,SMD0402 | WALSIN TECHNOLOGY CORPORATION | WF04U2000BTL | G | PWA BOM | In New BOM |
|  | R31,R40,R53,R393,R402,R416 | 6 | 61100V600-017-G | RES,200 Ohm,+/-0.1%,1/16W,G,SMD0402 | KOA SPEER ELECTRONICS, INC. | RN731ETTP2000B25 | G | PWA BOM | In Old BOM |
|  |  |  | 61100V600-012-G | RES,200 Ohm,+/-0.1%,1/16W,G,SMD0402 | WALSIN TECHNOLOGY CORPORATION | WF04U2000BTL | G | PWA BOM | In Old BOM |
|  |  |  | 61100V600-011-G | RES,200 Ohm,+/-0.1%,1/16W,G,SMD0402 | YAGEO CORPORATION COMPONENT | RT0402BRD07200RL | G | PWA BOM | In Old BOM |
| 7 | R790,R1154,R1157,R1237 | 4 | 61100BN00-017-G | RES,100KOhm,+/-1%,1/16W,G,SMD0402 | KOA SPEER ELECTRONICS, INC. | RN731ETTP1003F25 | G | PWA BOM | In New BOM |
|  |  |  | 61100BN00-011-G | RES,100KOhm,+/-1%,1/16W,G,SMD0402 | YAGEO CORPORATION COMPONENT | RT0402FRD07100KL | G | PWA BOM | In New BOM |
|  |  |  | 61100BN00-044-G | RES,100KOhm,+/-1%,1/16W,G,SMD0402 | TA-I TECHNOLOGY CO., LTD | RB04FTP1003 | G | PWA BOM | In New BOM |
|  |  |  | 61100BN00-012-G | RES,100KOhm,+/-1%,1/16W,G,SMD0402 | WALSIN TECHNOLOGY CORPORATION | WF04U1003FTL | G | PWA BOM | In New BOM |
|  | R790,R1154,R1157,R1237 | 4 | 61100BN00-017-G | RES,100KOhm,+/-1%,1/16W,G,SMD0402 | KOA SPEER ELECTRONICS, INC. | RN731ETTP1003F25 | G | PWA BOM | In Old BOM |
|  |  |  | 61100BN00-012-G | RES,100KOhm,+/-1%,1/16W,G,SMD0402 | WALSIN TECHNOLOGY CORPORATION | WF04U1003FTL | G | PWA BOM | In Old BOM |
|  |  |  | 61100BN00-011-G | RES,100KOhm,+/-1%,1/16W,G,SMD0402 | YAGEO CORPORATION COMPONENT | RT0402FRD07100KL | G | PWA BOM | In Old BOM |
| 8 | R961,R962,R963,R964,R965,R967,R968,R969,R970,R975,R976,R977,R978,R985,R986,R988,R989,R992,R1003 | 19 | 61100C600-017-G | RES,1KOhm,+/-0.5%,1/16W,G,SMD0402 | KOA SPEER ELECTRONICS, INC. | RN731ETTP1001D25 | G | PWA BOM | In New BOM |
|  |  |  | 61100C603-024-G | RES,1KOhm,+/-0.5%,1/16W,G,SMD0402 | PANASONIC INDUSTRIAL CO.,LTD. | ERA2AED102X | G | PWA BOM | In New BOM |
|  |  |  | 61100C600-029-G | RES,1KOhm,+/-0.5%,1/16W,G,SMD0402 | VISHAY ENTER TECHNO LOGY.INC | MCS04020D1001DE000 | G | PWA BOM | In New BOM |
|  |  |  | 61100C600-011-G | RES,1KOhm,+/-0.5%,1/16W,G,SMD0402 | YAGEO CORPORATION COMPONENT | RT0402DRE071KL | G | PWA BOM | In New BOM |
|  | R961,R962,R963,R964,R965,R967,R968,R969,R970,R975,R976,R977,R978,R985,R986,R988,R989,R992,R1003 | 19 | 61100C600-017-G | RES,1KOhm,+/-0.5%,1/16W,G,SMD0402 | KOA SPEER ELECTRONICS, INC. | RN731ETTP1001D25 | G | PWA BOM | In Old BOM |
|  |  |  | 61100C603-024-G | RES,1KOhm,+/-0.5%,1/16W,G,SMD0402 | PANASONIC INDUSTRIAL CO.,LTD. | ERA2AED102X | G | PWA BOM | In Old BOM |
|  |  |  | 61100C600-029-G | RES,1KOhm,+/-0.5%,1/16W,G,SMD0402 | VISHAY ENTER TECHNO LOGY.INC | MCS04020D1001DE000 | G | PWA BOM | In Old BOM |
| 9 | R1092,R1115 | 2 | 61100QH00-017-G | RES,510 Ohm,+/-0.1%,1/16W,G,SMD0402 | KOA SPEER ELECTRONICS, INC. | RN731ETTP5100B25 | G | PWA BOM | In New BOM |
|  |  |  | 61100QH00-011-G | RES,510 Ohm,+/-0.1%,1/16W,G,SMD0402 | YAGEO CORPORATION COMPONENT | RT0402BRD07510RL | G | PWA BOM | In New BOM |
|  |  |  | 61100QH00-044-G | RES,510 Ohm,+/-0.1%,1/16W,G,SMD0402 | TA-I TECHNOLOGY CO., LTD | RB04BTP5100 | G | PWA BOM | In New BOM |
|  |  |  | 61100QH00-012-G | RES,510 Ohm,+/-0.1%,1/16W,G,SMD0402 | WALSIN TECHNOLOGY CORPORATION | WF04U5100BTL | G | PWA BOM | In New BOM |
|  | R1092,R1115 | 2 | 61100QH00-017-G | RES,510 Ohm,+/-0.1%,1/16W,G,SMD0402 | KOA SPEER ELECTRONICS, INC. | RN731ETTP5100B25 | G | PWA BOM | In Old BOM |
|  |  |  | 61100QH00-012-G | RES,510 Ohm,+/-0.1%,1/16W,G,SMD0402 | WALSIN TECHNOLOGY CORPORATION | WF04U5100BTL | G | PWA BOM | In Old BOM |
|  |  |  | 61100QH00-011-G | RES,510 Ohm,+/-0.1%,1/16W,G,SMD0402 | YAGEO CORPORATION COMPONENT | RT0402BRD07510RL | G | PWA BOM | In Old BOM |
| 10 | R1483 | 1 | 61100QT01-017-G | RES,10 Ohm,+/-0.5%,1/16W,G,SMD0402 | KOA SPEER ELECTRONICS, INC. | RN731ETTP10R0D25 | G | PWA BOM | In New BOM |
|  |  |  | 61100QT00-011-G | RES,10 Ohm,+/-0.5%,1/16W,G,SMD0402 | YAGEO CORPORATION COMPONENT | RT0402DRE0710RL | G | PWA BOM | In New BOM |
|  |  |  | 61100QT00-012-G | RES,10 Ohm,+/-0.5%,1/16W,G,SMD0402 | WALSIN TECHNOLOGY CORPORATION | WF04T10R0DTL | G | PWA BOM | In New BOM |
|  | R1483 | 1 | 61100QT01-017-G | RES,10 Ohm,+/-0.5%,1/16W,G,SMD0402 | KOA SPEER ELECTRONICS, INC. | RN731ETTP10R0D25 | G | PWA BOM | In Old BOM |
| 11 | R1492 | 1 | 610118800-017-G | RES,499KOhm,+/-1%,1/8W,G,SMD0805 | KOA SPEER ELECTRONICS, INC. | RK73H2ATTD4993F | G | PWA BOM | In New BOM |
|  |  |  | 610118800-024-G | RES,499KOhm,+/-1%,1/8W,G,SMD0805 | PANASONIC INDUSTRIAL CO.,LTD. | ERJ6ENF4993V | G | PWA BOM | In New BOM |
|  |  |  | RC0805FR-07499KL | RES,499KOhm,+/-1%,1/8W,G,SMD0805 | YAGEO CORPORATION COMPONENT | RC0805FR-07499KL | G | PWA BOM | In New BOM |
|  | R1492 | 1 | 610118800-017-G | RES,499KOhm,+/-1%,1/8W,G,SMD0805 | KOA SPEER ELECTRONICS, INC. | RK73H2ATTD4993F | G | PWA BOM | In Old BOM |
|  |  |  | 610118800-024-G | RES,499KOhm,+/-1%,1/8W,G,SMD0805 | PANASONIC INDUSTRIAL CO.,LTD. | ERJ6ENF4993V | G | PWA BOM | In Old BOM |
| 12 | R1769,R1770 | 2 | 610130300-017-G | RES,60.4 Ohm,+/-1%,1/20W,G,SMD0201 | KOA SPEER ELECTRONICS, INC. | RK73H1HTTC60R4F | G | PWA BOM | In New BOM |
|  |  |  | 610130300-044-G | RES,thick film,60.4Ohm,+/-1%,1/20W,SMD0201,G | TA-I TECHNOLOGY CO., LTD | RM02FTN60R4 | G | PWA BOM | In New BOM |
|  |  |  | 610130300-011-G | RES,thick film,60.4Ohm,+/-1%,1/20W,SMD0201,G | YAGEO CORPORATION COMPONENT | RC0201FR-0760R4L | G | PWA BOM | In New BOM |
|  |  |  | 610130300-012-G | RES,thick film,60.4Ohm,+/-1%,1/20W,SMD0201,G | WALSIN TECHNOLOGY CORPORATION | WR02X60R4FAL | G | PWA BOM | In New BOM |
|  |  |  | 610130300-029-G | RES,60.4 Ohm,+/-1%,1/20W,G,SMD0201 | VISHAY ENTER TECHNO LOGY.INC | CRCW020160R4FKED | G | PWA BOM | In New BOM |
|  |  |  | 610130300-024-G | RES,60.4 Ohm,+/-1%,1/20W,G,SMD0201 | PANASONIC INDUSTRIAL CO.,LTD. | ERJ1GNF60R4C | G | PWA BOM | In New BOM |
|  | R1769,R1770 | 2 | 610130300-017-G | RES,60.4 Ohm,+/-1%,1/20W,G,SMD0201 | KOA SPEER ELECTRONICS, INC. | RK73H1HTTC60R4F | G | PWA BOM | In Old BOM |
|  |  |  | 610130300-029-G | RES,60.4 Ohm,+/-1%,1/20W,G,SMD0201 | VISHAY ENTER TECHNO LOGY.INC | CRCW020160R4FKED | G | PWA BOM | In Old BOM |
|  |  |  | 610130300-024-G | RES,60.4 Ohm,+/-1%,1/20W,G,SMD0201 | PANASONIC INDUSTRIAL CO.,LTD. | ERJ1GNF60R4C | G | PWA BOM | In Old BOM |
| 13 | U_TMP | 1 | 320403K00-183-G | IC,Temp Sensor,TMP75AIDR,3°C,G,SOIC-8,SMD | TEXAS INSTRUMENTS | TMP75AIDR | G | PWA BOM | In New BOM |
|  |  |  | 320403Q00-173-G | IC,Temp Sensor,DS75S+T&R,3°C,G,SO-8,SMD | MAXIM INTEGRATED PRODUCTS, INC. | DS75S+T&R | G | PWA BOM | In New BOM |
|  |  |  | 320405300-214-G | IC,Temp Sensor,STLM75M2F,±0.5°C,G,SO-8,SMD | ST MICRO ELECTRONICS,INC | STLM75M2F | G | PWA BOM | In New BOM |
|  |  |  | 32040SL00-223-G | IC,Temperature Sensor,NCT75DR2G,G,SOIC-8,SMD | ON SEMICONDUCTOR CORP | NCT75DR2G | G | PWA BOM | In New BOM |
|  |  |  | 32040FL00-031-G | IC,Temperature Sensor,LM75BD,G,SO-8,SMD | NXP SEMICONDUCTORS | LM75BD | G | PWA BOM | In New BOM |
|  | U_TMP | 1 | 320403K00-183-G | IC,Temp Sensor,TMP75AIDR,3°C,G,SOIC-8,SMD | TEXAS INSTRUMENTS | TMP75AIDR | G | PWA BOM | In Old BOM |
|  |  |  | 320404J00-190-G | IC,Temp Sensor,ADT75ARZ-REEL,1°C,G,SOIC-8,SMD | ANALOG DEVICES INC | ADT75ARZ-REEL | G | PWA BOM | In Old BOM |
|  |  |  | 320403Q00-173-G | IC,Temp Sensor,DS75S+T&R,3°C,G,SO-8,SMD | MAXIM INTEGRATED PRODUCTS, INC. | DS75S+T&R | G | PWA BOM | In Old BOM |
|  |  |  | 320405300-214-G | IC,Temp Sensor,STLM75M2F,±0.5°C,G,SO-8,SMD | ST MICRO ELECTRONICS,INC | STLM75M2F | G | PWA BOM | In Old BOM |
|  |  |  | 32040SL00-223-G | IC,Temperature Sensor,NCT75DR2G,G,SOIC-8,SMD | ON SEMICONDUCTOR CORP | NCT75DR2G | G | PWA BOM | In Old BOM |
|  |  |  | 32040FL00-031-G | IC,Temperature Sensor,LM75BD,G,SO-8,SMD | NXP SEMICONDUCTORS | LM75BD | G | PWA BOM | In Old BOM |
| 14 | U170,U174,U180 | 3 | 310109D00-031-G | IC,Gate&Inverter,74LVC1G32GW,1.65~5.5V,G,TSSOP-5,SMD | NXP SEMICONDUCTORS | 74LVC1G32GW | G | PWA BOM | In New BOM |
|  |  |  | 310109E00-223-G | IC,Gate&Inverter,NL17SZ32DFT2G,1.65~5.5V,G,SOT-353-5,SMD | ON SEMICONDUCTOR CORP | NL17SZ32DFT2G | G | PWA BOM | In New BOM |
|  |  |  | TC7SZ32FU,LJ(CT | IC,Gate&Inverter,TC7SZ32FU,1.65~5.5V,G,SSOP-5,SMD | TOSHIBA ELECTRONICS ASIA LTD | TC7SZ32FU,LJ(CT | G | PWA BOM | In New BOM |
|  | U170,U174,U180 | 3 | 310109D00-031-G | IC,Gate&Inverter,74LVC1G32GW,1.65~5.5V,G,TSSOP-5,SMD | NXP SEMICONDUCTORS | 74LVC1G32GW | G | PWA BOM | In Old BOM |
|  |  |  | 310109E00-223-G | IC,Gate&Inverter,NL17SZ32DFT2G,1.65~5.5V,G,SOT-353-5,SMD | ON SEMICONDUCTOR CORP | NL17SZ32DFT2G | G | PWA BOM | In Old BOM |
|  |  |  | 310108600-131-G | IC,Gate&Inverter,TC7SZ32FU,1.65~5.5V,G,SSOP-5,SMD | TOSHIBA ELECTRONICS ASIA LTD | TC7SZ32FU | G | PWA BOM | In Old BOM |
| 15 | U171 | 1 | 31050KL00-031-G | IC,Buffer,74HC75PW,2.0V~6.0V,G,TSSOP-16,SMD | NXP SEMICONDUCTORS | 74HC75PW | G | PWA BOM | In New BOM |
|  |  |  | CD74HC75PWR | IC,Translator,CD74HC75PWR,2V~6V,G,TSSOP-16,SMD | Texas Instruments | CD74HC75PWR | G | PWA BOM | In New BOM |
|  | U171 | 1 | 31050KL00-031-G | IC,Buffer,74HC75PW,2.0V~6.0V,G,TSSOP-16,SMD | NXP SEMICONDUCTORS | 74HC75PW | G | PWA BOM | In Old BOM |
|  |  |  | 311007400-183-G | IC,Translator,CD74HC75PWRG4,2V~6V,G,TSSOP-16,SMD | Texas Instruments | CD74HC75PWRG4 | G | PWA BOM | In Old BOM |
| 16 | Y1 | 1 | 71020SC00-107-G | OSC,24MHz,+/-25ppm,3.3V,15pF,G,SMD | DAISHINKU CORPORATION/DAISHINKU SINGAPORE PTE LTD/KDS | 1XSE024000AR40 | G | PWA BOM | In New BOM |
|  |  |  | SIT1602BI-22-33E | OSC,24MHz,+/-25ppm,3.3V,15pF,G,SMD | SiTime Corporation | SIT1602BI-22-33E-24.000000 | G | PWA BOM | In New BOM |
|  | Y1 | 1 | 71020SC00-107-G | OSC,24MHz,+/-25ppm,3.3V,15pF,G,SMD | DAISHINKU CORPORATION/DAISHINKU SINGAPORE PTE LTD/KDS | 1XSE024000AR40 | G | PWA BOM | In Old BOM |
|  |  |  | SIT1602BI-22-33E | OSC,24MHz,+/-25ppm,3.3V,15pF,G,SMD | SiTime Corporation | SIT1602BI-22-33E-24.000000 |  | PWA BOM | In Old BOM |
| 17 | C1424,C1427,C1451,C1455,C1459,C1464,C1466,C1468,C1470,C1499,C1533,C1577,C1585,C1596 | 14 | 620109S00-023-G | CAP,4.7uF,+/-10%,X7R,10V,G,SMD0805 | TAIYO ELECTRIC IND.CO.LTD | LMK212B7475KG-T | G | PWA BOM | In New BOM |
|  |  |  | 620109S00-026-G | CAP,4.7uF,+/-10%,X7R,10V,G,SMD0805 | SAMSUNG SEMICONDUCTOR | CL21B475KPFNNNE | G | PWA BOM | In New BOM |
|  |  |  | 620109S00-015-G | CAP,4.7uF,+/-10%,X7R,10V,G,SMD0805 | MURATA ELEC. NORTH AMERICA | GRM21BR71A475K | G | PWA BOM | In New BOM |
|  | C1424,C1427,C1451,C1455,C1459,C1464,C1466,C1468,C1470,C1499,C1533,C1577,C1585,C1596 | 14 | 620109S00-015-G | CAP,4.7uF,+/-10%,X7R,10V,G,SMD0805 | MURATA ELEC. NORTH AMERICA | GRM21BR71A475K | G | PWA BOM | In Old BOM |
|  |  |  | 620109S00-023-G | CAP,4.7uF,+/-10%,X7R,10V,G,SMD0805 | TAIYO ELECTRIC IND.CO.LTD | LMK212B7475KG-T | G | PWA BOM | In Old BOM |
|  |  |  | 620109S00-026-G | CAP,4.7uF,+/-10%,X7R,10V,G,SMD0805 | SAMSUNG SEMICONDUCTOR | CL21B475KPFNNNE | G | PWA BOM | In Old BOM |
| 18 | PHAC3 | 1 | 620133600-012-G | CAP,1nF,+/-5%,X7R,100V,G,SMD0805 | WALSIN TECHNOLOGY CORPORATION | 0805B102J101CT | G | PWA BOM | In New BOM |
|  |  |  | 620133600-015-G | CAP,1nF,+/-5%,X7R,100V,G,SMD0805 | MURATA ELEC. NORTH AMERICA | GRM219R72A102JA01D | G | PWA BOM | In New BOM |
|  |  |  | 620133600-026-G | CAP,1nF,+/-5%,X7R,100V,G,SMD0805 | SAMSUNG SEMICONDUCTOR | CL21B102JCANNNC | G | PWA BOM | In New BOM |
|  | PHAC3 | 1 | 620133600-015-G | CAP,1nF,+/-5%,X7R,100V,G,SMD0805 | MURATA ELEC. NORTH AMERICA | GRM219R72A102JA01D | G | PWA BOM | In Old BOM |
|  |  |  | 620133600-012-G | CAP,1nF,+/-5%,X7R,100V,G,SMD0805 | WALSIN TECHNOLOGY CORPORATION | 0805B102J101CT | G | PWA BOM | In Old BOM |
| 19 | U60 | 1 | PCF8523TK/1 | IC,NXP,PCF8523TK/1,G,HVSON-8,SMD | NXP SEMICONDUCTORS | PCF8523TK/1 | G | PWA BOM | In New BOM |
|  | U60 | 1 | 21050P200-031-G | IC,NXP,PCF8523TK,G,HVSON-8,SMD | NXP SEMICONDUCTORS | PCF8523TK | G | PWA BOM | In Old BOM |
| 20 | J_BMC_DEBUG1,J1,J4,J5,J36,J41,J43,J48,J147,J149 | 10 | 87898-0318 | CONN,Header,Pin Header,1X3,V/T,2.54mm,30u,G,SMD-3 | MOLEX INCORPORATED | 87898-0318 | G | PWA BOM | In New BOM |
|  |  |  | 34068LN00-317-G | CONN,Header,Pin Header,1X3,V/T,2.54mm,30u,G,SMD-3 | MOLEX INCORPORATED | 87898-0315 | G | PWA BOM | In New BOM |
|  |  |  | 34068HT00-245-G | CONN,Header,Pin Header,1X3,V/T,Bla,2.54mm,30u,SMD-3 | AMPHENOL SHANGHAI CORP. | G800MU305010EU | G | PWA BOM | In New BOM |
|  |  |  | 34068GU00-309-G | CONN,Header,Pin Header,1X3,V/T,Bla,2.54mm,30u,SMD-3 | SAMTEC INC. | TSM-103-01-S-SV-P-TR | G | PWA BOM | In New BOM |
|  | J_BMC_DEBUG1,J1,J4,J5,J36,J41,J43,J48,J147,J149 | 10 | 34068LN00-317-G | CONN,Header,Pin Header,1X3,V/T,2.54mm,30u,G,SMD-3 | MOLEX INCORPORATED | 87898-0315 | G | PWA BOM | In Old BOM |
|  |  |  | 34068HT00-245-G | CONN,Header,Pin Header,1X3,V/T,Bla,2.54mm,30u,SMD-3 | AMPHENOL SHANGHAI CORP. | G800MU305010EU | G | PWA BOM | In Old BOM |
|  |  |  | 34068GU00-309-G | CONN,Header,Pin Header,1X3,V/T,Bla,2.54mm,30u,SMD-3 | SAMTEC INC. | TSM-103-01-S-SV-P-TR | G | PWA BOM | In Old BOM |
| 21 | J148 | 1 | 87898-0458 | CONN,Pin Header,1X4,V/T,Bla,2.54mm,30u,G,SMD-4 | MOLEX INCORPORATED | 87898-0458 | G | PWA BOM | In New BOM |
|  |  |  | 340672300-317-G | CONN,Pin Header,1X4,V/T,Bla,2.54mm,30u,G,SMD-4 | MOLEX INCORPORATED | 87898-0455 | G | PWA BOM | In New BOM |
|  |  |  | 34068VT00-GRT-G | CONN,Header,Pin Header,1X4,V/T,Bla,2.54mm,30u,G,SMD-4 | PINREX TECHNOLOGY CORP. | 212-91-04SBEJ | G | PWA BOM | In New BOM |
|  |  |  | 340692T00-245-G | CONN,Header,Pin Header,1X4,V/T,Bla,2.54mm,30u,G,SMD-4 | AMPHENOL SHANGHAI CORP. | G800MR304010HR | G | PWA BOM | In New BOM |
|  | J148 | 1 | 340672300-317-G | CONN,Pin Header,1X4,V/T,Bla,2.54mm,30u,G,SMD-4 | MOLEX INCORPORATED | 87898-0455 | G | PWA BOM | In Old BOM |
|  |  |  | 34068VT00-GRT-G | CONN,Header,Pin Header,1X4,V/T,Bla,2.54mm,30u,G,SMD-4 | PINREX TECHNOLOGY CORP. | 212-91-04SBEJ | G | PWA BOM | In Old BOM |
|  |  |  | 340692T00-245-G | CONN,Header,Pin Header,1X4,V/T,Bla,2.54mm,30u,G,SMD-4 | AMPHENOL SHANGHAI CORP. | G800MR304010HR | G | PWA BOM | In Old BOM |
| ##### Change Revision |  |  |  |  |  |  |  |  |  |
| Sheet | REV OF BOM | CUSTOMER | CUSTOMER P/N | PWA PN | PWA DESCRIPTION | PWA REV | DATE | Remark |  |
| OOOOOOOOOOOOOOOOOOOOOOOOOOOOOOOOOOOOOOOOOOOOOOOOOOOOOOOOOOOOOOOOOOOOOOOOOOOOOOOOOOOOOOOOOO | OOOOOOOOOOOOOOOOOOOOOOOOOOOOOOOOOOOOOOOOOOOOOOOOOOOOOOOOOOOOOOOOOOOOOOOOOOOOOOOOOOOOOOOOOO | OOOOOOOOOOOOOOOOOOOOOOOOOOOOOOOOOOOOOOOOOOOOOOOOOOOOOOOOOOOOOOOOOOOOOOOOOOOOOOOOOOOOOOOOOO | OOOOOOOOOOOOOOOOOOOOOOOOOOOOOOOOOOOOOOOOOOOOOOOOOOOOOOOOOOOOOOOOOOOOOOOOOOOOOOOOOOOOOOOOOO | OOOOOOOOOOOOOOOOOOOOOOOOOOOOOOOOOOOOOOOOOOOOOOOOOOOOOOOOOOOOOOOOOOOOOOOOOOOOOOOOOOOOOOOOOO | OOOOOOOOOOOOOOOOOOOOOOOOOOOOOOOOOOOOOOOOOOOOOOOOOOOOOOOOOOOOOOOOOOOOOOOOOOOOOOOOOOOOOOOOOO | OOOOOOOOOOOOOOOOOOOOOOOOOOOOOOOOOOOOOOOOOOOOOOOOOOOOOOOOOOOOOOOOOOOOOOOOOOOOOOOOOOOOOOOOOO | OOOOOOOOOOOOOOOOOOOOOOOOOOOOOOOOOOOOOOOOOOOOOOOOOOOOOOOOOOOOOOOOOOOOOOOOOOOOOOOOOOOOOOOOOO | OOOOOOOOOOOOOOOOOOOOOOOOOOOOOOOOOOOOOOOOOOOOOOOOOOOOOOOOOOOOOOOOOOOOOOOOOOOOOOOOOOOOOOOOOO | OOOOOOOOOOOOOOOOOOOOOOOOOOOOOOOOOOOOOOOOOOOOOOOOOOOOOOOOOOOOOOOOOOOOOOOOOOOOOOOOOOOOOOOOOO |
| Second Source Change |  |  |  |  |  |  |  |  |  |
| Item | Location | Change Type | Foxconn P/N | Part Description | Manufacturer Full Name | Manufacturer P/N | RoHS | Sheet |  |
| 1 | PCB |  | 0101FBQ00-000-G | PCB,Zaius-MB PVT-X04,OSP,Gre,22L,22.20*13.00,G | GOLD CIRCUIT ELECTRONICS LTD. | 0101FBQ00-000-G | G | PWA BOM |  |
|  |  | NO | 0101FBQ00-000-G | PCB,Zaius-MB PVT-X04,OSP,Gre,22L,22.20*13.00,G | ZHUHAI FOUNDER PRINTED CIRCUIT BOARD（HK） DEVELOPMENT LIMITED | 0101FBQ00-000-G | G | PWA BOM |  |
| 2 | PBMR54,PBFR54,PBER54,PBAR54,PAMR54,PAFR54,PAER54,PAAR54 |  | 61011MC02-017-G | Res,374 Ohm,+/-1%,1/16W,G,SMD0402 | KOA SPEER ELECTRONICS, INC. | RK73H1ETTP3740F | G | PWA BOM |  |
|  |  | ADD | 61011MC00-011-G | RES,374 Ohm,+/-1%,1/16W,G,SMD0402 | YAGEO CORPORATION COMPONENT | RC0402FR-07374RL | G | PWA BOM |  |
|  |  | NO | 61011MC00-024-G | RES,thick film,374Ohm,+/-1%,1/16W,SMD0402,G | PANASONIC INDUSTRIAL CO.,LTD. | ERJ2RKF3740X | G | PWA BOM |  |
|  |  | NO | 61011MC00-029-G | RES,thick film,374Ohm,+/-1%,1/16W,SMD0402,G | VISHAY ENTER TECHNO LOGY.INC | CRCW0402374RFKED | G | PWA BOM |  |
| 3 | PUAC4,PSAC4,PRAC4,PQAC4,PPAC4,PIAC4,PFAC4,PEAC4,PUAC5,PSAC5,PRAC5,PQAC5,PPAC5,PIAC5,PFAC5,PEAC5,PUAC6,PSAC6,PRAC6,PQAC6,PPAC6,PIAC6,PFAC6,PEAC6 |  | 62011DD00-015-G | CAP,22uF,+/-10%,X6S,6.3V,G,SMD1206 | MURATA ELEC. NORTH AMERICA | GRM31CC80J226K | G | PWA BOM |  |
|  |  | Delete | 62011DD00-011-G | CAP,MLCC,22uF,+/-10%,X6S,6.3V,SMD1206,G | YAGEO CORPORATION COMPONENT | CC1206KKX6S5BB226 | G | PWA BOM |  |
| 4 | Q5,Q7 |  | 510406000-185-G | MOS P,FDD6685,30V,11A,30m@4.5V,G,TO252-3,SMD | FAIRCHILD SEMICONDUCTOR CORP | FDD6685 | G | PWA BOM |  |
|  |  | ADD | 510410G00-221-G | MOS P,IPD042P03L3 G,-30V,-70A,TO-252-3,SMD | INFINEON TECHNOLOGIES CORP. | IPD042P03L3 G | G | PWA BOM |  |
|  |  | NO | 51040WQ00-131-G | MOSFET-P,TJ40S04M3L,-40V,-40A,9.1mOhm@Vgs=-10V,13mOhm@Vgs=-6V,SMD,3P,G | TOSHIBA ELECTRONICS ASIA LTD | TJ40S04M3L | G | PWA BOM |  |
|  |  | Delete | 510410800-221-G | MOS P,IPD042P03L3G,-30V,-70A,4.2m@-10V,G,TO-252-3,SMD | INFINEON TECHNOLOGIES CORP. | IPD042P03L3G | G | PWA BOM |  |
| 5 | R31,R40,R53,R393,R402,R416 |  | 61100V600-017-G | RES,200 Ohm,+/-0.1%,1/16W,G,SMD0402 | KOA SPEER ELECTRONICS, INC. | RN731ETTP2000B25 | G | PWA BOM |  |
|  |  | NO | 61100V600-011-G | RES,200 Ohm,+/-0.1%,1/16W,G,SMD0402 | YAGEO CORPORATION COMPONENT | RT0402BRD07200RL | G | PWA BOM |  |
|  |  | ADD | 61100V600-044-G | RES,200 Ohm,+/-0.1%,1/16W,G,SMD0402 | TA-I TECHNOLOGY CO., LTD | RB04BTP2000 | G | PWA BOM |  |
|  |  | NO | 61100V600-012-G | RES,200 Ohm,+/-0.1%,1/16W,G,SMD0402 | WALSIN TECHNOLOGY CORPORATION | WF04U2000BTL | G | PWA BOM |  |
| 6 | R790,R1154,R1157,R1237 |  | 61100BN00-017-G | RES,100KOhm,+/-1%,1/16W,G,SMD0402 | KOA SPEER ELECTRONICS, INC. | RN731ETTP1003F25 | G | PWA BOM |  |
|  |  | NO | 61100BN00-011-G | RES,100KOhm,+/-1%,1/16W,G,SMD0402 | YAGEO CORPORATION COMPONENT | RT0402FRD07100KL | G | PWA BOM |  |
|  |  | ADD | 61100BN00-044-G | RES,100KOhm,+/-1%,1/16W,G,SMD0402 | TA-I TECHNOLOGY CO., LTD | RB04FTP1003 | G | PWA BOM |  |
|  |  | NO | 61100BN00-012-G | RES,100KOhm,+/-1%,1/16W,G,SMD0402 | WALSIN TECHNOLOGY CORPORATION | WF04U1003FTL | G | PWA BOM |  |
| 7 | R961,R962,R963,R964,R965,R967,R968,R969,R970,R975,R976,R977,R978,R985,R986,R988,R989,R992,R1003 |  | 61100C600-017-G | RES,1KOhm,+/-0.5%,1/16W,G,SMD0402 | KOA SPEER ELECTRONICS, INC. | RN731ETTP1001D25 | G | PWA BOM |  |
|  |  | NO | 61100C603-024-G | RES,1KOhm,+/-0.5%,1/16W,G,SMD0402 | PANASONIC INDUSTRIAL CO.,LTD. | ERA2AED102X | G | PWA BOM |  |
|  |  | NO | 61100C600-029-G | RES,1KOhm,+/-0.5%,1/16W,G,SMD0402 | VISHAY ENTER TECHNO LOGY.INC | MCS04020D1001DE000 | G | PWA BOM |  |
|  |  | ADD | 61100C600-011-G | RES,1KOhm,+/-0.5%,1/16W,G,SMD0402 | YAGEO CORPORATION COMPONENT | RT0402DRE071KL | G | PWA BOM |  |
| 8 | R1092,R1115 |  | 61100QH00-017-G | RES,510 Ohm,+/-0.1%,1/16W,G,SMD0402 | KOA SPEER ELECTRONICS, INC. | RN731ETTP5100B25 | G | PWA BOM |  |
|  |  | NO | 61100QH00-011-G | RES,510 Ohm,+/-0.1%,1/16W,G,SMD0402 | YAGEO CORPORATION COMPONENT | RT0402BRD07510RL | G | PWA BOM |  |
|  |  | ADD | 61100QH00-044-G | RES,510 Ohm,+/-0.1%,1/16W,G,SMD0402 | TA-I TECHNOLOGY CO., LTD | RB04BTP5100 | G | PWA BOM |  |
|  |  | NO | 61100QH00-012-G | RES,510 Ohm,+/-0.1%,1/16W,G,SMD0402 | WALSIN TECHNOLOGY CORPORATION | WF04U5100BTL | G | PWA BOM |  |
| 9 | R1483 |  | 61100QT01-017-G | RES,10 Ohm,+/-0.5%,1/16W,G,SMD0402 | KOA SPEER ELECTRONICS, INC. | RN731ETTP10R0D25 | G | PWA BOM |  |
|  |  | ADD | 61100QT00-011-G | RES,10 Ohm,+/-0.5%,1/16W,G,SMD0402 | YAGEO CORPORATION COMPONENT | RT0402DRE0710RL | G | PWA BOM |  |
|  |  | ADD | 61100QT00-012-G | RES,10 Ohm,+/-0.5%,1/16W,G,SMD0402 | WALSIN TECHNOLOGY CORPORATION | WF04T10R0DTL | G | PWA BOM |  |
| 10 | R1492 |  | 610118800-017-G | RES,499KOhm,+/-1%,1/8W,G,SMD0805 | KOA SPEER ELECTRONICS, INC. | RK73H2ATTD4993F | G | PWA BOM |  |
|  |  | NO | 610118800-024-G | RES,499KOhm,+/-1%,1/8W,G,SMD0805 | PANASONIC INDUSTRIAL CO.,LTD. | ERJ6ENF4993V | G | PWA BOM |  |
|  |  | ADD | RC0805FR-07499KL | RES,499KOhm,+/-1%,1/8W,G,SMD0805 | YAGEO CORPORATION COMPONENT | RC0805FR-07499KL | G | PWA BOM |  |
| 11 | R1769,R1770 |  | 610130300-017-G | RES,60.4 Ohm,+/-1%,1/20W,G,SMD0201 | KOA SPEER ELECTRONICS, INC. | RK73H1HTTC60R4F | G | PWA BOM |  |
|  |  | ADD | 610130300-044-G | RES,thick film,60.4Ohm,+/-1%,1/20W,SMD0201,G | TA-I TECHNOLOGY CO., LTD | RM02FTN60R4 | G | PWA BOM |  |
|  |  | ADD | 610130300-011-G | RES,thick film,60.4Ohm,+/-1%,1/20W,SMD0201,G | YAGEO CORPORATION COMPONENT | RC0201FR-0760R4L | G | PWA BOM |  |
|  |  | ADD | 610130300-012-G | RES,thick film,60.4Ohm,+/-1%,1/20W,SMD0201,G | WALSIN TECHNOLOGY CORPORATION | WR02X60R4FAL | G | PWA BOM |  |
|  |  | NO | 610130300-029-G | RES,60.4 Ohm,+/-1%,1/20W,G,SMD0201 | VISHAY ENTER TECHNO LOGY.INC | CRCW020160R4FKED | G | PWA BOM |  |
|  |  | NO | 610130300-024-G | RES,60.4 Ohm,+/-1%,1/20W,G,SMD0201 | PANASONIC INDUSTRIAL CO.,LTD. | ERJ1GNF60R4C | G | PWA BOM |  |
| 12 | U_TMP |  | 320403K00-183-G | IC,Temp Sensor,TMP75AIDR,3°C,G,SOIC-8,SMD | TEXAS INSTRUMENTS | TMP75AIDR | G | PWA BOM |  |
|  |  | NO | 320403Q00-173-G | IC,Temp Sensor,DS75S+T&R,3°C,G,SO-8,SMD | MAXIM INTEGRATED PRODUCTS, INC. | DS75S+T&R | G | PWA BOM |  |
|  |  | NO | 320405300-214-G | IC,Temp Sensor,STLM75M2F,±0.5°C,G,SO-8,SMD | ST MICRO ELECTRONICS,INC | STLM75M2F | G | PWA BOM |  |
|  |  | NO | 32040SL00-223-G | IC,Temperature Sensor,NCT75DR2G,G,SOIC-8,SMD | ON SEMICONDUCTOR CORP | NCT75DR2G | G | PWA BOM |  |
|  |  | NO | 32040FL00-031-G | IC,Temperature Sensor,LM75BD,G,SO-8,SMD | NXP SEMICONDUCTORS | LM75BD | G | PWA BOM |  |
|  |  | Delete | 320404J00-190-G | IC,Temp Sensor,ADT75ARZ-REEL,1°C,G,SOIC-8,SMD | ANALOG DEVICES INC | ADT75ARZ-REEL | G | PWA BOM |  |
| 13 | U170,U174,U180 |  | 310109D00-031-G | IC,Gate&Inverter,74LVC1G32GW,1.65~5.5V,G,TSSOP-5,SMD | NXP SEMICONDUCTORS | 74LVC1G32GW | G | PWA BOM |  |
|  |  | NO | 310109E00-223-G | IC,Gate&Inverter,NL17SZ32DFT2G,1.65~5.5V,G,SOT-353-5,SMD | ON SEMICONDUCTOR CORP | NL17SZ32DFT2G | G | PWA BOM |  |
|  |  | ADD | TC7SZ32FU,LJ(CT | IC,Gate&Inverter,TC7SZ32FU,1.65~5.5V,G,SSOP-5,SMD | TOSHIBA ELECTRONICS ASIA LTD | TC7SZ32FU,LJ(CT | G | PWA BOM |  |
|  |  | Delete | 310108600-131-G | IC,Gate&Inverter,TC7SZ32FU,1.65~5.5V,G,SSOP-5,SMD | TOSHIBA ELECTRONICS ASIA LTD | TC7SZ32FU | G | PWA BOM |  |
| 14 | U171 |  | 31050KL00-031-G | IC,Buffer,74HC75PW,2.0V~6.0V,G,TSSOP-16,SMD | NXP SEMICONDUCTORS | 74HC75PW | G | PWA BOM |  |
|  |  | ADD | CD74HC75PWR | IC,Translator,CD74HC75PWR,2V~6V,G,TSSOP-16,SMD | Texas Instruments | CD74HC75PWR | G | PWA BOM |  |
|  |  | Delete | 311007400-183-G | IC,Translator,CD74HC75PWRG4,2V~6V,G,TSSOP-16,SMD | Texas Instruments | CD74HC75PWRG4 | G | PWA BOM |  |
| OOOOOOOOOOOOOOOOOOOOOOOOOOOOOOOOOOOOOOOOOOOOOOOOOOOOOOOOOOOOOOOOOOOOOOOOOOOOOOOOOOOOOOOOOO | OOOOOOOOOOOOOOOOOOOOOOOOOOOOOOOOOOOOOOOOOOOOOOOOOOOOOOOOOOOOOOOOOOOOOOOOOOOOOOOOOOOOOOOOOO | OOOOOOOOOOOOOOOOOOOOOOOOOOOOOOOOOOOOOOOOOOOOOOOOOOOOOOOOOOOOOOOOOOOOOOOOOOOOOOOOOOOOOOOOOO | OOOOOOOOOOOOOOOOOOOOOOOOOOOOOOOOOOOOOOOOOOOOOOOOOOOOOOOOOOOOOOOOOOOOOOOOOOOOOOOOOOOOOOOOOO | OOOOOOOOOOOOOOOOOOOOOOOOOOOOOOOOOOOOOOOOOOOOOOOOOOOOOOOOOOOOOOOOOOOOOOOOOOOOOOOOOOOOOOOOOO | OOOOOOOOOOOOOOOOOOOOOOOOOOOOOOOOOOOOOOOOOOOOOOOOOOOOOOOOOOOOOOOOOOOOOOOOOOOOOOOOOOOOOOOOOO | OOOOOOOOOOOOOOOOOOOOOOOOOOOOOOOOOOOOOOOOOOOOOOOOOOOOOOOOOOOOOOOOOOOOOOOOOOOOOOOOOOOOOOOOOO | OOOOOOOOOOOOOOOOOOOOOOOOOOOOOOOOOOOOOOOOOOOOOOOOOOOOOOOOOOOOOOOOOOOOOOOOOOOOOOOOOOOOOOOOOO | OOOOOOOOOOOOOOOOOOOOOOOOOOOOOOOOOOOOOOOOOOOOOOOOOOOOOOOOOOOOOOOOOOOOOOOOOOOOOOOOOOOOOOOOOO | OOOOOOOOOOOOOOOOOOOOOOOOOOOOOOOOOOOOOOOOOOOOOOOOOOOOOOOOOOOOOOOOOOOOOOOOOOOOOOOOOOOOOOOOOO |
| Master Materials Change |  |  |  |  |  |  |  |  |  |
| Item | Foxconn P/N | Orig._Usage | New_Usage | Part Description | Manufacturer Full Name | Manufacturer P/N | RoHS | Location | Sheet |
| 1 | 620109S00-023-G | 0 | 14 | CAP,4.7uF,+/-10%,X7R,10V,G,SMD0805 | TAIYO ELECTRIC IND.CO.LTD | LMK212B7475KG-T | G | (+)C1424,C1427,C1451,C1455,C1459,C1464,C1466,C1468,C1470,C1499,C1533,C1577,C1585,C1596 | PWA BOM |
|  | 620109S00-026-G |  |  | CAP,4.7uF,+/-10%,X7R,10V,G,SMD0805 | SAMSUNG SEMICONDUCTOR | CL21B475KPFNNNE |  |  | PWA BOM |
|  | 620109S00-015-G |  |  | CAP,4.7uF,+/-10%,X7R,10V,G,SMD0805 | MURATA ELEC. NORTH AMERICA | GRM21BR71A475K |  |  | PWA BOM |
| 2 | 620133600-012-G | 0 | 1 | CAP,1nF,+/-5%,X7R,100V,G,SMD0805 | WALSIN TECHNOLOGY CORPORATION | 0805B102J101CT | G | (+)PHAC3 | PWA BOM |
|  | 620133600-015-G |  |  | CAP,1nF,+/-5%,X7R,100V,G,SMD0805 | MURATA ELEC. NORTH AMERICA | GRM219R72A102JA01D |  |  | PWA BOM |
|  | 620133600-026-G |  |  | CAP,1nF,+/-5%,X7R,100V,G,SMD0805 | SAMSUNG SEMICONDUCTOR | CL21B102JCANNNC |  |  | PWA BOM |
| 3 | PCF8523TK/1 | 0 | 1 | IC,NXP,PCF8523TK/1,G,HVSON-8,SMD | NXP SEMICONDUCTORS | PCF8523TK/1 | G | (+)U60 | PWA BOM |
| 4 | 87898-0318 | 0 | 10 | CONN,Header,Pin Header,1X3,V/T,2.54mm,30u,G,SMD-3 | MOLEX INCORPORATED | 87898-0318 | G | (+)J_BMC_DEBUG1,J1,J4,J5,J36,J41,J43,J48,J147,J149 | PWA BOM |
|  | 34068LN00-317-G |  |  | CONN,Header,Pin Header,1X3,V/T,2.54mm,30u,G,SMD-3 | MOLEX INCORPORATED | 87898-0315 |  |  | PWA BOM |
|  | 34068HT00-245-G |  |  | CONN,Header,Pin Header,1X3,V/T,Bla,2.54mm,30u,SMD-3 | AMPHENOL SHANGHAI CORP. | G800MU305010EU |  |  | PWA BOM |
|  | 34068GU00-309-G |  |  | CONN,Header,Pin Header,1X3,V/T,Bla,2.54mm,30u,SMD-3 | SAMTEC INC. | TSM-103-01-S-SV-P-TR |  |  | PWA BOM |
| 5 | 87898-0458 | 0 | 1 | CONN,Pin Header,1X4,V/T,Bla,2.54mm,30u,G,SMD-4 | MOLEX INCORPORATED | 87898-0458 | G | (+)J148 | PWA BOM |
|  | 340672300-317-G |  |  | CONN,Pin Header,1X4,V/T,Bla,2.54mm,30u,G,SMD-4 | MOLEX INCORPORATED | 87898-0455 |  |  | PWA BOM |
|  | 34068VT00-GRT-G |  |  | CONN,Header,Pin Header,1X4,V/T,Bla,2.54mm,30u,G,SMD-4 | PINREX TECHNOLOGY CORP. | 212-91-04SBEJ |  |  | PWA BOM |
|  | 340692T00-245-G |  |  | CONN,Header,Pin Header,1X4,V/T,Bla,2.54mm,30u,G,SMD-4 | AMPHENOL SHANGHAI CORP. | G800MR304010HR |  |  | PWA BOM |
| 6 | 620109S00-015-G | 14 | 0 | CAP,4.7uF,+/-10%,X7R,10V,G,SMD0805 | MURATA ELEC. NORTH AMERICA | GRM21BR71A475K | G | (-)C1424,C1427,C1451,C1455,C1459,C1464,C1466,C1468,C1470,C1499,C1533,C1577,C1585,C1596 | PWA BOM |
|  | 620109S00-023-G |  |  | CAP,4.7uF,+/-10%,X7R,10V,G,SMD0805 | TAIYO ELECTRIC IND.CO.LTD | LMK212B7475KG-T |  |  | PWA BOM |
|  | 620109S00-026-G |  |  | CAP,4.7uF,+/-10%,X7R,10V,G,SMD0805 | SAMSUNG SEMICONDUCTOR | CL21B475KPFNNNE |  |  | PWA BOM |
| 7 | 620133600-015-G | 1 | 0 | CAP,1nF,+/-5%,X7R,100V,G,SMD0805 | MURATA ELEC. NORTH AMERICA | GRM219R72A102JA01D | G | (-)PHAC3 | PWA BOM |
|  | 620133600-012-G |  |  | CAP,1nF,+/-5%,X7R,100V,G,SMD0805 | WALSIN TECHNOLOGY CORPORATION | 0805B102J101CT |  |  | PWA BOM |
| 8 | 21050P200-031-G | 1 | 0 | IC,NXP,PCF8523TK,G,HVSON-8,SMD | NXP SEMICONDUCTORS | PCF8523TK | G | (-)U60 | PWA BOM |
| 9 | 34068LN00-317-G | 10 | 0 | CONN,Header,Pin Header,1X3,V/T,2.54mm,30u,G,SMD-3 | MOLEX INCORPORATED | 87898-0315 | G | (-)J_BMC_DEBUG1,J1,J4,J5,J36,J41,J43,J48,J147,J149 | PWA BOM |
|  | 34068HT00-245-G |  |  | CONN,Header,Pin Header,1X3,V/T,Bla,2.54mm,30u,SMD-3 | AMPHENOL SHANGHAI CORP. | G800MU305010EU |  |  | PWA BOM |
|  | 34068GU00-309-G |  |  | CONN,Header,Pin Header,1X3,V/T,Bla,2.54mm,30u,SMD-3 | SAMTEC INC. | TSM-103-01-S-SV-P-TR |  |  | PWA BOM |
| 10 | 340672300-317-G | 1 | 0 | CONN,Pin Header,1X4,V/T,Bla,2.54mm,30u,G,SMD-4 | MOLEX INCORPORATED | 87898-0455 | G | (-)J148 | PWA BOM |
|  | 34068VT00-GRT-G |  |  | CONN,Header,Pin Header,1X4,V/T,Bla,2.54mm,30u,G,SMD-4 | PINREX TECHNOLOGY CORP. | 212-91-04SBEJ |  |  | PWA BOM |
|  | 340692T00-245-G |  |  | CONN,Header,Pin Header,1X4,V/T,Bla,2.54mm,30u,G,SMD-4 | AMPHENOL SHANGHAI CORP. | G800MR304010HR |  |  | PWA BOM |
| OOOOOOOOOOOOOOOOOOOOOOOOOOOOOOOOOOOOOOOOOOOOOOOOOOOOOOOOOOOOOOOOOOOOOOOOOOOOOOOOOOOOOOOOOO | OOOOOOOOOOOOOOOOOOOOOOOOOOOOOOOOOOOOOOOOOOOOOOOOOOOOOOOOOOOOOOOOOOOOOOOOOOOOOOOOOOOOOOOOOO | OOOOOOOOOOOOOOOOOOOOOOOOOOOOOOOOOOOOOOOOOOOOOOOOOOOOOOOOOOOOOOOOOOOOOOOOOOOOOOOOOOOOOOOOOO | OOOOOOOOOOOOOOOOOOOOOOOOOOOOOOOOOOOOOOOOOOOOOOOOOOOOOOOOOOOOOOOOOOOOOOOOOOOOOOOOOOOOOOOOOO | OOOOOOOOOOOOOOOOOOOOOOOOOOOOOOOOOOOOOOOOOOOOOOOOOOOOOOOOOOOOOOOOOOOOOOOOOOOOOOOOOOOOOOOOOO | OOOOOOOOOOOOOOOOOOOOOOOOOOOOOOOOOOOOOOOOOOOOOOOOOOOOOOOOOOOOOOOOOOOOOOOOOOOOOOOOOOOOOOOOOO | OOOOOOOOOOOOOOOOOOOOOOOOOOOOOOOOOOOOOOOOOOOOOOOOOOOOOOOOOOOOOOOOOOOOOOOOOOOOOOOOOOOOOOOOOO | OOOOOOOOOOOOOOOOOOOOOOOOOOOOOOOOOOOOOOOOOOOOOOOOOOOOOOOOOOOOOOOOOOOOOOOOOOOOOOOOOOOOOOOOOO | OOOOOOOOOOOOOOOOOOOOOOOOOOOOOOOOOOOOOOOOOOOOOOOOOOOOOOOOOOOOOOOOOOOOOOOOOOOOOOOOOOOOOOOOOO | OOOOOOOOOOOOOOOOOOOOOOOOOOOOOOOOOOOOOOOOOOOOOOOOOOOOOOOOOOOOOOOOOOOOOOOOOOOOOOOOOOOOOOOOOO |
| TLA Parts Change |  |  |  |  |  |  |  |  |  |
| Item | Foxconn P/N | Qty | Part Description | Manufacturer Full Name | Manufacturer P/N | RoHS | Location | Remark | BOM |
| BOM Change List Date:Wed Sep 13 09:16:36 GMT+08:00 2017 |  |  |  |  |  |  |  |  |  |
| New BOM file : E:\barreleye g2\0912\Zaius BG2\BG2 0913.xls |  |  |  |  |  |  |  |  |  |
| Old BOM file : E:\barreleye g2\0912\Zaius BG2\BG2 0906.xls |  |  |  |  |  |  |  |  |  |
| ##### Add Parts |  |  |  |  |  |  |  |  |  |
| Item | Location | Qty | Foxconn P/N | Part Description | Manufacturer Full Name | Manufacturer P/N | RoHS | Sheet |  |
| ##### Remove Parts |  |  |  |  |  |  |  |  |  |
| Item | Location | Qty | Foxconn P/N | Part Description | Manufacturer Full Name | Manufacturer P/N | RoHS | Sheet |  |
| ##### Change Parts |  |  |  |  |  |  |  |  |  |
| Item | Location | Qty | Foxconn P/N | Part Description | Manufacturer Full Name | Manufacturer P/N | RoHS | Sheet | Remark |
| 1 | U20,U21 | 2 | 410512F00-233-G | Flash,MX66L51235FMI-10G,2.7V~3.6V,512M,SPI,G,SOP-16,SMD | MACRONIX INTERNATIONAL CO.,LTD. | MX66L51235FMI-10G | G | PWA BOM | In New BOM |
|  | U20,U21 | 2 | 410512F00-233-G | Flash,MX66L51235FMI-10G,2.7V~3.6V,512M,SPI,G,SOP-16,SMD | MACRONIX INTERNATIONAL CO.,LTD. | MX66L51235FMI-10G | G | PWA BOM | In Old BOM |
|  |  |  | 410513L00-216-G | Flash,SOP-16,MT25QL512ABB8ESF-0SIT | MICRON SEMICONDUCTOR ASIA PTE.LTD. | MT25QL512ABB8ESF-0SIT | G | PWA BOM | In Old BOM |
| 2 | X1 | 1 | 71011RD00-100-G | XTAL,25MHz,+/-25ppm,20pF,G,SMD | TXC CORPORATION | 7V25000016 | G | PWA BOM | In New BOM |
|  |  |  | 1N225000CC0DT | XTAL,25MHz,+/-25ppm,20pF,G,SMD | KDS | 1N225000CC0DT | G | PWA BOM | In New BOM |
|  | X1 | 1 | 71011RD00-100-G | XTAL,25MHz,+/-25ppm,20pF,G,SMD | TXC CORPORATION | 7V25000016 | G | PWA BOM | In Old BOM |
|  |  |  | 1N225000CC0DT | XTAL,25MHz,+/-25ppm,20pF,G,SMD | KDS | 1N225000CC0DT | G | PWA BOM | In Old BOM |
|  |  |  | 1C225000CC0DT | XTAL,25MHz,+/-25ppm,20pF,G,SMD | KDS | 1C225000CC0DT | G | PWA BOM | In Old BOM |
| 3 | PBMU1,PBFU1,PBEU1,PBAU1,PAMU1,PAFU1,PAEU1,PAAU1 | 8 | ISL68137IRAZ-GG04 | IC,PWM Controller,ISL68137IRAZ-T,G,QFN-48,SMD | INTERSIL CORPORATION | ISL68137IRAZ-GG04 | G | PWA BOM | In New BOM |
|  | PBMU1,PBFU1,PBEU1,PBAU1,PAMU1,PAFU1,PAEU1,PAAU1 | 8 | 320242200-230-G | IC,PWM Controller,ISL68137IRAZ-T,G,QFN-48,SMD | INTERSIL CORPORATION | ISL68137IRAZ-T | G | PWA BOM | In Old BOM |
| 4 | U5 | 1 | UCD90160RGCR-C13 | IC,Power Controller,UCD90160RGCR,G,VQFN-64,SMD | TEXAS INSTRUMENTS | UCD90160RGCR-C13 | G | PWA BOM | In New BOM |
|  | U5 | 1 | 320241C00-183-G | IC,Power Controller,UCD90160RGCR,G,VQFN-64,SMD | TEXAS INSTRUMENTS | UCD90160RGCR | G | PWA BOM | In Old BOM |
| ##### Change Revision |  |  |  |  |  |  |  |  |  |
| Sheet | REV OF BOM | CUSTOMER | CUSTOMER P/N | PWA PN | PWA DESCRIPTION | PWA REV | DATE | Remark |  |
| OOOOOOOOOOOOOOOOOOOOOOOOOOOOOOOOOOOOOOOOOOOOOOOOOOOOOOOOOOOOOOOOOOOOOOOOOOOOOOOOOOOOOOOOOO | OOOOOOOOOOOOOOOOOOOOOOOOOOOOOOOOOOOOOOOOOOOOOOOOOOOOOOOOOOOOOOOOOOOOOOOOOOOOOOOOOOOOOOOOOO | OOOOOOOOOOOOOOOOOOOOOOOOOOOOOOOOOOOOOOOOOOOOOOOOOOOOOOOOOOOOOOOOOOOOOOOOOOOOOOOOOOOOOOOOOO | OOOOOOOOOOOOOOOOOOOOOOOOOOOOOOOOOOOOOOOOOOOOOOOOOOOOOOOOOOOOOOOOOOOOOOOOOOOOOOOOOOOOOOOOOO | OOOOOOOOOOOOOOOOOOOOOOOOOOOOOOOOOOOOOOOOOOOOOOOOOOOOOOOOOOOOOOOOOOOOOOOOOOOOOOOOOOOOOOOOOO | OOOOOOOOOOOOOOOOOOOOOOOOOOOOOOOOOOOOOOOOOOOOOOOOOOOOOOOOOOOOOOOOOOOOOOOOOOOOOOOOOOOOOOOOOO | OOOOOOOOOOOOOOOOOOOOOOOOOOOOOOOOOOOOOOOOOOOOOOOOOOOOOOOOOOOOOOOOOOOOOOOOOOOOOOOOOOOOOOOOOO | OOOOOOOOOOOOOOOOOOOOOOOOOOOOOOOOOOOOOOOOOOOOOOOOOOOOOOOOOOOOOOOOOOOOOOOOOOOOOOOOOOOOOOOOOO | OOOOOOOOOOOOOOOOOOOOOOOOOOOOOOOOOOOOOOOOOOOOOOOOOOOOOOOOOOOOOOOOOOOOOOOOOOOOOOOOOOOOOOOOOO | OOOOOOOOOOOOOOOOOOOOOOOOOOOOOOOOOOOOOOOOOOOOOOOOOOOOOOOOOOOOOOOOOOOOOOOOOOOOOOOOOOOOOOOOOO |
| Second Source Change |  |  |  |  |  |  |  |  |  |
| Item | Location | Change Type | Foxconn P/N | Part Description | Manufacturer Full Name | Manufacturer P/N | RoHS | Sheet |  |
| 1 | U20,U21 |  | 410512F00-233-G | Flash,MX66L51235FMI-10G,2.7V~3.6V,512M,SPI,G,SOP-16,SMD | MACRONIX INTERNATIONAL CO.,LTD. | MX66L51235FMI-10G | G | PWA BOM |  |
|  |  | Delete | 410513L00-216-G | Flash,SOP-16,MT25QL512ABB8ESF-0SIT | MICRON SEMICONDUCTOR ASIA PTE.LTD. | MT25QL512ABB8ESF-0SIT | G | PWA BOM |  |
| 2 | X1 |  | 71011RD00-100-G | XTAL,25MHz,+/-25ppm,20pF,G,SMD | TXC CORPORATION | 7V25000016 | G | PWA BOM |  |
|  |  | NO | 1N225000CC0DT | XTAL,25MHz,+/-25ppm,20pF,G,SMD | KDS | 1N225000CC0DT | G | PWA BOM |  |
|  |  | Delete | 1C225000CC0DT | XTAL,25MHz,+/-25ppm,20pF,G,SMD | KDS | 1C225000CC0DT | G | PWA BOM |  |
| OOOOOOOOOOOOOOOOOOOOOOOOOOOOOOOOOOOOOOOOOOOOOOOOOOOOOOOOOOOOOOOOOOOOOOOOOOOOOOOOOOOOOOOOOO | OOOOOOOOOOOOOOOOOOOOOOOOOOOOOOOOOOOOOOOOOOOOOOOOOOOOOOOOOOOOOOOOOOOOOOOOOOOOOOOOOOOOOOOOOO | OOOOOOOOOOOOOOOOOOOOOOOOOOOOOOOOOOOOOOOOOOOOOOOOOOOOOOOOOOOOOOOOOOOOOOOOOOOOOOOOOOOOOOOOOO | OOOOOOOOOOOOOOOOOOOOOOOOOOOOOOOOOOOOOOOOOOOOOOOOOOOOOOOOOOOOOOOOOOOOOOOOOOOOOOOOOOOOOOOOOO | OOOOOOOOOOOOOOOOOOOOOOOOOOOOOOOOOOOOOOOOOOOOOOOOOOOOOOOOOOOOOOOOOOOOOOOOOOOOOOOOOOOOOOOOOO | OOOOOOOOOOOOOOOOOOOOOOOOOOOOOOOOOOOOOOOOOOOOOOOOOOOOOOOOOOOOOOOOOOOOOOOOOOOOOOOOOOOOOOOOOO | OOOOOOOOOOOOOOOOOOOOOOOOOOOOOOOOOOOOOOOOOOOOOOOOOOOOOOOOOOOOOOOOOOOOOOOOOOOOOOOOOOOOOOOOOO | OOOOOOOOOOOOOOOOOOOOOOOOOOOOOOOOOOOOOOOOOOOOOOOOOOOOOOOOOOOOOOOOOOOOOOOOOOOOOOOOOOOOOOOOOO | OOOOOOOOOOOOOOOOOOOOOOOOOOOOOOOOOOOOOOOOOOOOOOOOOOOOOOOOOOOOOOOOOOOOOOOOOOOOOOOOOOOOOOOOOO | OOOOOOOOOOOOOOOOOOOOOOOOOOOOOOOOOOOOOOOOOOOOOOOOOOOOOOOOOOOOOOOOOOOOOOOOOOOOOOOOOOOOOOOOOO |
| Master Materials Change |  |  |  |  |  |  |  |  |  |
| Item | Foxconn P/N | Orig._Usage | New_Usage | Part Description | Manufacturer Full Name | Manufacturer P/N | RoHS | Location | Sheet |
| 1 | ISL68137IRAZ-GG04 | 0 | 8 | IC,PWM Controller,ISL68137IRAZ-T,G,QFN-48,SMD | INTERSIL CORPORATION | ISL68137IRAZ-GG04 | G | (+)PBMU1,PBFU1,PBEU1,PBAU1,PAMU1,PAFU1,PAEU1,PAAU1 | PWA BOM |
| 2 | UCD90160RGCR-C13 | 0 | 1 | IC,Power Controller,UCD90160RGCR,G,VQFN-64,SMD | TEXAS INSTRUMENTS | UCD90160RGCR-C13 | G | (+)U5 | PWA BOM |
| 3 | 320242200-230-G | 8 | 0 | IC,PWM Controller,ISL68137IRAZ-T,G,QFN-48,SMD | INTERSIL CORPORATION | ISL68137IRAZ-T | G | (-)PBMU1,PBFU1,PBEU1,PBAU1,PAMU1,PAFU1,PAEU1,PAAU1 | PWA BOM |
| 4 | 320241C00-183-G | 1 | 0 | IC,Power Controller,UCD90160RGCR,G,VQFN-64,SMD | TEXAS INSTRUMENTS | UCD90160RGCR | G | (-)U5 | PWA BOM |
| OOOOOOOOOOOOOOOOOOOOOOOOOOOOOOOOOOOOOOOOOOOOOOOOOOOOOOOOOOOOOOOOOOOOOOOOOOOOOOOOOOOOOOOOOO | OOOOOOOOOOOOOOOOOOOOOOOOOOOOOOOOOOOOOOOOOOOOOOOOOOOOOOOOOOOOOOOOOOOOOOOOOOOOOOOOOOOOOOOOOO | OOOOOOOOOOOOOOOOOOOOOOOOOOOOOOOOOOOOOOOOOOOOOOOOOOOOOOOOOOOOOOOOOOOOOOOOOOOOOOOOOOOOOOOOOO | OOOOOOOOOOOOOOOOOOOOOOOOOOOOOOOOOOOOOOOOOOOOOOOOOOOOOOOOOOOOOOOOOOOOOOOOOOOOOOOOOOOOOOOOOO | OOOOOOOOOOOOOOOOOOOOOOOOOOOOOOOOOOOOOOOOOOOOOOOOOOOOOOOOOOOOOOOOOOOOOOOOOOOOOOOOOOOOOOOOOO | OOOOOOOOOOOOOOOOOOOOOOOOOOOOOOOOOOOOOOOOOOOOOOOOOOOOOOOOOOOOOOOOOOOOOOOOOOOOOOOOOOOOOOOOOO | OOOOOOOOOOOOOOOOOOOOOOOOOOOOOOOOOOOOOOOOOOOOOOOOOOOOOOOOOOOOOOOOOOOOOOOOOOOOOOOOOOOOOOOOOO | OOOOOOOOOOOOOOOOOOOOOOOOOOOOOOOOOOOOOOOOOOOOOOOOOOOOOOOOOOOOOOOOOOOOOOOOOOOOOOOOOOOOOOOOOO | OOOOOOOOOOOOOOOOOOOOOOOOOOOOOOOOOOOOOOOOOOOOOOOOOOOOOOOOOOOOOOOOOOOOOOOOOOOOOOOOOOOOOOOOOO | OOOOOOOOOOOOOOOOOOOOOOOOOOOOOOOOOOOOOOOOOOOOOOOOOOOOOOOOOOOOOOOOOOOOOOOOOOOOOOOOOOOOOOOOOO |
| TLA Parts Change |  |  |  |  |  |  |  |  |  |
| Item | Foxconn P/N | Qty | Part Description | Manufacturer Full Name | Manufacturer P/N | RoHS | Location | Remark | BOM |
| BOM Change List Date:Fri Sep 29 09:15:17 GMT+08:00 2017 |  |  |  |  |  |  |  |  |  |
| New BOM file : C:\<user>\BARRELEYE-G2-MB-PVT-HW-EBOM-20170928.xls |  |  |  |  |  |  |  |  |  |
| Old BOM file : C:\<user>\BARRELEYE-G2-MB-PVT-HW-EBOM-20170830.xls |  |  |  |  |  |  |  |  |  |
| ##### Add Parts |  |  |  |  |  |  |  |  |  |
| Item | Location | Qty | Foxconn P/N | Part Description | Manufacturer Full Name | Manufacturer P/N | RoHS | Sheet |  |
| ##### Remove Parts |  |  |  |  |  |  |  |  |  |
| Item | Location | Qty | Foxconn P/N | Part Description | Manufacturer Full Name | Manufacturer P/N | RoHS | Sheet |  |
| 1 | C2092,C2120,C2121,C2122 | 4 | 620106200-015-G | CAP,10nF,+/-10%,X7R,16V,G,SMD0402 | MURATA ELEC. NORTH AMERICA | GRM155R71C103KA01D | Y | PWA BOM |  |
| 2 | C2008,C2010 | 2 | 620108100-015-G | CAP,15pF,+/-5%,NPO(C0G),50V,G,SMD0402 | MURATA ELEC. NORTH AMERICA | GRM1555C1H150J | N | PWA BOM |  |
| 3 | R1425,R1516,R1517,R1518 | 4 | 610114U00-017-G | RES,3.3KOhm,+/-1%,1/16W,G,SMD0402 | KOA SPEER ELECTRONICS, INC. | RK73H1ETTP3301F | N | PWA BOM |  |
| ##### Change Parts |  |  |  |  |  |  |  |  |  |
| Item | Location | Qty | Foxconn P/N | Part Description | Manufacturer Full Name | Manufacturer P/N | RoHS | Sheet | Remark |
| 1 | U5 | 1 | UCD90160RGCR-C13 | IC,Power Controller,UCD90160RGCR,G,VQFN-64,SMD | TEXAS INSTRUMENTS | UCD90160RGCR-C13 |  | PWA BOM | In New BOM |
|  | U5 | 1 | 320241C00-183-G | IC,Power Controller,UCD90160RGCR,G,VQFN-64,SMD | TEXAS INSTRUMENTS | UCD90160RGCR |  | PWA BOM | In Old BOM |
| ##### Change Revision |  |  |  |  |  |  |  |  |  |
| Sheet | REV OF BOM | CUSTOMER | CUSTOMER P/N | PWA PN | PWA DESCRIPTION | PWA REV | DATE | Remark |  |
| OOOOOOOOOOOOOOOOOOOOOOOOOOOOOOOOOOOOOOOOOOOOOOOOOOOOOOOOOOOOOOOOOOOOOOOOOOOOOOOOOOOOOOOOOO | OOOOOOOOOOOOOOOOOOOOOOOOOOOOOOOOOOOOOOOOOOOOOOOOOOOOOOOOOOOOOOOOOOOOOOOOOOOOOOOOOOOOOOOOOO | OOOOOOOOOOOOOOOOOOOOOOOOOOOOOOOOOOOOOOOOOOOOOOOOOOOOOOOOOOOOOOOOOOOOOOOOOOOOOOOOOOOOOOOOOO | OOOOOOOOOOOOOOOOOOOOOOOOOOOOOOOOOOOOOOOOOOOOOOOOOOOOOOOOOOOOOOOOOOOOOOOOOOOOOOOOOOOOOOOOOO | OOOOOOOOOOOOOOOOOOOOOOOOOOOOOOOOOOOOOOOOOOOOOOOOOOOOOOOOOOOOOOOOOOOOOOOOOOOOOOOOOOOOOOOOOO | OOOOOOOOOOOOOOOOOOOOOOOOOOOOOOOOOOOOOOOOOOOOOOOOOOOOOOOOOOOOOOOOOOOOOOOOOOOOOOOOOOOOOOOOOO | OOOOOOOOOOOOOOOOOOOOOOOOOOOOOOOOOOOOOOOOOOOOOOOOOOOOOOOOOOOOOOOOOOOOOOOOOOOOOOOOOOOOOOOOOO | OOOOOOOOOOOOOOOOOOOOOOOOOOOOOOOOOOOOOOOOOOOOOOOOOOOOOOOOOOOOOOOOOOOOOOOOOOOOOOOOOOOOOOOOOO | OOOOOOOOOOOOOOOOOOOOOOOOOOOOOOOOOOOOOOOOOOOOOOOOOOOOOOOOOOOOOOOOOOOOOOOOOOOOOOOOOOOOOOOOOO | OOOOOOOOOOOOOOOOOOOOOOOOOOOOOOOOOOOOOOOOOOOOOOOOOOOOOOOOOOOOOOOOOOOOOOOOOOOOOOOOOOOOOOOOOO |
| Second Source Change |  |  |  |  |  |  |  |  |  |
| Item | Location | Change Type | Foxconn P/N | Part Description | Manufacturer Full Name | Manufacturer P/N | RoHS | Sheet |  |
| OOOOOOOOOOOOOOOOOOOOOOOOOOOOOOOOOOOOOOOOOOOOOOOOOOOOOOOOOOOOOOOOOOOOOOOOOOOOOOOOOOOOOOOOOO | OOOOOOOOOOOOOOOOOOOOOOOOOOOOOOOOOOOOOOOOOOOOOOOOOOOOOOOOOOOOOOOOOOOOOOOOOOOOOOOOOOOOOOOOOO | OOOOOOOOOOOOOOOOOOOOOOOOOOOOOOOOOOOOOOOOOOOOOOOOOOOOOOOOOOOOOOOOOOOOOOOOOOOOOOOOOOOOOOOOOO | OOOOOOOOOOOOOOOOOOOOOOOOOOOOOOOOOOOOOOOOOOOOOOOOOOOOOOOOOOOOOOOOOOOOOOOOOOOOOOOOOOOOOOOOOO | OOOOOOOOOOOOOOOOOOOOOOOOOOOOOOOOOOOOOOOOOOOOOOOOOOOOOOOOOOOOOOOOOOOOOOOOOOOOOOOOOOOOOOOOOO | OOOOOOOOOOOOOOOOOOOOOOOOOOOOOOOOOOOOOOOOOOOOOOOOOOOOOOOOOOOOOOOOOOOOOOOOOOOOOOOOOOOOOOOOOO | OOOOOOOOOOOOOOOOOOOOOOOOOOOOOOOOOOOOOOOOOOOOOOOOOOOOOOOOOOOOOOOOOOOOOOOOOOOOOOOOOOOOOOOOOO | OOOOOOOOOOOOOOOOOOOOOOOOOOOOOOOOOOOOOOOOOOOOOOOOOOOOOOOOOOOOOOOOOOOOOOOOOOOOOOOOOOOOOOOOOO | OOOOOOOOOOOOOOOOOOOOOOOOOOOOOOOOOOOOOOOOOOOOOOOOOOOOOOOOOOOOOOOOOOOOOOOOOOOOOOOOOOOOOOOOOO | OOOOOOOOOOOOOOOOOOOOOOOOOOOOOOOOOOOOOOOOOOOOOOOOOOOOOOOOOOOOOOOOOOOOOOOOOOOOOOOOOOOOOOOOOO |
| Master Materials Change |  |  |  |  |  |  |  |  |  |
| Item | Foxconn P/N | Orig._Usage | New_Usage | Part Description | Manufacturer Full Name | Manufacturer P/N | RoHS | Location | Sheet |
| 1 | 620106200-015-G | 42 | 38 | CAP,10nF,+/-10%,X7R,16V,G,SMD0402 | MURATA ELEC. NORTH AMERICA | GRM155R71C103KA01D | Y | (-)C2092,C2120,C2121,C2122 | PWA BOM |
| 2 | 610114U00-017-G | 25 | 21 | RES,3.3KOhm,+/-1%,1/16W,G,SMD0402 | KOA SPEER ELECTRONICS, INC. | RK73H1ETTP3301F | N | (-)R1425,R1516,R1517,R1518 | PWA BOM |
| 3 | UCD90160RGCR-C13 | 0 | 1 | IC,Power Controller,UCD90160RGCR,G,VQFN-64,SMD | TEXAS INSTRUMENTS | UCD90160RGCR-C13 |  | (+)U5 | PWA BOM |
| 4 | 620108100-015-G | 2 | 0 | CAP,15pF,+/-5%,NPO(C0G),50V,G,SMD0402 | MURATA ELEC. NORTH AMERICA | GRM1555C1H150J | N | (-)C2008,C2010 | PWA BOM |
| 5 | 320241C00-183-G | 1 | 0 | IC,Power Controller,UCD90160RGCR,G,VQFN-64,SMD | TEXAS INSTRUMENTS | UCD90160RGCR |  | (-)U5 | PWA BOM |
| OOOOOOOOOOOOOOOOOOOOOOOOOOOOOOOOOOOOOOOOOOOOOOOOOOOOOOOOOOOOOOOOOOOOOOOOOOOOOOOOOOOOOOOOOO | OOOOOOOOOOOOOOOOOOOOOOOOOOOOOOOOOOOOOOOOOOOOOOOOOOOOOOOOOOOOOOOOOOOOOOOOOOOOOOOOOOOOOOOOOO | OOOOOOOOOOOOOOOOOOOOOOOOOOOOOOOOOOOOOOOOOOOOOOOOOOOOOOOOOOOOOOOOOOOOOOOOOOOOOOOOOOOOOOOOOO | OOOOOOOOOOOOOOOOOOOOOOOOOOOOOOOOOOOOOOOOOOOOOOOOOOOOOOOOOOOOOOOOOOOOOOOOOOOOOOOOOOOOOOOOOO | OOOOOOOOOOOOOOOOOOOOOOOOOOOOOOOOOOOOOOOOOOOOOOOOOOOOOOOOOOOOOOOOOOOOOOOOOOOOOOOOOOOOOOOOOO | OOOOOOOOOOOOOOOOOOOOOOOOOOOOOOOOOOOOOOOOOOOOOOOOOOOOOOOOOOOOOOOOOOOOOOOOOOOOOOOOOOOOOOOOOO | OOOOOOOOOOOOOOOOOOOOOOOOOOOOOOOOOOOOOOOOOOOOOOOOOOOOOOOOOOOOOOOOOOOOOOOOOOOOOOOOOOOOOOOOOO | OOOOOOOOOOOOOOOOOOOOOOOOOOOOOOOOOOOOOOOOOOOOOOOOOOOOOOOOOOOOOOOOOOOOOOOOOOOOOOOOOOOOOOOOOO | OOOOOOOOOOOOOOOOOOOOOOOOOOOOOOOOOOOOOOOOOOOOOOOOOOOOOOOOOOOOOOOOOOOOOOOOOOOOOOOOOOOOOOOOOO |  |
| TLA Parts Change |  |  |  |  |  |  |  |  |  |
| Item | Foxconn P/N | Qty | Part Description | Manufacturer Full Name | Manufacturer P/N | RoHS | Location | Remark |  |
| BOM Change List Date:Fri Sep 29 16:21:39 GMT+08:00 2017 |  |  |  |  |  |  |  |  |  |
| New BOM file : E:\barreleye g2\0928\BARRELEYE_G2-MB-PVT-X04-HW-BOM-X19_20170929.xls |  |  |  |  |  |  |  |  |  |
| Old BOM file : E:\barreleye g2\0928\BG2 0913.xls |  |  |  |  |  |  |  |  |  |
| ##### Add Parts |  |  |  |  |  |  |  |  |  |
| Item | Location | Qty | Foxconn P/N | Part Description | Manufacturer Full Name | Manufacturer P/N | RoHS | Sheet |  |
| ##### Remove Parts |  |  |  |  |  |  |  |  |  |
| Item | Location | Qty | Foxconn P/N | Part Description | Manufacturer Full Name | Manufacturer P/N | RoHS | Sheet |  |
| 1 | C2092,C2120,C2121,C2122 | 4 | 620106200-015-G | CAP,10nF,+/-10%,X7R,16V,G,SMD0402 | MURATA ELEC. NORTH AMERICA | GRM155R71C103KA01D | G | PWA BOM |  |
|  |  |  | 620106200-012-G | CAP,10nF,+/-10%,X7R,16V,G,SMD0402 | WALSIN TECHNOLOGY CORPORATION | 0402B103K160CT | G | PWA BOM |  |
|  |  |  | 620106200-026-G | CAP,10nF,+/-10%,X7R,16V,G,SMD0402 | SAMSUNG SEMICONDUCTOR | CL05B103KO5NNNC | G | PWA BOM |  |
|  |  |  | 620106200-023-G | CAP,10nF,+/-10%,X7R,16V,G,SMD0402 | TAIYO ELECTRIC IND.CO.LTD | EMK105B7103KV-F | G | PWA BOM |  |
| 2 | C2008,C2010 | 2 | 620108100-015-G | CAP,15pF,+/-5%,NPO(C0G),50V,G,SMD0402 | MURATA ELEC. NORTH AMERICA | GRM1555C1H150J | G | PWA BOM |  |
|  |  |  | 620108100-011-G | CAP,15pF,+/-5%,NPO(C0G),50V,G,SMD0402 | YAGEO CORPORATION COMPONENT | CC0402JRNPO9BN150 | G | PWA BOM |  |
|  |  |  | 620108100-012-G | CAP,15pF,+/-5%,NPO(C0G),50V,G,SMD0402 | WALSIN TECHNOLOGY CORPORATION | 0402N150J500LT | G | PWA BOM |  |
|  |  |  | 620108100-023-G | CAP,15pF,+/-5%,NPO(C0G),50V,G,SMD0402 | TAIYO ELECTRIC IND.CO.LTD | UMK105CG150JV-F | G | PWA BOM |  |
|  |  |  | 620108100-025-G | CAP,15pF,+/-5%,NPO(C0G),50V,G,SMD0402 | KEMET ELECTRONICS CORPORATION | C0402C150J5GAC | G | PWA BOM |  |
|  |  |  | 620108100-026-G | CAP,15pF,+/-5%,NPO(C0G),50V,G,SMD0402 | SAMSUNG SEMICONDUCTOR | CL05C150JB5NNNC | G | PWA BOM |  |
| 3 | R1425,R1516,R1517,R1518 | 4 | 610114U00-017-G | RES,3.3KOhm,+/-1%,1/16W,G,SMD0402 | KOA SPEER ELECTRONICS, INC. | RK73H1ETTP3301F | G | PWA BOM |  |
|  |  |  | 610114U00-012-G | RES,3.3KOhm,+/-1%,1/16W,G,SMD0402 | WALSIN TECHNOLOGY CORPORATION | WR04X3301FTL | G | PWA BOM |  |
|  |  |  | 610114U00-011-G | RES,3.3KOhm,+/-1%,1/16W,G,SMD0402 | YAGEO CORPORATION COMPONENT | RC0402FR-073K3L | G | PWA BOM |  |
|  |  |  | 610114U00-044-G | RES,3.3KOhm,+/-1%,1/16W,G,SMD0402 | TA-I TECHNOLOGY CO., LTD | RM04FTN3301 | G | PWA BOM |  |
|  |  |  | 610114U00-024-G | RES,3.3KOhm,+/-1%,1/16W,G,SMD0402 | PANASONIC INDUSTRIAL CO.,LTD. | ERJ2RKF3301X | G | PWA BOM |  |
| ##### Change Parts |  |  |  |  |  |  |  |  |  |
| Item | Location | Qty | Foxconn P/N | Part Description | Manufacturer Full Name | Manufacturer P/N | RoHS | Sheet | Remark |
| 1 | QN1 | 1 | 510507500-185-G | MOS N/P,FDC6327C,20V,2.7/1.9A,80m/170m@4.5V,G,SuperSOT-6,SMD | FAIRCHILD SEMICONDUCTOR CORP | FDC6327C | G | PWA BOM | In New BOM |
|  |  |  | 51050BG00-223-G | MOS N/P,NTGD4167CT1G,30V,2.9/2.2A,90m/170m@4.5V,G,TSOP-6,SMD | ON SEMICONDUCTOR CORP | NTGD4167CT1G | G | PWA BOM | In New BOM |
|  |  |  | 51050LB00-237-G | MOS N/N,DMC2038LVT,+/-20V,4.5A/-3.1A,35m@4.5V,G,TSOT-6,SMD | DIODES INCORPORATION | DMC2038LVT | G | PWA BOM | In New BOM |
|  | QN1 | 1 | 510507500-185-G | MOS N/P,FDC6327C,20V,2.7/1.9A,80m/170m@4.5V,G,SuperSOT-6,SMD | FAIRCHILD SEMICONDUCTOR CORP | FDC6327C | G | PWA BOM | In Old BOM |
|  |  |  | 51050BG00-223-G | MOS N/P,NTGD4167CT1G,30V,2.9/2.2A,90m/170m@4.5V,G,TSOP-6,SMD | ON SEMICONDUCTOR CORP | NTGD4167CT1G | G | PWA BOM | In Old BOM |
|  |  |  | DMC2038LVT | MOS N/P,NTGD4167CT1G,30V,2.9/2.2A,90m/170m@4.5V,G,TSOP-6,SMD | DIODES INCORPORATION | DMC2038LVT | G | PWA BOM | In Old BOM |
| 2 | R1492 | 1 | 610118800-017-G | RES,499KOhm,+/-1%,1/8W,G,SMD0805 | KOA SPEER ELECTRONICS, INC. | RK73H2ATTD4993F | G | PWA BOM | In New BOM |
|  |  |  | 610118800-024-G | RES,499KOhm,+/-1%,1/8W,G,SMD0805 | PANASONIC INDUSTRIAL CO.,LTD. | ERJ6ENF4993V | G | PWA BOM | In New BOM |
|  |  |  | 610118800-011-G | RES,499KOhm,+/-1%,1/8W,G,SMD0805 | YAGEO CORPORATION COMPONENT | RC0805FR-07499KL | G | PWA BOM | In New BOM |
|  | R1492 | 1 | 610118800-017-G | RES,499KOhm,+/-1%,1/8W,G,SMD0805 | KOA SPEER ELECTRONICS, INC. | RK73H2ATTD4993F | G | PWA BOM | In Old BOM |
|  |  |  | 610118800-024-G | RES,499KOhm,+/-1%,1/8W,G,SMD0805 | PANASONIC INDUSTRIAL CO.,LTD. | ERJ6ENF4993V | G | PWA BOM | In Old BOM |
|  |  |  | RC0805FR-07499KL | RES,499KOhm,+/-1%,1/8W,G,SMD0805 | YAGEO CORPORATION COMPONENT | RC0805FR-07499KL | G | PWA BOM | In Old BOM |
| 3 | X1 | 1 | 71011RD00-100-G | XTAL,25MHz,+/-25ppm,20pF,G,SMD | TXC CORPORATION | 7V25000016 | G | PWA BOM | In New BOM |
|  |  |  | 71012KY00-107-G | XTAL,25MHz,+/-25ppm,20pF,G,SMD | KDS | 1N225000CC0DT | G | PWA BOM | In New BOM |
|  | X1 | 1 | 71011RD00-100-G | XTAL,25MHz,+/-25ppm,20pF,G,SMD | TXC CORPORATION | 7V25000016 | G | PWA BOM | In Old BOM |
|  |  |  | 1N225000CC0DT | XTAL,25MHz,+/-25ppm,20pF,G,SMD | KDS | 1N225000CC0DT | G | PWA BOM | In Old BOM |
| 4 | Y1 | 1 | 71020SC00-107-G | OSC,24MHz,+/-25ppm,3.3V,15pF,G,SMD | DAISHINKU CORPORATION/DAISHINKU SINGAPORE PTE LTD/KDS | 1XSE024000AR40 | G | PWA BOM | In New BOM |
|  |  |  | 710217200-16G-G | OSC,24MHz,+/-25ppm,3.3V,15pF,G,SMD | SiTime Corporation | SIT1602BI-22-33E-24.000000 | G | PWA BOM | In New BOM |
|  | Y1 | 1 | 71020SC00-107-G | OSC,24MHz,+/-25ppm,3.3V,15pF,G,SMD | DAISHINKU CORPORATION/DAISHINKU SINGAPORE PTE LTD/KDS | 1XSE024000AR40 | G | PWA BOM | In Old BOM |
|  |  |  | SIT1602BI-22-33E | OSC,24MHz,+/-25ppm,3.3V,15pF,G,SMD | SiTime Corporation | SIT1602BI-22-33E-24.000000 | G | PWA BOM | In Old BOM |
| 5 | DIMM02,DIMM04,DIMM06,DIMM09,DIMM11,DIMM13,DIMM15,DIMM16,DIMM18,DIMM20,DIMM22,DIMM25,DIMM27,DIMM29,DIMM31,DIMM00 | 16 | 34021BC00-G78-G | CONN,DDR IV,V/T,1.2V,Blu,0.85mm,15u,G,SMD-288 | FCI CONNECTORS HONGKONG LTD. | 10140702-0302K11LF | G | PWA BOM | In New BOM |
|  |  |  | 34021CD00-600-G | Memory Connector,AH58897-T2L31-3F,DDR IV,288,SMD,THERMOPLASTIC,0.85mm,15u",Blue,G | FOXCONN TECHNOLOGY CO.,LTD. | AH58897-T2L31-3F | G | PWA BOM | In New BOM |
|  |  |  | ADDR0245-K010C | CONN,DDR IV,V/T,1.2V,Blu,0.85mm,15u,G,SMD-288 | LOTES CO LTD | ADDR0245-K010C | G | PWA BOM | In New BOM |
|  |  |  | 34021DR00-317-G | CONN,2042451004,DDR IV,V/T,1.2V,288,SMD | MOLEX INCORPORATED | 204245-1004 | G | PWA BOM | In New BOM |
|  | DIMM02,DIMM04,DIMM06,DIMM09,DIMM11,DIMM13,DIMM15,DIMM16,DIMM18,DIMM20,DIMM22,DIMM25,DIMM27,DIMM29,DIMM31,DIMM00 | 16 | 34021BC00-G78-G | CONN,DDR IV,V/T,1.2V,Blu,0.85mm,15u,G,SMD-288 | FCI CONNECTORS HONGKONG LTD. | 10140702-0302K11LF | G | PWA BOM | In Old BOM |
|  |  |  | 34021CD00-600-G | Memory Connector,AH58897-T2L31-3F,DDR IV,288,SMD,THERMOPLASTIC,0.85mm,15u",Blue,G | FOXCONN TECHNOLOGY CO.,LTD. | AH58897-T2L31-3F | G | PWA BOM | In Old BOM |
|  |  |  | ADDR0245-K010C | CONN,DDR IV,V/T,1.2V,Blu,0.85mm,15u,G,SMD-288 | LOTES CO LTD | ADDR0245-K010C | G | PWA BOM | In Old BOM |
|  |  |  | 2042451004 | CONN,2042451004,DDR IV,V/T,1.2V,288,SMD | MOLEX INCORPORATED | 2042451004 | G | PWA BOM | In Old BOM |
| 6 | DIMM01,DIMM03,DIMM05,DIMM07,DIMM08,DIMM10,DIMM12,DIMM14,DIMM17,DIMM19,DIMM21,DIMM23,DIMM24,DIMM26,DIMM28,DIMM30 | 16 | 34021BD00-G78-G | CONN,DDR IV,V/T,1.2V,Bla,0.85mm,15u,G,SMD-288 | FCI CONNECTORS HONGKONG LTD. | 10140702-0301K11LF | G | PWA BOM | In New BOM |
|  |  |  | ADDR0245-P009C | CONN,DDR IV,V/T,1.2V,Bla,0.85mm,15u,G,SMD-288 | LOTES CO LTD | ADDR0245-P009C | G | PWA BOM | In New BOM |
|  |  |  | 34021CF00-600-G | Memory Connector,AH58897-T2B21-3F,DDR IV,288,SMD,THERMOPLASTIC,0.85mm,15u",Black,G | FOXCONN TECHNOLOGY CO.,LTD. | AH58897-T2B21-3F | G | PWA BOM | In New BOM |
|  |  |  | 34021DS00-317-G | CONN,2042451003,DDR IV,V/T,1.2V,288,SMD | MOLEX INCORPORATED | 204245-1003 | G | PWA BOM | In New BOM |
|  | DIMM01,DIMM03,DIMM05,DIMM07,DIMM08,DIMM10,DIMM12,DIMM14,DIMM17,DIMM19,DIMM21,DIMM23,DIMM24,DIMM26,DIMM28,DIMM30 | 16 | 34021BD00-G78-G | CONN,DDR IV,V/T,1.2V,Bla,0.85mm,15u,G,SMD-288 | FCI CONNECTORS HONGKONG LTD. | 10140702-0301K11LF | G | PWA BOM | In Old BOM |
|  |  |  | ADDR0245-P009C | CONN,DDR IV,V/T,1.2V,Bla,0.85mm,15u,G,SMD-288 | LOTES CO LTD | ADDR0245-P009C | G | PWA BOM | In Old BOM |
|  |  |  | 34021CF00-600-G | Memory Connector,AH58897-T2B21-3F,DDR IV,288,SMD,THERMOPLASTIC,0.85mm,15u",Black,G | FOXCONN TECHNOLOGY CO.,LTD. | AH58897-T2B21-3F | G | PWA BOM | In Old BOM |
|  |  |  | 2042451003 | CONN,2042451003,DDR IV,V/T,1.2V,288,SMD | MOLEX INCORPORATED | 2042451003 | G | PWA BOM | In Old BOM |
| 7 | PBMU1,PBFU1,PBEU1,PBAU1,PAMU1,PAFU1,PAEU1,PAAU1 | 8 | 320242200-230-G | IC,PWM Controller,ISL68137IRAZ-T,G,QFN-48,SMD | INTERSIL CORPORATION | ISL68137IRAZ-T | G | PWA BOM | In New BOM |
|  | PBMU1,PBFU1,PBEU1,PBAU1,PAMU1,PAFU1,PAEU1,PAAU1 | 8 | ISL68137IRAZ-GG04 | IC,PWM Controller,ISL68137IRAZ-T,G,QFN-48,SMD | INTERSIL CORPORATION | ISL68137IRAZ-GG04 | G | PWA BOM | In Old BOM |
| 8 | U60 | 1 | 21050P200-031-G | IC,NXP,PCF8523TK,G,HVSON-8,SMD | NXP SEMICONDUCTORS | PCF8523TK | G | PWA BOM | In New BOM |
|  | U60 | 1 | PCF8523TK/1 | IC,NXP,PCF8523TK/1,G,HVSON-8,SMD | NXP SEMICONDUCTORS | PCF8523TK/1 | G | PWA BOM | In Old BOM |
| ##### Change Revision |  |  |  |  |  |  |  |  |  |
| Sheet | REV OF BOM | CUSTOMER | CUSTOMER P/N | PWA PN | PWA DESCRIPTION | PWA REV | DATE | Remark |  |
| OOOOOOOOOOOOOOOOOOOOOOOOOOOOOOOOOOOOOOOOOOOOOOOOOOOOOOOOOOOOOOOOOOOOOOOOOOOOOOOOOOOOOOOOOO | OOOOOOOOOOOOOOOOOOOOOOOOOOOOOOOOOOOOOOOOOOOOOOOOOOOOOOOOOOOOOOOOOOOOOOOOOOOOOOOOOOOOOOOOOO | OOOOOOOOOOOOOOOOOOOOOOOOOOOOOOOOOOOOOOOOOOOOOOOOOOOOOOOOOOOOOOOOOOOOOOOOOOOOOOOOOOOOOOOOOO | OOOOOOOOOOOOOOOOOOOOOOOOOOOOOOOOOOOOOOOOOOOOOOOOOOOOOOOOOOOOOOOOOOOOOOOOOOOOOOOOOOOOOOOOOO | OOOOOOOOOOOOOOOOOOOOOOOOOOOOOOOOOOOOOOOOOOOOOOOOOOOOOOOOOOOOOOOOOOOOOOOOOOOOOOOOOOOOOOOOOO | OOOOOOOOOOOOOOOOOOOOOOOOOOOOOOOOOOOOOOOOOOOOOOOOOOOOOOOOOOOOOOOOOOOOOOOOOOOOOOOOOOOOOOOOOO | OOOOOOOOOOOOOOOOOOOOOOOOOOOOOOOOOOOOOOOOOOOOOOOOOOOOOOOOOOOOOOOOOOOOOOOOOOOOOOOOOOOOOOOOOO | OOOOOOOOOOOOOOOOOOOOOOOOOOOOOOOOOOOOOOOOOOOOOOOOOOOOOOOOOOOOOOOOOOOOOOOOOOOOOOOOOOOOOOOOOO | OOOOOOOOOOOOOOOOOOOOOOOOOOOOOOOOOOOOOOOOOOOOOOOOOOOOOOOOOOOOOOOOOOOOOOOOOOOOOOOOOOOOOOOOOO | OOOOOOOOOOOOOOOOOOOOOOOOOOOOOOOOOOOOOOOOOOOOOOOOOOOOOOOOOOOOOOOOOOOOOOOOOOOOOOOOOOOOOOOOOO |
| Second Source Change |  |  |  |  |  |  |  |  |  |
| Item | Location | Change Type | Foxconn P/N | Part Description | Manufacturer Full Name | Manufacturer P/N | RoHS | Sheet |  |
| 1 | PCB |  | 0101FBQ00-000-G | PCB,Zaius-MB PVT-X04,OSP,Gre,22L,22.20*13.00,G | GOLD CIRCUIT ELECTRONICS LTD. | 0101FBQ00-000-G | G | PWA BOM |  |
|  |  | ADD | 0101FBQ00-000-G-1 | PCB,Zaius-MB PVT-X04,OSP,Gre,22L,22.20*13.00,G | ZHUHAI FOUNDER PRINTED CIRCUIT BOARD（HK） DEVELOPMENT LIMITED | 0101FBQ00-000-G-1 | G | PWA BOM |  |
| 2 | QN1 |  | 510507500-185-G | MOS N/P,FDC6327C,20V,2.7/1.9A,80m/170m@4.5V,G,SuperSOT-6,SMD | FAIRCHILD SEMICONDUCTOR CORP | FDC6327C | G | PWA BOM |  |
|  |  | NO | 51050BG00-223-G | MOS N/P,NTGD4167CT1G,30V,2.9/2.2A,90m/170m@4.5V,G,TSOP-6,SMD | ON SEMICONDUCTOR CORP | NTGD4167CT1G | G | PWA BOM |  |
|  |  | ADD | 51050LB00-237-G | MOS N/N,DMC2038LVT,+/-20V,4.5A/-3.1A,35m@4.5V,G,TSOT-6,SMD | DIODES INCORPORATION | DMC2038LVT | G | PWA BOM |  |
|  |  | Delete | DMC2038LVT | MOS N/P,NTGD4167CT1G,30V,2.9/2.2A,90m/170m@4.5V,G,TSOP-6,SMD | DIODES INCORPORATION | DMC2038LVT | G | PWA BOM |  |
| 3 | R1492 |  | 610118800-017-G | RES,499KOhm,+/-1%,1/8W,G,SMD0805 | KOA SPEER ELECTRONICS, INC. | RK73H2ATTD4993F | G | PWA BOM |  |
|  |  | NO | 610118800-024-G | RES,499KOhm,+/-1%,1/8W,G,SMD0805 | PANASONIC INDUSTRIAL CO.,LTD. | ERJ6ENF4993V | G | PWA BOM |  |
|  |  | ADD | 610118800-011-G | RES,499KOhm,+/-1%,1/8W,G,SMD0805 | YAGEO CORPORATION COMPONENT | RC0805FR-07499KL | G | PWA BOM |  |
|  |  | Delete | RC0805FR-07499KL | RES,499KOhm,+/-1%,1/8W,G,SMD0805 | YAGEO CORPORATION COMPONENT | RC0805FR-07499KL | G | PWA BOM |  |
| 4 | X1 |  | 71011RD00-100-G | XTAL,25MHz,+/-25ppm,20pF,G,SMD | TXC CORPORATION | 7V25000016 | G | PWA BOM |  |
|  |  | ADD | 71012KY00-107-G | XTAL,25MHz,+/-25ppm,20pF,G,SMD | KDS | 1N225000CC0DT | G | PWA BOM |  |
|  |  | Delete | 1N225000CC0DT | XTAL,25MHz,+/-25ppm,20pF,G,SMD | KDS | 1N225000CC0DT | G | PWA BOM |  |
| 5 | Y1 |  | 71020SC00-107-G | OSC,24MHz,+/-25ppm,3.3V,15pF,G,SMD | DAISHINKU CORPORATION/DAISHINKU SINGAPORE PTE LTD/KDS | 1XSE024000AR40 | G | PWA BOM |  |
|  |  | ADD | 710217200-16G-G | OSC,24MHz,+/-25ppm,3.3V,15pF,G,SMD | SiTime Corporation | SIT1602BI-22-33E-24.000000 | G | PWA BOM |  |
|  |  | Delete | SIT1602BI-22-33E | OSC,24MHz,+/-25ppm,3.3V,15pF,G,SMD | SiTime Corporation | SIT1602BI-22-33E-24.000000 | G | PWA BOM |  |
| 6 | DIMM02,DIMM04,DIMM06,DIMM09,DIMM11,DIMM13,DIMM15,DIMM16,DIMM18,DIMM20,DIMM22,DIMM25,DIMM27,DIMM29,DIMM31,DIMM00 |  | 34021BC00-G78-G | CONN,DDR IV,V/T,1.2V,Blu,0.85mm,15u,G,SMD-288 | FCI CONNECTORS HONGKONG LTD. | 10140702-0302K11LF | G | PWA BOM |  |
|  |  | NO | 34021CD00-600-G | Memory Connector,AH58897-T2L31-3F,DDR IV,288,SMD,THERMOPLASTIC,0.85mm,15u",Blue,G | FOXCONN TECHNOLOGY CO.,LTD. | AH58897-T2L31-3F | G | PWA BOM |  |
|  |  | NO | ADDR0245-K010C | CONN,DDR IV,V/T,1.2V,Blu,0.85mm,15u,G,SMD-288 | LOTES CO LTD | ADDR0245-K010C | G | PWA BOM |  |
|  |  | ADD | 34021DR00-317-G | CONN,2042451004,DDR IV,V/T,1.2V,288,SMD | MOLEX INCORPORATED | 204245-1004 | G | PWA BOM |  |
|  |  | Delete | 2042451004 | CONN,2042451004,DDR IV,V/T,1.2V,288,SMD | MOLEX INCORPORATED | 2042451004 | G | PWA BOM |  |
| 7 | DIMM01,DIMM03,DIMM05,DIMM07,DIMM08,DIMM10,DIMM12,DIMM14,DIMM17,DIMM19,DIMM21,DIMM23,DIMM24,DIMM26,DIMM28,DIMM30 |  | 34021BD00-G78-G | CONN,DDR IV,V/T,1.2V,Bla,0.85mm,15u,G,SMD-288 | FCI CONNECTORS HONGKONG LTD. | 10140702-0301K11LF | G | PWA BOM |  |
|  |  | NO | ADDR0245-P009C | CONN,DDR IV,V/T,1.2V,Bla,0.85mm,15u,G,SMD-288 | LOTES CO LTD | ADDR0245-P009C | G | PWA BOM |  |
|  |  | NO | 34021CF00-600-G | Memory Connector,AH58897-T2B21-3F,DDR IV,288,SMD,THERMOPLASTIC,0.85mm,15u",Black,G | FOXCONN TECHNOLOGY CO.,LTD. | AH58897-T2B21-3F | G | PWA BOM |  |
|  |  | ADD | 34021DS00-317-G | CONN,2042451003,DDR IV,V/T,1.2V,288,SMD | MOLEX INCORPORATED | 204245-1003 | G | PWA BOM |  |
|  |  | Delete | 2042451003 | CONN,2042451003,DDR IV,V/T,1.2V,288,SMD | MOLEX INCORPORATED | 2.042451003E9 | G | PWA BOM |  |
| OOOOOOOOOOOOOOOOOOOOOOOOOOOOOOOOOOOOOOOOOOOOOOOOOOOOOOOOOOOOOOOOOOOOOOOOOOOOOOOOOOOOOOOOOO | OOOOOOOOOOOOOOOOOOOOOOOOOOOOOOOOOOOOOOOOOOOOOOOOOOOOOOOOOOOOOOOOOOOOOOOOOOOOOOOOOOOOOOOOOO | OOOOOOOOOOOOOOOOOOOOOOOOOOOOOOOOOOOOOOOOOOOOOOOOOOOOOOOOOOOOOOOOOOOOOOOOOOOOOOOOOOOOOOOOOO | OOOOOOOOOOOOOOOOOOOOOOOOOOOOOOOOOOOOOOOOOOOOOOOOOOOOOOOOOOOOOOOOOOOOOOOOOOOOOOOOOOOOOOOOOO | OOOOOOOOOOOOOOOOOOOOOOOOOOOOOOOOOOOOOOOOOOOOOOOOOOOOOOOOOOOOOOOOOOOOOOOOOOOOOOOOOOOOOOOOOO | OOOOOOOOOOOOOOOOOOOOOOOOOOOOOOOOOOOOOOOOOOOOOOOOOOOOOOOOOOOOOOOOOOOOOOOOOOOOOOOOOOOOOOOOOO | OOOOOOOOOOOOOOOOOOOOOOOOOOOOOOOOOOOOOOOOOOOOOOOOOOOOOOOOOOOOOOOOOOOOOOOOOOOOOOOOOOOOOOOOOO | OOOOOOOOOOOOOOOOOOOOOOOOOOOOOOOOOOOOOOOOOOOOOOOOOOOOOOOOOOOOOOOOOOOOOOOOOOOOOOOOOOOOOOOOOO | OOOOOOOOOOOOOOOOOOOOOOOOOOOOOOOOOOOOOOOOOOOOOOOOOOOOOOOOOOOOOOOOOOOOOOOOOOOOOOOOOOOOOOOOOO | OOOOOOOOOOOOOOOOOOOOOOOOOOOOOOOOOOOOOOOOOOOOOOOOOOOOOOOOOOOOOOOOOOOOOOOOOOOOOOOOOOOOOOOOOO |
| Master Materials Change |  |  |  |  |  |  |  |  |  |
| Item | Foxconn P/N | Orig._Usage | New_Usage | Part Description | Manufacturer Full Name | Manufacturer P/N | RoHS | Location | Sheet |
| 1 | 620106200-015-G | 42 | 38 | CAP,10nF,+/-10%,X7R,16V,G,SMD0402 | MURATA ELEC. NORTH AMERICA | GRM155R71C103KA01D | G | (-)C2092,C2120,C2121,C2122 | PWA BOM |
|  | 620106200-012-G |  |  | CAP,10nF,+/-10%,X7R,16V,G,SMD0402 | WALSIN TECHNOLOGY CORPORATION | 0402B103K160CT |  |  | PWA BOM |
|  | 620106200-026-G |  |  | CAP,10nF,+/-10%,X7R,16V,G,SMD0402 | SAMSUNG SEMICONDUCTOR | CL05B103KO5NNNC |  |  | PWA BOM |
|  | 620106200-023-G |  |  | CAP,10nF,+/-10%,X7R,16V,G,SMD0402 | TAIYO ELECTRIC IND.CO.LTD | EMK105B7103KV-F |  |  | PWA BOM |
| 2 | 320242200-230-G | 0 | 8 | IC,PWM Controller,ISL68137IRAZ-T,G,QFN-48,SMD | INTERSIL CORPORATION | ISL68137IRAZ-T | G | (+)PBMU1,PBFU1,PBEU1,PBAU1,PAMU1,PAFU1,PAEU1,PAAU1 | PWA BOM |
| 3 | 610114U00-017-G | 25 | 21 | RES,3.3KOhm,+/-1%,1/16W,G,SMD0402 | KOA SPEER ELECTRONICS, INC. | RK73H1ETTP3301F | G | (-)R1425,R1516,R1517,R1518 | PWA BOM |
|  | 610114U00-012-G |  |  | RES,3.3KOhm,+/-1%,1/16W,G,SMD0402 | WALSIN TECHNOLOGY CORPORATION | WR04X3301FTL |  |  | PWA BOM |
|  | 610114U00-011-G |  |  | RES,3.3KOhm,+/-1%,1/16W,G,SMD0402 | YAGEO CORPORATION COMPONENT | RC0402FR-073K3L |  |  | PWA BOM |
|  | 610114U00-044-G |  |  | RES,3.3KOhm,+/-1%,1/16W,G,SMD0402 | TA-I TECHNOLOGY CO., LTD | RM04FTN3301 |  |  | PWA BOM |
|  | 610114U00-024-G |  |  | RES,3.3KOhm,+/-1%,1/16W,G,SMD0402 | PANASONIC INDUSTRIAL CO.,LTD. | ERJ2RKF3301X |  |  | PWA BOM |
| 4 | 21050P200-031-G | 0 | 1 | IC,NXP,PCF8523TK,G,HVSON-8,SMD | NXP SEMICONDUCTORS | PCF8523TK | G | (+)U60 | PWA BOM |
| 5 | 620108100-015-G | 2 | 0 | CAP,15pF,+/-5%,NPO(C0G),50V,G,SMD0402 | MURATA ELEC. NORTH AMERICA | GRM1555C1H150J | G | (-)C2008,C2010 | PWA BOM |
|  | 620108100-011-G |  |  | CAP,15pF,+/-5%,NPO(C0G),50V,G,SMD0402 | YAGEO CORPORATION COMPONENT | CC0402JRNPO9BN150 |  |  | PWA BOM |
|  | 620108100-012-G |  |  | CAP,15pF,+/-5%,NPO(C0G),50V,G,SMD0402 | WALSIN TECHNOLOGY CORPORATION | 0402N150J500LT |  |  | PWA BOM |
|  | 620108100-023-G |  |  | CAP,15pF,+/-5%,NPO(C0G),50V,G,SMD0402 | TAIYO ELECTRIC IND.CO.LTD | UMK105CG150JV-F |  |  | PWA BOM |
|  | 620108100-025-G |  |  | CAP,15pF,+/-5%,NPO(C0G),50V,G,SMD0402 | KEMET ELECTRONICS CORPORATION | C0402C150J5GAC |  |  | PWA BOM |
|  | 620108100-026-G |  |  | CAP,15pF,+/-5%,NPO(C0G),50V,G,SMD0402 | SAMSUNG SEMICONDUCTOR | CL05C150JB5NNNC |  |  | PWA BOM |
| 6 | ISL68137IRAZ-GG04 | 8 | 0 | IC,PWM Controller,ISL68137IRAZ-T,G,QFN-48,SMD | INTERSIL CORPORATION | ISL68137IRAZ-GG04 | G | (-)PBMU1,PBFU1,PBEU1,PBAU1,PAMU1,PAFU1,PAEU1,PAAU1 | PWA BOM |
| 7 | PCF8523TK/1 | 1 | 0 | IC,NXP,PCF8523TK/1,G,HVSON-8,SMD | NXP SEMICONDUCTORS | PCF8523TK/1 | G | (-)U60 | PWA BOM |
| OOOOOOOOOOOOOOOOOOOOOOOOOOOOOOOOOOOOOOOOOOOOOOOOOOOOOOOOOOOOOOOOOOOOOOOOOOOOOOOOOOOOOOOOOO | OOOOOOOOOOOOOOOOOOOOOOOOOOOOOOOOOOOOOOOOOOOOOOOOOOOOOOOOOOOOOOOOOOOOOOOOOOOOOOOOOOOOOOOOOO | OOOOOOOOOOOOOOOOOOOOOOOOOOOOOOOOOOOOOOOOOOOOOOOOOOOOOOOOOOOOOOOOOOOOOOOOOOOOOOOOOOOOOOOOOO | OOOOOOOOOOOOOOOOOOOOOOOOOOOOOOOOOOOOOOOOOOOOOOOOOOOOOOOOOOOOOOOOOOOOOOOOOOOOOOOOOOOOOOOOOO | OOOOOOOOOOOOOOOOOOOOOOOOOOOOOOOOOOOOOOOOOOOOOOOOOOOOOOOOOOOOOOOOOOOOOOOOOOOOOOOOOOOOOOOOOO | OOOOOOOOOOOOOOOOOOOOOOOOOOOOOOOOOOOOOOOOOOOOOOOOOOOOOOOOOOOOOOOOOOOOOOOOOOOOOOOOOOOOOOOOOO | OOOOOOOOOOOOOOOOOOOOOOOOOOOOOOOOOOOOOOOOOOOOOOOOOOOOOOOOOOOOOOOOOOOOOOOOOOOOOOOOOOOOOOOOOO | OOOOOOOOOOOOOOOOOOOOOOOOOOOOOOOOOOOOOOOOOOOOOOOOOOOOOOOOOOOOOOOOOOOOOOOOOOOOOOOOOOOOOOOOOO | OOOOOOOOOOOOOOOOOOOOOOOOOOOOOOOOOOOOOOOOOOOOOOOOOOOOOOOOOOOOOOOOOOOOOOOOOOOOOOOOOOOOOOOOOO |  |
| TLA Parts Change |  |  |  |  |  |  |  |  |  |
| Item | Foxconn P/N | Qty | Part Description | Manufacturer Full Name | Manufacturer P/N | RoHS | Location | Remark |  |
| BOM Change List Date:Tue Oct 24 08:38:42 GMT+08:00 2017 |  |  |  |  |  |  |  |  |  |
| New BOM file : E:\barreleye g2\1021\BG2 1021.xls |  |  |  |  |  |  |  |  |  |
| Old BOM file : E:\barreleye g2\1021\BG2 0929.xls |  |  |  |  |  |  |  |  |  |
| ##### Add Parts |  |  |  |  |  |  |  |  |  |
| Item | Location | Qty | Foxconn P/N | Part Description | Manufacturer Full Name | Manufacturer P/N | RoHS | Sheet |  |
| ##### Remove Parts |  |  |  |  |  |  |  |  |  |
| Item | Location | Qty | Foxconn P/N | Part Description | Manufacturer Full Name | Manufacturer P/N | RoHS | Sheet |  |
| ##### Change Parts |  |  |  |  |  |  |  |  |  |
| Item | Location | Qty | Foxconn P/N | Part Description | Manufacturer Full Name | Manufacturer P/N | RoHS | Sheet | Remark |
| 1 | PUAC4,PSAC4,PRAC4,PQAC4,PPAC4,PIAC4,PFAC4,PEAC4,PUAC5,PSAC5,PRAC5,PQAC5,PPAC5,PIAC5,PFAC5,PEAC5,PUAC6,PSAC6,PRAC6,PQAC6,PPAC6,PIAC6,PFAC6,PEAC6 | 24 | 62011DD00-015-G | CAP,22uF,+/-10%,X6S,6.3V,G,SMD1206 | MURATA ELEC. NORTH AMERICA | GRM31CC80J226K | G | PWA BOM | In New BOM |
|  |  |  | CL31X226KQHNNNE | CAP,22uF,+/-10%,X6S,6.3V,G,SMD1206 | SAMSUNG SEMICONDUCTOR | CL31X226KQHNNNE | G | PWA BOM | In New BOM |
|  | PUAC4,PSAC4,PRAC4,PQAC4,PPAC4,PIAC4,PFAC4,PEAC4,PUAC5,PSAC5,PRAC5,PQAC5,PPAC5,PIAC5,PFAC5,PEAC5,PUAC6,PSAC6,PRAC6,PQAC6,PPAC6,PIAC6,PFAC6,PEAC6 | 24 | 62011DD00-015-G | CAP,22uF,+/-10%,X6S,6.3V,G,SMD1206 | MURATA ELEC. NORTH AMERICA | GRM31CC80J226K | G | PWA BOM | In Old BOM |
| 2 | PSIC4,PETC4,PERC4,PSIC5,PETC5,PERC5,PSIC6,PETC6,PERC6,PETC22 | 10 | 62013BP00-015-G | CAP,22uF,+/-20%,X6S,25V,G,SMD1206 | MURATA ELEC. NORTH AMERICA | GRM31CC81E226ME11L | G | PWA BOM | In New BOM |
|  |  |  | 62013BP00-011-G | CAP,22uF,+/-20%,X6S,25V,G,SMD1206 | YAGEO CORPORATION COMPONENT | CC1206MKX6S8BB226 | G | PWA BOM | In New BOM |
|  | PSIC4,PETC4,PERC4,PSIC5,PETC5,PERC5,PSIC6,PETC6,PERC6,PETC22 | 10 | 62013BP00-015-G | CAP,22uF,+/-20%,X6S,25V,G,SMD1206 | MURATA ELEC. NORTH AMERICA | GRM31CC81E226ME11L | G | PWA BOM | In Old BOM |
| 3 | PETC3 | 1 | 62011LT01-015-G | CAP,130pF,+/-5%,NPO(C0G),50V,G,SMD0402 | MURATA ELEC. NORTH AMERICA | GRM1555C1H131JA01D | G | PWA BOM | In New BOM |
|  |  |  | 62011LT00-011-G | CAP,130pF,+/-5%,NPO(C0G),50V,G,SMD0402 | YAGEO CORPORATION COMPONENT | CC0402JRNPO9BN131 | G | PWA BOM | In New BOM |
|  |  |  | 62011LT00-012-G | CAP,130pF,+/-5%,NPO(C0G),50V,G,SMD0402 | WALSIN TECHNOLOGY CORPORATION | 0402N131J500LT | G | PWA BOM | In New BOM |
|  | PETC3 | 1 | 62011LT01-015-G | CAP,130pF,+/-5%,NPO(C0G),50V,G,SMD0402 | MURATA ELEC. NORTH AMERICA | GRM1555C1H131JA01D | G | PWA BOM | In Old BOM |
| 4 | PSIC3 | 1 | 62011LY01-015-G | CAP,160pF,+/-5%,NPO(C0G),50V,G,SMD0402 | MURATA ELEC. NORTH AMERICA | GRM1555C1H161JA01D | G | PWA BOM | In New BOM |
|  |  |  | 62011LY00-012-G | CAP,MLCC,160pF,+/-5%,NPO(C0G),50V,SMD0402,G | WALSIN TECHNOLOGY CORPORATION | 0402N161J500LT | G | PWA BOM | In New BOM |
|  |  |  | 62011LY00-011-G | CAP,MLCC,160pF,+/-5%,NPO(C0G),50V,SMD0402,G | YAGEO CORPORATION COMPONENT | CC0402JRNPO9BN161 | G | PWA BOM | In New BOM |
|  | PSIC3 | 1 | 62011LY01-015-G | CAP,160pF,+/-5%,NPO(C0G),50V,G,SMD0402 | MURATA ELEC. NORTH AMERICA | GRM1555C1H161JA01D | G | PWA BOM | In Old BOM |
| 5 | QN1 | 1 | 510507500-185-G | MOS N/P,FDC6327C,20V,2.7/1.9A,80m/170m@4.5V,G,SuperSOT-6,SMD | FAIRCHILD SEMICONDUCTOR CORP | FDC6327C | G | PWA BOM | In New BOM |
|  |  |  | 51050BG00-223-G | MOS N/P,NTGD4167CT1G,30V,2.9/2.2A,90m/170m@4.5V,G,TSOP-6,SMD | ON SEMICONDUCTOR CORP | NTGD4167CT1G | G | PWA BOM | In New BOM |
|  |  |  | 51050LB00-237-G | MOS N/P,DMC2038LVT,+/-20V,4.5A/-3.1A,35m@4.5V,G,TSOT-6,SMD | DIODES INCORPORATION | DMC2038LVT | G | PWA BOM | In New BOM |
|  | QN1 | 1 | 510507500-185-G | MOS N/P,FDC6327C,20V,2.7/1.9A,80m/170m@4.5V,G,SuperSOT-6,SMD | FAIRCHILD SEMICONDUCTOR CORP | FDC6327C | G | PWA BOM | In Old BOM |
|  |  |  | 51050BG00-223-G | MOS N/P,NTGD4167CT1G,30V,2.9/2.2A,90m/170m@4.5V,G,TSOP-6,SMD | ON SEMICONDUCTOR CORP | NTGD4167CT1G | G | PWA BOM | In Old BOM |
|  |  |  | 51050LB00-237-G | MOS N/N,DMC2038LVT,+/-20V,4.5A/-3.1A,35m@4.5V,G,TSOT-6,SMD | DIODES INCORPORATION | DMC2038LVT | G | PWA BOM | In Old BOM |
| 6 | PHAC3 | 1 | 62011DB01-015-G | CAP,1nF,+/-10%,X7R,100V,G,SMD0402 | MURATA ELEC. NORTH AMERICA | GRM155R72A102KA01D | G | PWA BOM | In New BOM |
|  |  |  | 62011DB00-011-G | CAP,1nF,+/-10%,X7R,100V,G,SMD0402 | YAGEO CORPORATION COMPONENT | CC0402KRX7R0BB102 | G | PWA BOM | In New BOM |
|  | PHAC3 | 1 | 620133600-012-G | CAP,1nF,+/-5%,X7R,100V,G,SMD0805 | WALSIN TECHNOLOGY CORPORATION | 0805B102J101CT | G | PWA BOM | In Old BOM |
|  |  |  | 620133600-015-G | CAP,1nF,+/-5%,X7R,100V,G,SMD0805 | MURATA ELEC. NORTH AMERICA | GRM219R72A102JA01D | G | PWA BOM | In Old BOM |
|  |  |  | 620133600-026-G | CAP,1nF,+/-5%,X7R,100V,G,SMD0805 | SAMSUNG SEMICONDUCTOR | CL21B102JCANNNC | G | PWA BOM | In Old BOM |
| ##### Change Revision |  |  |  |  |  |  |  |  |  |
| Sheet | REV OF BOM | CUSTOMER | CUSTOMER P/N | PWA PN | PWA DESCRIPTION | PWA REV | DATE | Remark |  |
| OOOOOOOOOOOOOOOOOOOOOOOOOOOOOOOOOOOOOOOOOOOOOOOOOOOOOOOOOOOOOOOOOOOOOOOOOOOOOOOOOOOOOOOOOO | OOOOOOOOOOOOOOOOOOOOOOOOOOOOOOOOOOOOOOOOOOOOOOOOOOOOOOOOOOOOOOOOOOOOOOOOOOOOOOOOOOOOOOOOOO | OOOOOOOOOOOOOOOOOOOOOOOOOOOOOOOOOOOOOOOOOOOOOOOOOOOOOOOOOOOOOOOOOOOOOOOOOOOOOOOOOOOOOOOOOO | OOOOOOOOOOOOOOOOOOOOOOOOOOOOOOOOOOOOOOOOOOOOOOOOOOOOOOOOOOOOOOOOOOOOOOOOOOOOOOOOOOOOOOOOOO | OOOOOOOOOOOOOOOOOOOOOOOOOOOOOOOOOOOOOOOOOOOOOOOOOOOOOOOOOOOOOOOOOOOOOOOOOOOOOOOOOOOOOOOOOO | OOOOOOOOOOOOOOOOOOOOOOOOOOOOOOOOOOOOOOOOOOOOOOOOOOOOOOOOOOOOOOOOOOOOOOOOOOOOOOOOOOOOOOOOOO | OOOOOOOOOOOOOOOOOOOOOOOOOOOOOOOOOOOOOOOOOOOOOOOOOOOOOOOOOOOOOOOOOOOOOOOOOOOOOOOOOOOOOOOOOO | OOOOOOOOOOOOOOOOOOOOOOOOOOOOOOOOOOOOOOOOOOOOOOOOOOOOOOOOOOOOOOOOOOOOOOOOOOOOOOOOOOOOOOOOOO | OOOOOOOOOOOOOOOOOOOOOOOOOOOOOOOOOOOOOOOOOOOOOOOOOOOOOOOOOOOOOOOOOOOOOOOOOOOOOOOOOOOOOOOOOO | OOOOOOOOOOOOOOOOOOOOOOOOOOOOOOOOOOOOOOOOOOOOOOOOOOOOOOOOOOOOOOOOOOOOOOOOOOOOOOOOOOOOOOOOOO |
| Second Source Change |  |  |  |  |  |  |  |  |  |
| Item | Location | Change Type | Foxconn P/N | Part Description | Manufacturer Full Name | Manufacturer P/N | RoHS | Sheet |  |
| 1 | PCB |  | 0101FBQ00-000-G | PCB,Zaius-MB PVT-X04,OSP,Gre,22L,22.20*13.00,G | GOLD CIRCUIT ELECTRONICS LTD. | 0101FBQ00-000-G | G | PWA BOM |  |
|  |  | ADD | 0101FBQ00-000-G | PCB,Zaius-MB PVT-X04,OSP,Gre,22L,22.20*13.00,G | ZHUHAI FOUNDER PRINTED CIRCUIT BOARD（HK） DEVELOPMENT LIMITED | 0101FBQ00-000-G | G | PWA BOM |  |
| 2 | PUAC4,PSAC4,PRAC4,PQAC4,PPAC4,PIAC4,PFAC4,PEAC4,PUAC5,PSAC5,PRAC5,PQAC5,PPAC5,PIAC5,PFAC5,PEAC5,PUAC6,PSAC6,PRAC6,PQAC6,PPAC6,PIAC6,PFAC6,PEAC6 |  | 62011DD00-015-G | CAP,22uF,+/-10%,X6S,6.3V,G,SMD1206 | MURATA ELEC. NORTH AMERICA | GRM31CC80J226K | G | PWA BOM |  |
|  |  | ADD | CL31X226KQHNNNE | CAP,22uF,+/-10%,X6S,6.3V,G,SMD1206 | SAMSUNG SEMICONDUCTOR | CL31X226KQHNNNE | G | PWA BOM |  |
| 3 | PSIC4,PETC4,PERC4,PSIC5,PETC5,PERC5,PSIC6,PETC6,PERC6,PETC22 |  | 62013BP00-015-G | CAP,22uF,+/-20%,X6S,25V,G,SMD1206 | MURATA ELEC. NORTH AMERICA | GRM31CC81E226ME11L | G | PWA BOM |  |
|  |  | ADD | 62013BP00-011-G | CAP,22uF,+/-20%,X6S,25V,G,SMD1206 | YAGEO CORPORATION COMPONENT | CC1206MKX6S8BB226 | G | PWA BOM |  |
| 4 | PETC3 |  | 62011LT01-015-G | CAP,130pF,+/-5%,NPO(C0G),50V,G,SMD0402 | MURATA ELEC. NORTH AMERICA | GRM1555C1H131JA01D | G | PWA BOM |  |
|  |  | ADD | 62011LT00-011-G | CAP,130pF,+/-5%,NPO(C0G),50V,G,SMD0402 | YAGEO CORPORATION COMPONENT | CC0402JRNPO9BN131 | G | PWA BOM |  |
|  |  | ADD | 62011LT00-012-G | CAP,130pF,+/-5%,NPO(C0G),50V,G,SMD0402 | WALSIN TECHNOLOGY CORPORATION | 0402N131J500LT | G | PWA BOM |  |
| 5 | PSIC3 |  | 62011LY01-015-G | CAP,160pF,+/-5%,NPO(C0G),50V,G,SMD0402 | MURATA ELEC. NORTH AMERICA | GRM1555C1H161JA01D | G | PWA BOM |  |
|  |  | ADD | 62011LY00-012-G | CAP,MLCC,160pF,+/-5%,NPO(C0G),50V,SMD0402,G | WALSIN TECHNOLOGY CORPORATION | 0402N161J500LT | G | PWA BOM |  |
|  |  | ADD | 62011LY00-011-G | CAP,MLCC,160pF,+/-5%,NPO(C0G),50V,SMD0402,G | YAGEO CORPORATION COMPONENT | CC0402JRNPO9BN161 | G | PWA BOM |  |
| OOOOOOOOOOOOOOOOOOOOOOOOOOOOOOOOOOOOOOOOOOOOOOOOOOOOOOOOOOOOOOOOOOOOOOOOOOOOOOOOOOOOOOOOOO | OOOOOOOOOOOOOOOOOOOOOOOOOOOOOOOOOOOOOOOOOOOOOOOOOOOOOOOOOOOOOOOOOOOOOOOOOOOOOOOOOOOOOOOOOO | OOOOOOOOOOOOOOOOOOOOOOOOOOOOOOOOOOOOOOOOOOOOOOOOOOOOOOOOOOOOOOOOOOOOOOOOOOOOOOOOOOOOOOOOOO | OOOOOOOOOOOOOOOOOOOOOOOOOOOOOOOOOOOOOOOOOOOOOOOOOOOOOOOOOOOOOOOOOOOOOOOOOOOOOOOOOOOOOOOOOO | OOOOOOOOOOOOOOOOOOOOOOOOOOOOOOOOOOOOOOOOOOOOOOOOOOOOOOOOOOOOOOOOOOOOOOOOOOOOOOOOOOOOOOOOOO | OOOOOOOOOOOOOOOOOOOOOOOOOOOOOOOOOOOOOOOOOOOOOOOOOOOOOOOOOOOOOOOOOOOOOOOOOOOOOOOOOOOOOOOOOO | OOOOOOOOOOOOOOOOOOOOOOOOOOOOOOOOOOOOOOOOOOOOOOOOOOOOOOOOOOOOOOOOOOOOOOOOOOOOOOOOOOOOOOOOOO | OOOOOOOOOOOOOOOOOOOOOOOOOOOOOOOOOOOOOOOOOOOOOOOOOOOOOOOOOOOOOOOOOOOOOOOOOOOOOOOOOOOOOOOOOO | OOOOOOOOOOOOOOOOOOOOOOOOOOOOOOOOOOOOOOOOOOOOOOOOOOOOOOOOOOOOOOOOOOOOOOOOOOOOOOOOOOOOOOOOOO | OOOOOOOOOOOOOOOOOOOOOOOOOOOOOOOOOOOOOOOOOOOOOOOOOOOOOOOOOOOOOOOOOOOOOOOOOOOOOOOOOOOOOOOOOO |
| Master Materials Change |  |  |  |  |  |  |  |  |  |
| Item | Foxconn P/N | Orig._Usage | New_Usage | Part Description | Manufacturer Full Name | Manufacturer P/N | RoHS | Location | Sheet |
| 1 | 62011DB01-015-G | 0 | 1 | CAP,1nF,+/-10%,X7R,100V,G,SMD0402 | MURATA ELEC. NORTH AMERICA | GRM155R72A102KA01D | G | (+)PHAC3 | PWA BOM |
|  | 62011DB00-011-G |  |  | CAP,1nF,+/-10%,X7R,100V,G,SMD0402 | YAGEO CORPORATION COMPONENT | CC0402KRX7R0BB102 |  |  | PWA BOM |
| 2 | 620133600-012-G | 1 | 0 | CAP,1nF,+/-5%,X7R,100V,G,SMD0805 | WALSIN TECHNOLOGY CORPORATION | 0805B102J101CT | G | (-)PHAC3 | PWA BOM |
|  | 620133600-015-G |  |  | CAP,1nF,+/-5%,X7R,100V,G,SMD0805 | MURATA ELEC. NORTH AMERICA | GRM219R72A102JA01D |  |  | PWA BOM |
|  | 620133600-026-G |  |  | CAP,1nF,+/-5%,X7R,100V,G,SMD0805 | SAMSUNG SEMICONDUCTOR | CL21B102JCANNNC |  |  | PWA BOM |
| OOOOOOOOOOOOOOOOOOOOOOOOOOOOOOOOOOOOOOOOOOOOOOOOOOOOOOOOOOOOOOOOOOOOOOOOOOOOOOOOOOOOOOOOOO | OOOOOOOOOOOOOOOOOOOOOOOOOOOOOOOOOOOOOOOOOOOOOOOOOOOOOOOOOOOOOOOOOOOOOOOOOOOOOOOOOOOOOOOOOO | OOOOOOOOOOOOOOOOOOOOOOOOOOOOOOOOOOOOOOOOOOOOOOOOOOOOOOOOOOOOOOOOOOOOOOOOOOOOOOOOOOOOOOOOOO | OOOOOOOOOOOOOOOOOOOOOOOOOOOOOOOOOOOOOOOOOOOOOOOOOOOOOOOOOOOOOOOOOOOOOOOOOOOOOOOOOOOOOOOOOO | OOOOOOOOOOOOOOOOOOOOOOOOOOOOOOOOOOOOOOOOOOOOOOOOOOOOOOOOOOOOOOOOOOOOOOOOOOOOOOOOOOOOOOOOOO | OOOOOOOOOOOOOOOOOOOOOOOOOOOOOOOOOOOOOOOOOOOOOOOOOOOOOOOOOOOOOOOOOOOOOOOOOOOOOOOOOOOOOOOOOO | OOOOOOOOOOOOOOOOOOOOOOOOOOOOOOOOOOOOOOOOOOOOOOOOOOOOOOOOOOOOOOOOOOOOOOOOOOOOOOOOOOOOOOOOOO | OOOOOOOOOOOOOOOOOOOOOOOOOOOOOOOOOOOOOOOOOOOOOOOOOOOOOOOOOOOOOOOOOOOOOOOOOOOOOOOOOOOOOOOOOO | OOOOOOOOOOOOOOOOOOOOOOOOOOOOOOOOOOOOOOOOOOOOOOOOOOOOOOOOOOOOOOOOOOOOOOOOOOOOOOOOOOOOOOOOOO | OOOOOOOOOOOOOOOOOOOOOOOOOOOOOOOOOOOOOOOOOOOOOOOOOOOOOOOOOOOOOOOOOOOOOOOOOOOOOOOOOOOOOOOOOO |
| TLA Parts Change |  |  |  |  |  |  |  |  |  |
| Item | Foxconn P/N | Qty | Part Description | Manufacturer Full Name | Manufacturer P/N | RoHS | Location | Remark | BOM |
| BOM Change List Date:Tue Oct 31 10:03:57 GMT+08:00 2017 |  |  |  |  |  |  |  |  |  |
| New BOM file : E:\barreleye g2\1031\foxbis\BG2 1031.xls |  |  |  |  |  |  |  |  |  |
| Old BOM file : E:\barreleye g2\1031\foxbis\BG2 1021.xls |  |  |  |  |  |  |  |  |  |
| ##### Add Parts |  |  |  |  |  |  |  |  |  |
| Item | Location | Qty | Foxconn P/N | Part Description | Manufacturer Full Name | Manufacturer P/N | RoHS | Sheet |  |
| ##### Remove Parts |  |  |  |  |  |  |  |  |  |
| Item | Location | Qty | Foxconn P/N | Part Description | Manufacturer Full Name | Manufacturer P/N | RoHS | Sheet |  |
| ##### Change Parts |  |  |  |  |  |  |  |  |  |
| Item | Location | Qty | Foxconn P/N | Part Description | Manufacturer Full Name | Manufacturer P/N | RoHS | Sheet | Remark |
| 1 | PUAC4,PSAC4,PRAC4,PQAC4,PPAC4,PIAC4,PFAC4,PEAC4,PUAC5,PSAC5,PRAC5,PQAC5,PPAC5,PIAC5,PFAC5,PEAC5,PUAC6,PSAC6,PRAC6,PQAC6,PPAC6,PIAC6,PFAC6,PEAC6 | 24 | 62011DD00-015-G | CAP,22uF,+/-10%,X6S,6.3V,G,SMD1206 | MURATA ELEC. NORTH AMERICA | GRM31CC80J226K | G | PWA BOM | In New BOM |
|  |  |  | 62011DD00-026-G | CAP,22uF,+/-10%,X6S,6.3V,G,SMD1206 | SAMSUNG SEMICONDUCTOR | CL31X226KQHNNNE | G | PWA BOM | In New BOM |
|  | PUAC4,PSAC4,PRAC4,PQAC4,PPAC4,PIAC4,PFAC4,PEAC4,PUAC5,PSAC5,PRAC5,PQAC5,PPAC5,PIAC5,PFAC5,PEAC5,PUAC6,PSAC6,PRAC6,PQAC6,PPAC6,PIAC6,PFAC6,PEAC6 | 24 | 62011DD00-015-G | CAP,22uF,+/-10%,X6S,6.3V,G,SMD1206 | MURATA ELEC. NORTH AMERICA | GRM31CC80J226K | G | PWA BOM | In Old BOM |
|  |  |  | CL31X226KQHNNNE | CAP,22uF,+/-10%,X6S,6.3V,G,SMD1206 | SAMSUNG SEMICONDUCTOR | CL31X226KQHNNNE | G | PWA BOM | In Old BOM |
| 2 | U170,U174,U180 | 3 | 310109D00-031-G | IC,Gate&Inverter,74LVC1G32GW,1.65~5.5V,G,TSSOP-5,SMD | NXP SEMICONDUCTORS | 74LVC1G32GW | G | PWA BOM | In New BOM |
|  |  |  | 310109E00-223-G | IC,Gate&Inverter,NL17SZ32DFT2G,1.65~5.5V,G,SOT-353-5,SMD | ON SEMICONDUCTOR CORP | NL17SZ32DFT2G | G | PWA BOM | In New BOM |
|  |  |  | 31010VY00-131-G | IC,Gate&Inverter,TC7SZ32FU,1.65~5.5V,G,SSOP-5,SMD | TOSHIBA ELECTRONICS ASIA LTD | TC7SZ32FU,LJ(CT | G | PWA BOM | In New BOM |
|  | U170,U174,U180 | 3 | 310109D00-031-G | IC,Gate&Inverter,74LVC1G32GW,1.65~5.5V,G,TSSOP-5,SMD | NXP SEMICONDUCTORS | 74LVC1G32GW | G | PWA BOM | In Old BOM |
|  |  |  | 310109E00-223-G | IC,Gate&Inverter,NL17SZ32DFT2G,1.65~5.5V,G,SOT-353-5,SMD | ON SEMICONDUCTOR CORP | NL17SZ32DFT2G | G | PWA BOM | In Old BOM |
|  |  |  | TC7SZ32FU,LJ(CT | IC,Gate&Inverter,TC7SZ32FU,1.65~5.5V,G,SSOP-5,SMD | TOSHIBA ELECTRONICS ASIA LTD | TC7SZ32FU,LJ(CT | G | PWA BOM | In Old BOM |
| 3 | U171 | 1 | 31050KL00-031-G | IC,Buffer,74HC75PW,2.0V~6.0V,G,TSSOP-16,SMD | NXP SEMICONDUCTORS | 74HC75PW | G | PWA BOM | In New BOM |
|  |  |  | 311007C00-183-G | IC,Translator,CD74HC75PWR,2V~6V,G,TSSOP-16,SMD | Texas Instruments | CD74HC75PWR | G | PWA BOM | In New BOM |
|  | U171 | 1 | 31050KL00-031-G | IC,Buffer,74HC75PW,2.0V~6.0V,G,TSSOP-16,SMD | NXP SEMICONDUCTORS | 74HC75PW | G | PWA BOM | In Old BOM |
|  |  |  | CD74HC75PWR | IC,Translator,CD74HC75PWR,2V~6V,G,TSSOP-16,SMD | Texas Instruments | CD74HC75PWR | G | PWA BOM | In Old BOM |
| 4 | DIMM02,DIMM04,DIMM06,DIMM09,DIMM11,DIMM13,DIMM15,DIMM16,DIMM18,DIMM20,DIMM22,DIMM25,DIMM27,DIMM29,DIMM31,DIMM00 | 16 | 34021BC00-G78-G | CONN,DDR IV,V/T,1.2V,Blu,0.85mm,15u,G,SMD-288 | FCI CONNECTORS HONGKONG LTD. | 10140702-0302K11LF | G | PWA BOM | In New BOM |
|  |  |  | 34021CD00-600-G | Memory Connector,AH58897-T2L31-3F,DDR IV,288,SMD,THERMOPLASTIC,0.85mm,15u",Blue,G | FOXCONN TECHNOLOGY CO.,LTD. | AH58897-T2L31-3F | G | PWA BOM | In New BOM |
|  |  |  | 34021E200-GRS-G | CONN,DDR IV,V/T,1.2V,Blu,0.85mm,15u,G,SMD-288 | LOTES CO LTD | ADDR0245-K010C | G | PWA BOM | In New BOM |
|  |  |  | 34021DR00-317-G | CONN,DDR IV,V/T,1.2V,Blu,0.85mm,15u,G,SMD-288 | MOLEX INCORPORATED | 204245-1004 | G | PWA BOM | In New BOM |
|  | DIMM02,DIMM04,DIMM06,DIMM09,DIMM11,DIMM13,DIMM15,DIMM16,DIMM18,DIMM20,DIMM22,DIMM25,DIMM27,DIMM29,DIMM31,DIMM00 | 16 | 34021BC00-G78-G | CONN,DDR IV,V/T,1.2V,Blu,0.85mm,15u,G,SMD-288 | FCI CONNECTORS HONGKONG LTD. | 10140702-0302K11LF | G | PWA BOM | In Old BOM |
|  |  |  | 34021CD00-600-G | Memory Connector,AH58897-T2L31-3F,DDR IV,288,SMD,THERMOPLASTIC,0.85mm,15u",Blue,G | FOXCONN TECHNOLOGY CO.,LTD. | AH58897-T2L31-3F | G | PWA BOM | In Old BOM |
|  |  |  | ADDR0245-K010C | CONN,DDR IV,V/T,1.2V,Blu,0.85mm,15u,G,SMD-288 | LOTES CO LTD | ADDR0245-K010C | G | PWA BOM | In Old BOM |
|  |  |  | 34021DR00-317-G | CONN,DDR IV,V/T,1.2V,Blu,0.85mm,15u,G,SMD-288 | MOLEX INCORPORATED | 204245-1004 | G | PWA BOM | In Old BOM |
| 5 | DIMM01,DIMM03,DIMM05,DIMM07,DIMM08,DIMM10,DIMM12,DIMM14,DIMM17,DIMM19,DIMM21,DIMM23,DIMM24,DIMM26,DIMM28,DIMM30 | 16 | 34021BD00-G78-G | CONN,DDR IV,V/T,1.2V,Bla,0.85mm,15u,G,SMD-288 | FCI CONNECTORS HONGKONG LTD. | 10140702-0301K11LF | G | PWA BOM | In New BOM |
|  |  |  | 34021E100-GRS-G | CONN,DDR IV,V/T,1.2V,Bla,0.85mm,15u,G,SMD-288 | LOTES CO LTD | ADDR0245-P009C | G | PWA BOM | In New BOM |
|  |  |  | 34021CF00-600-G | Memory Connector,AH58897-T2B21-3F,DDR IV,288,SMD,THERMOPLASTIC,0.85mm,15u",Black,G | FOXCONN TECHNOLOGY CO.,LTD. | AH58897-T2B21-3F | G | PWA BOM | In New BOM |
|  |  |  | 34021DS00-317-G | CONN,DDR IV,V/T,1.2V,Bla,0.85mm,15u,G,SMD-288 | MOLEX INCORPORATED | 204245-1003 | G | PWA BOM | In New BOM |
|  | DIMM01,DIMM03,DIMM05,DIMM07,DIMM08,DIMM10,DIMM12,DIMM14,DIMM17,DIMM19,DIMM21,DIMM23,DIMM24,DIMM26,DIMM28,DIMM30 | 16 | 34021BD00-G78-G | CONN,DDR IV,V/T,1.2V,Bla,0.85mm,15u,G,SMD-288 | FCI CONNECTORS HONGKONG LTD. | 10140702-0301K11LF | G | PWA BOM | In Old BOM |
|  |  |  | ADDR0245-P009C | CONN,DDR IV,V/T,1.2V,Bla,0.85mm,15u,G,SMD-288 | LOTES CO LTD | ADDR0245-P009C | G | PWA BOM | In Old BOM |
|  |  |  | 34021CF00-600-G | Memory Connector,AH58897-T2B21-3F,DDR IV,288,SMD,THERMOPLASTIC,0.85mm,15u",Black,G | FOXCONN TECHNOLOGY CO.,LTD. | AH58897-T2B21-3F | G | PWA BOM | In Old BOM |
|  |  |  | 34021DS00-317-G | CONN,DDR IV,V/T,1.2V,Bla,0.85mm,15u,G,SMD-288 | MOLEX INCORPORATED | 204245-1003 | G | PWA BOM | In Old BOM |
| 6 | ED2,ED3 | 2 | 521800900-227-G | DIODE,Array-TVS,SRV05-4.TCT,5V,12A,G,SOT23-6,SMD | SEMTECH CORPORATION. | SRV05-4.TCT | G | PWA BOM | In New BOM |
|  |  |  | 52180C200-086-G | Diode,Array-TVS,SRV05-4HTG,SOT-23,6P,G | LITTELFUSE FAR EAST PTE LTD | SRV05-4HTG | G | PWA BOM | In New BOM |
|  | ED2,ED3 | 2 | SRV05-4ATCT | DIODE,Array-TVS,SRV05-4.TCT,5V,12A,G,SOT23-6,SMD | SEMTECH CORPORATION. | SRV05-4ATCT | G | PWA BOM | In Old BOM |
|  |  |  | 521800900-227-G | DIODE,Array-TVS,SRV05-4.TCT,5V,12A,G,SOT23-6,SMD | SEMTECH CORPORATION. | SRV05-4.TCT | G | PWA BOM | In Old BOM |
|  |  |  | 52180C200-086-G | Diode,Array-TVS,SRV05-4HTG,SOT-23,6P,G | LITTELFUSE FAR EAST PTE LTD | SRV05-4HTG | G | PWA BOM | In Old BOM |
| ##### Change Revision |  |  |  |  |  |  |  |  |  |
| Sheet | REV OF BOM | CUSTOMER | CUSTOMER P/N | PWA PN | PWA DESCRIPTION | PWA REV | DATE | Remark |  |
| OOOOOOOOOOOOOOOOOOOOOOOOOOOOOOOOOOOOOOOOOOOOOOOOOOOOOOOOOOOOOOOOOOOOOOOOOOOOOOOOOOOOOOOOOO | OOOOOOOOOOOOOOOOOOOOOOOOOOOOOOOOOOOOOOOOOOOOOOOOOOOOOOOOOOOOOOOOOOOOOOOOOOOOOOOOOOOOOOOOOO | OOOOOOOOOOOOOOOOOOOOOOOOOOOOOOOOOOOOOOOOOOOOOOOOOOOOOOOOOOOOOOOOOOOOOOOOOOOOOOOOOOOOOOOOOO | OOOOOOOOOOOOOOOOOOOOOOOOOOOOOOOOOOOOOOOOOOOOOOOOOOOOOOOOOOOOOOOOOOOOOOOOOOOOOOOOOOOOOOOOOO | OOOOOOOOOOOOOOOOOOOOOOOOOOOOOOOOOOOOOOOOOOOOOOOOOOOOOOOOOOOOOOOOOOOOOOOOOOOOOOOOOOOOOOOOOO | OOOOOOOOOOOOOOOOOOOOOOOOOOOOOOOOOOOOOOOOOOOOOOOOOOOOOOOOOOOOOOOOOOOOOOOOOOOOOOOOOOOOOOOOOO | OOOOOOOOOOOOOOOOOOOOOOOOOOOOOOOOOOOOOOOOOOOOOOOOOOOOOOOOOOOOOOOOOOOOOOOOOOOOOOOOOOOOOOOOOO | OOOOOOOOOOOOOOOOOOOOOOOOOOOOOOOOOOOOOOOOOOOOOOOOOOOOOOOOOOOOOOOOOOOOOOOOOOOOOOOOOOOOOOOOOO | OOOOOOOOOOOOOOOOOOOOOOOOOOOOOOOOOOOOOOOOOOOOOOOOOOOOOOOOOOOOOOOOOOOOOOOOOOOOOOOOOOOOOOOOOO | OOOOOOOOOOOOOOOOOOOOOOOOOOOOOOOOOOOOOOOOOOOOOOOOOOOOOOOOOOOOOOOOOOOOOOOOOOOOOOOOOOOOOOOOOO |
| Second Source Change |  |  |  |  |  |  |  |  |  |
| Item | Location | Change Type | Foxconn P/N | Part Description | Manufacturer Full Name | Manufacturer P/N | RoHS | Sheet |  |
| 1 | PUAC4,PSAC4,PRAC4,PQAC4,PPAC4,PIAC4,PFAC4,PEAC4,PUAC5,PSAC5,PRAC5,PQAC5,PPAC5,PIAC5,PFAC5,PEAC5,PUAC6,PSAC6,PRAC6,PQAC6,PPAC6,PIAC6,PFAC6,PEAC6 |  | 62011DD00-015-G | CAP,22uF,+/-10%,X6S,6.3V,G,SMD1206 | MURATA ELEC. NORTH AMERICA | GRM31CC80J226K | G | PWA BOM |  |
|  |  | ADD | 62011DD00-026-G | CAP,22uF,+/-10%,X6S,6.3V,G,SMD1206 | SAMSUNG SEMICONDUCTOR | CL31X226KQHNNNE | G | PWA BOM |  |
|  |  | Delete | CL31X226KQHNNNE | CAP,22uF,+/-10%,X6S,6.3V,G,SMD1206 | SAMSUNG SEMICONDUCTOR | CL31X226KQHNNNE | G | PWA BOM |  |
| 2 | U170,U174,U180 |  | 310109D00-031-G | IC,Gate&Inverter,74LVC1G32GW,1.65~5.5V,G,TSSOP-5,SMD | NXP SEMICONDUCTORS | 74LVC1G32GW | G | PWA BOM |  |
|  |  | NO | 310109E00-223-G | IC,Gate&Inverter,NL17SZ32DFT2G,1.65~5.5V,G,SOT-353-5,SMD | ON SEMICONDUCTOR CORP | NL17SZ32DFT2G | G | PWA BOM |  |
|  |  | ADD | 31010VY00-131-G | IC,Gate&Inverter,TC7SZ32FU,1.65~5.5V,G,SSOP-5,SMD | TOSHIBA ELECTRONICS ASIA LTD | TC7SZ32FU,LJ(CT | G | PWA BOM |  |
|  |  | Delete | TC7SZ32FU,LJ(CT | IC,Gate&Inverter,TC7SZ32FU,1.65~5.5V,G,SSOP-5,SMD | TOSHIBA ELECTRONICS ASIA LTD | TC7SZ32FU,LJ(CT | G | PWA BOM |  |
| 3 | U171 |  | 31050KL00-031-G | IC,Buffer,74HC75PW,2.0V~6.0V,G,TSSOP-16,SMD | NXP SEMICONDUCTORS | 74HC75PW | G | PWA BOM |  |
|  |  | ADD | 311007C00-183-G | IC,Translator,CD74HC75PWR,2V~6V,G,TSSOP-16,SMD | Texas Instruments | CD74HC75PWR | G | PWA BOM |  |
|  |  | Delete | CD74HC75PWR | IC,Translator,CD74HC75PWR,2V~6V,G,TSSOP-16,SMD | Texas Instruments | CD74HC75PWR | G | PWA BOM |  |
| 4 | DIMM02,DIMM04,DIMM06,DIMM09,DIMM11,DIMM13,DIMM15,DIMM16,DIMM18,DIMM20,DIMM22,DIMM25,DIMM27,DIMM29,DIMM31,DIMM00 |  | 34021BC00-G78-G | CONN,DDR IV,V/T,1.2V,Blu,0.85mm,15u,G,SMD-288 | FCI CONNECTORS HONGKONG LTD. | 10140702-0302K11LF | G | PWA BOM |  |
|  |  | NO | 34021CD00-600-G | Memory Connector,AH58897-T2L31-3F,DDR IV,288,SMD,THERMOPLASTIC,0.85mm,15u",Blue,G | FOXCONN TECHNOLOGY CO.,LTD. | AH58897-T2L31-3F | G | PWA BOM |  |
|  |  | ADD | 34021E200-GRS-G | CONN,DDR IV,V/T,1.2V,Blu,0.85mm,15u,G,SMD-288 | LOTES CO LTD | ADDR0245-K010C | G | PWA BOM |  |
|  |  | NO | 34021DR00-317-G | CONN,DDR IV,V/T,1.2V,Blu,0.85mm,15u,G,SMD-288 | MOLEX INCORPORATED | 204245-1004 | G | PWA BOM |  |
|  |  | Delete | ADDR0245-K010C | CONN,DDR IV,V/T,1.2V,Blu,0.85mm,15u,G,SMD-288 | LOTES CO LTD | ADDR0245-K010C | G | PWA BOM |  |
| 5 | DIMM01,DIMM03,DIMM05,DIMM07,DIMM08,DIMM10,DIMM12,DIMM14,DIMM17,DIMM19,DIMM21,DIMM23,DIMM24,DIMM26,DIMM28,DIMM30 |  | 34021BD00-G78-G | CONN,DDR IV,V/T,1.2V,Bla,0.85mm,15u,G,SMD-288 | FCI CONNECTORS HONGKONG LTD. | 10140702-0301K11LF | G | PWA BOM |  |
|  |  | ADD | 34021E100-GRS-G | CONN,DDR IV,V/T,1.2V,Bla,0.85mm,15u,G,SMD-288 | LOTES CO LTD | ADDR0245-P009C | G | PWA BOM |  |
|  |  | NO | 34021CF00-600-G | Memory Connector,AH58897-T2B21-3F,DDR IV,288,SMD,THERMOPLASTIC,0.85mm,15u",Black,G | FOXCONN TECHNOLOGY CO.,LTD. | AH58897-T2B21-3F | G | PWA BOM |  |
|  |  | NO | 34021DS00-317-G | CONN,DDR IV,V/T,1.2V,Bla,0.85mm,15u,G,SMD-288 | MOLEX INCORPORATED | 204245-1003 | G | PWA BOM |  |
|  |  | Delete | ADDR0245-P009C | CONN,DDR IV,V/T,1.2V,Bla,0.85mm,15u,G,SMD-288 | LOTES CO LTD | ADDR0245-P009C | G | PWA BOM |  |
| OOOOOOOOOOOOOOOOOOOOOOOOOOOOOOOOOOOOOOOOOOOOOOOOOOOOOOOOOOOOOOOOOOOOOOOOOOOOOOOOOOOOOOOOOO | OOOOOOOOOOOOOOOOOOOOOOOOOOOOOOOOOOOOOOOOOOOOOOOOOOOOOOOOOOOOOOOOOOOOOOOOOOOOOOOOOOOOOOOOOO | OOOOOOOOOOOOOOOOOOOOOOOOOOOOOOOOOOOOOOOOOOOOOOOOOOOOOOOOOOOOOOOOOOOOOOOOOOOOOOOOOOOOOOOOOO | OOOOOOOOOOOOOOOOOOOOOOOOOOOOOOOOOOOOOOOOOOOOOOOOOOOOOOOOOOOOOOOOOOOOOOOOOOOOOOOOOOOOOOOOOO | OOOOOOOOOOOOOOOOOOOOOOOOOOOOOOOOOOOOOOOOOOOOOOOOOOOOOOOOOOOOOOOOOOOOOOOOOOOOOOOOOOOOOOOOOO | OOOOOOOOOOOOOOOOOOOOOOOOOOOOOOOOOOOOOOOOOOOOOOOOOOOOOOOOOOOOOOOOOOOOOOOOOOOOOOOOOOOOOOOOOO | OOOOOOOOOOOOOOOOOOOOOOOOOOOOOOOOOOOOOOOOOOOOOOOOOOOOOOOOOOOOOOOOOOOOOOOOOOOOOOOOOOOOOOOOOO | OOOOOOOOOOOOOOOOOOOOOOOOOOOOOOOOOOOOOOOOOOOOOOOOOOOOOOOOOOOOOOOOOOOOOOOOOOOOOOOOOOOOOOOOOO | OOOOOOOOOOOOOOOOOOOOOOOOOOOOOOOOOOOOOOOOOOOOOOOOOOOOOOOOOOOOOOOOOOOOOOOOOOOOOOOOOOOOOOOOOO | OOOOOOOOOOOOOOOOOOOOOOOOOOOOOOOOOOOOOOOOOOOOOOOOOOOOOOOOOOOOOOOOOOOOOOOOOOOOOOOOOOOOOOOOOO |
| Master Materials Change |  |  |  |  |  |  |  |  |  |
| Item | Foxconn P/N | Orig._Usage | New_Usage | Part Description | Manufacturer Full Name | Manufacturer P/N | RoHS | Location | Sheet |
| 1 | 521800900-227-G | 0 | 2 | DIODE,Array-TVS,SRV05-4.TCT,5V,12A,G,SOT23-6,SMD | SEMTECH CORPORATION. | SRV05-4.TCT | G | (+)ED2,ED3 | PWA BOM |
|  | 52180C200-086-G |  |  | Diode,Array-TVS,SRV05-4HTG,SOT-23,6P,G | LITTELFUSE FAR EAST PTE LTD | SRV05-4HTG |  |  | PWA BOM |
| 2 | SRV05-4ATCT | 2 | 0 | DIODE,Array-TVS,SRV05-4.TCT,5V,12A,G,SOT23-6,SMD | SEMTECH CORPORATION. | SRV05-4ATCT | G | (-)ED2,ED3 | PWA BOM |
|  | 521800900-227-G |  |  | DIODE,Array-TVS,SRV05-4.TCT,5V,12A,G,SOT23-6,SMD | SEMTECH CORPORATION. | SRV05-4.TCT |  |  | PWA BOM |
|  | 52180C200-086-G |  |  | Diode,Array-TVS,SRV05-4HTG,SOT-23,6P,G | LITTELFUSE FAR EAST PTE LTD | SRV05-4HTG |  |  | PWA BOM |
| OOOOOOOOOOOOOOOOOOOOOOOOOOOOOOOOOOOOOOOOOOOOOOOOOOOOOOOOOOOOOOOOOOOOOOOOOOOOOOOOOOOOOOOOOO | OOOOOOOOOOOOOOOOOOOOOOOOOOOOOOOOOOOOOOOOOOOOOOOOOOOOOOOOOOOOOOOOOOOOOOOOOOOOOOOOOOOOOOOOOO | OOOOOOOOOOOOOOOOOOOOOOOOOOOOOOOOOOOOOOOOOOOOOOOOOOOOOOOOOOOOOOOOOOOOOOOOOOOOOOOOOOOOOOOOOO | OOOOOOOOOOOOOOOOOOOOOOOOOOOOOOOOOOOOOOOOOOOOOOOOOOOOOOOOOOOOOOOOOOOOOOOOOOOOOOOOOOOOOOOOOO | OOOOOOOOOOOOOOOOOOOOOOOOOOOOOOOOOOOOOOOOOOOOOOOOOOOOOOOOOOOOOOOOOOOOOOOOOOOOOOOOOOOOOOOOOO | OOOOOOOOOOOOOOOOOOOOOOOOOOOOOOOOOOOOOOOOOOOOOOOOOOOOOOOOOOOOOOOOOOOOOOOOOOOOOOOOOOOOOOOOOO | OOOOOOOOOOOOOOOOOOOOOOOOOOOOOOOOOOOOOOOOOOOOOOOOOOOOOOOOOOOOOOOOOOOOOOOOOOOOOOOOOOOOOOOOOO | OOOOOOOOOOOOOOOOOOOOOOOOOOOOOOOOOOOOOOOOOOOOOOOOOOOOOOOOOOOOOOOOOOOOOOOOOOOOOOOOOOOOOOOOOO | OOOOOOOOOOOOOOOOOOOOOOOOOOOOOOOOOOOOOOOOOOOOOOOOOOOOOOOOOOOOOOOOOOOOOOOOOOOOOOOOOOOOOOOOOO | OOOOOOOOOOOOOOOOOOOOOOOOOOOOOOOOOOOOOOOOOOOOOOOOOOOOOOOOOOOOOOOOOOOOOOOOOOOOOOOOOOOOOOOOOO |
| TLA Parts Change |  |  |  |  |  |  |  |  |  |
| Item | Foxconn P/N | Qty | Part Description | Manufacturer Full Name | Manufacturer P/N | RoHS | Location | Remark | BOM |
| BOM Change List Date:Mon Nov 20 15:55:38 GMT+08:00 2017 |  |  |  |  |  |  |  |  |  |
| New BOM file : E:\barreleye g2\1120\BG2 1120.xls |  |  |  |  |  |  |  |  |  |
| Old BOM file : E:\barreleye g2\1120\BG2 1031.xls |  |  |  |  |  |  |  |  |  |
| ##### Add Parts |  |  |  |  |  |  |  |  |  |
| Item | Location | Qty | Foxconn P/N | Part Description | Manufacturer Full Name | Manufacturer P/N | RoHS | Sheet |  |
| ##### Remove Parts |  |  |  |  |  |  |  |  |  |
| Item | Location | Qty | Foxconn P/N | Part Description | Manufacturer Full Name | Manufacturer P/N | RoHS | Sheet |  |
| 1 | R1240 | 1 | 61010LA00-017-G | RES,4.7KOhm,+/-1%,1/16W,G,SMD0402 | KOA SPEER ELECTRONICS, INC. | RK73H1ETTP4701F | G | PWA BOM |  |
|  |  |  | 61010LA00-012-G | RES,4.7KOhm,+/-1%,1/16W,G,SMD0402 | WALSIN TECHNOLOGY CORPORATION | WR04X4701FTL | G | PWA BOM |  |
|  |  |  | 61010LA00-011-G | RES,4.7KOhm,+/-1%,1/16W,G,SMD0402 | YAGEO CORPORATION COMPONENT | RC0402FR-074K7L | G | PWA BOM |  |
|  |  |  | 61010LA00-044-G | RES,4.7KOhm,+/-1%,1/16W,G,SMD0402 | TA-I TECHNOLOGY CO., LTD | RM04FTN4701 | G | PWA BOM |  |
| ##### Change Parts |  |  |  |  |  |  |  |  |  |
| Item | Location | Qty | Foxconn P/N | Part Description | Manufacturer Full Name | Manufacturer P/N | RoHS | Sheet | Remark |
| 1 | PFRR19 | 1 | 61100YB00-017-G | RES,2.94KOhm,+/-0.1%,1/16W,G,SMD0402 | KOA SPEER ELECTRONICS, INC. | RN731ETTP2941B25 | G | PWA BOM | In New BOM |
|  |  |  | 61100YB00-011-G | RES,2.94KOhm,+/-0.1%,1/16W,G,SMD0402 | YAGEO CORPORATION COMPONENT | RT0402BRD072K94L | G | PWA BOM | In New BOM |
|  |  |  | 61100YB00-044-G | RES,2.94KOhm,+/-0.1%,1/16W,G,SMD0402 | TA-I TECHNOLOGY CO., LTD | RB04BTP2941 | G | PWA BOM | In New BOM |
|  | PFRR19 | 1 | 61100YB00-017-G | RES,2.94KOhm,+/-0.1%,1/16W,G,SMD0402 | KOA SPEER ELECTRONICS, INC. | RN731ETTP2941B25 | G | PWA BOM | In Old BOM |
| ##### Change Revision |  |  |  |  |  |  |  |  |  |
| Sheet | REV OF BOM | CUSTOMER | CUSTOMER P/N | PWA PN | PWA DESCRIPTION | PWA REV | DATE | Remark |  |
| OOOOOOOOOOOOOOOOOOOOOOOOOOOOOOOOOOOOOOOOOOOOOOOOOOOOOOOOOOOOOOOOOOOOOOOOOOOOOOOOOOOOOOOOOO | OOOOOOOOOOOOOOOOOOOOOOOOOOOOOOOOOOOOOOOOOOOOOOOOOOOOOOOOOOOOOOOOOOOOOOOOOOOOOOOOOOOOOOOOOO | OOOOOOOOOOOOOOOOOOOOOOOOOOOOOOOOOOOOOOOOOOOOOOOOOOOOOOOOOOOOOOOOOOOOOOOOOOOOOOOOOOOOOOOOOO | OOOOOOOOOOOOOOOOOOOOOOOOOOOOOOOOOOOOOOOOOOOOOOOOOOOOOOOOOOOOOOOOOOOOOOOOOOOOOOOOOOOOOOOOOO | OOOOOOOOOOOOOOOOOOOOOOOOOOOOOOOOOOOOOOOOOOOOOOOOOOOOOOOOOOOOOOOOOOOOOOOOOOOOOOOOOOOOOOOOOO | OOOOOOOOOOOOOOOOOOOOOOOOOOOOOOOOOOOOOOOOOOOOOOOOOOOOOOOOOOOOOOOOOOOOOOOOOOOOOOOOOOOOOOOOOO | OOOOOOOOOOOOOOOOOOOOOOOOOOOOOOOOOOOOOOOOOOOOOOOOOOOOOOOOOOOOOOOOOOOOOOOOOOOOOOOOOOOOOOOOOO | OOOOOOOOOOOOOOOOOOOOOOOOOOOOOOOOOOOOOOOOOOOOOOOOOOOOOOOOOOOOOOOOOOOOOOOOOOOOOOOOOOOOOOOOOO | OOOOOOOOOOOOOOOOOOOOOOOOOOOOOOOOOOOOOOOOOOOOOOOOOOOOOOOOOOOOOOOOOOOOOOOOOOOOOOOOOOOOOOOOOO | OOOOOOOOOOOOOOOOOOOOOOOOOOOOOOOOOOOOOOOOOOOOOOOOOOOOOOOOOOOOOOOOOOOOOOOOOOOOOOOOOOOOOOOOOO |
| Second Source Change |  |  |  |  |  |  |  |  |  |
| Item | Location | Change Type | Foxconn P/N | Part Description | Manufacturer Full Name | Manufacturer P/N | RoHS | Sheet |  |
| 2 | PFRR19 |  | 61100YB00-017-G | RES,2.94KOhm,+/-0.1%,1/16W,G,SMD0402 | KOA SPEER ELECTRONICS, INC. | RN731ETTP2941B25 | G | PWA BOM |  |
|  |  | ADD | 61100YB00-011-G | RES,2.94KOhm,+/-0.1%,1/16W,G,SMD0402 | YAGEO CORPORATION COMPONENT | RT0402BRD072K94L | G | PWA BOM |  |
|  |  | ADD | 61100YB00-044-G | RES,2.94KOhm,+/-0.1%,1/16W,G,SMD0402 | TA-I TECHNOLOGY CO., LTD | RB04BTP2941 | G | PWA BOM |  |
| OOOOOOOOOOOOOOOOOOOOOOOOOOOOOOOOOOOOOOOOOOOOOOOOOOOOOOOOOOOOOOOOOOOOOOOOOOOOOOOOOOOOOOOOOO | OOOOOOOOOOOOOOOOOOOOOOOOOOOOOOOOOOOOOOOOOOOOOOOOOOOOOOOOOOOOOOOOOOOOOOOOOOOOOOOOOOOOOOOOOO | OOOOOOOOOOOOOOOOOOOOOOOOOOOOOOOOOOOOOOOOOOOOOOOOOOOOOOOOOOOOOOOOOOOOOOOOOOOOOOOOOOOOOOOOOO | OOOOOOOOOOOOOOOOOOOOOOOOOOOOOOOOOOOOOOOOOOOOOOOOOOOOOOOOOOOOOOOOOOOOOOOOOOOOOOOOOOOOOOOOOO | OOOOOOOOOOOOOOOOOOOOOOOOOOOOOOOOOOOOOOOOOOOOOOOOOOOOOOOOOOOOOOOOOOOOOOOOOOOOOOOOOOOOOOOOOO | OOOOOOOOOOOOOOOOOOOOOOOOOOOOOOOOOOOOOOOOOOOOOOOOOOOOOOOOOOOOOOOOOOOOOOOOOOOOOOOOOOOOOOOOOO | OOOOOOOOOOOOOOOOOOOOOOOOOOOOOOOOOOOOOOOOOOOOOOOOOOOOOOOOOOOOOOOOOOOOOOOOOOOOOOOOOOOOOOOOOO | OOOOOOOOOOOOOOOOOOOOOOOOOOOOOOOOOOOOOOOOOOOOOOOOOOOOOOOOOOOOOOOOOOOOOOOOOOOOOOOOOOOOOOOOOO | OOOOOOOOOOOOOOOOOOOOOOOOOOOOOOOOOOOOOOOOOOOOOOOOOOOOOOOOOOOOOOOOOOOOOOOOOOOOOOOOOOOOOOOOOO | OOOOOOOOOOOOOOOOOOOOOOOOOOOOOOOOOOOOOOOOOOOOOOOOOOOOOOOOOOOOOOOOOOOOOOOOOOOOOOOOOOOOOOOOOO |
| Master Materials Change |  |  |  |  |  |  |  |  |  |
| Item | Foxconn P/N | Orig._Usage | New_Usage | Part Description | Manufacturer Full Name | Manufacturer P/N | RoHS | Location | Sheet |
| 1 | 61010LA00-017-G | 153 | 152 | RES,4.7KOhm,+/-1%,1/16W,G,SMD0402 | KOA SPEER ELECTRONICS, INC. | RK73H1ETTP4701F | G | (-)R1240 | PWA BOM |
|  | 61010LA00-012-G |  |  | RES,4.7KOhm,+/-1%,1/16W,G,SMD0402 | WALSIN TECHNOLOGY CORPORATION | WR04X4701FTL |  |  | PWA BOM |
|  | 61010LA00-011-G |  |  | RES,4.7KOhm,+/-1%,1/16W,G,SMD0402 | YAGEO CORPORATION COMPONENT | RC0402FR-074K7L |  |  | PWA BOM |
|  | 61010LA00-044-G |  |  | RES,4.7KOhm,+/-1%,1/16W,G,SMD0402 | TA-I TECHNOLOGY CO., LTD | RM04FTN4701 |  |  | PWA BOM |
| OOOOOOOOOOOOOOOOOOOOOOOOOOOOOOOOOOOOOOOOOOOOOOOOOOOOOOOOOOOOOOOOOOOOOOOOOOOOOOOOOOOOOOOOOO | OOOOOOOOOOOOOOOOOOOOOOOOOOOOOOOOOOOOOOOOOOOOOOOOOOOOOOOOOOOOOOOOOOOOOOOOOOOOOOOOOOOOOOOOOO | OOOOOOOOOOOOOOOOOOOOOOOOOOOOOOOOOOOOOOOOOOOOOOOOOOOOOOOOOOOOOOOOOOOOOOOOOOOOOOOOOOOOOOOOOO | OOOOOOOOOOOOOOOOOOOOOOOOOOOOOOOOOOOOOOOOOOOOOOOOOOOOOOOOOOOOOOOOOOOOOOOOOOOOOOOOOOOOOOOOOO | OOOOOOOOOOOOOOOOOOOOOOOOOOOOOOOOOOOOOOOOOOOOOOOOOOOOOOOOOOOOOOOOOOOOOOOOOOOOOOOOOOOOOOOOOO | OOOOOOOOOOOOOOOOOOOOOOOOOOOOOOOOOOOOOOOOOOOOOOOOOOOOOOOOOOOOOOOOOOOOOOOOOOOOOOOOOOOOOOOOOO | OOOOOOOOOOOOOOOOOOOOOOOOOOOOOOOOOOOOOOOOOOOOOOOOOOOOOOOOOOOOOOOOOOOOOOOOOOOOOOOOOOOOOOOOOO | OOOOOOOOOOOOOOOOOOOOOOOOOOOOOOOOOOOOOOOOOOOOOOOOOOOOOOOOOOOOOOOOOOOOOOOOOOOOOOOOOOOOOOOOOO | OOOOOOOOOOOOOOOOOOOOOOOOOOOOOOOOOOOOOOOOOOOOOOOOOOOOOOOOOOOOOOOOOOOOOOOOOOOOOOOOOOOOOOOOOO | OOOOOOOOOOOOOOOOOOOOOOOOOOOOOOOOOOOOOOOOOOOOOOOOOOOOOOOOOOOOOOOOOOOOOOOOOOOOOOOOOOOOOOOOOO |
| TLA Parts Change |  |  |  |  |  |  |  |  |  |
| Item | Foxconn P/N | Qty | Part Description | Manufacturer Full Name | Manufacturer P/N | RoHS | Location | Remark | BOM |
| BOM Change List Date:Fri Nov 24 15:41:53 GMT+08:00 2017 |  |  |  |  |  |  |  |  |  |
| New BOM file : E:\barreleye g2\1124\BG2-MB 1124.xls |  |  |  |  |  |  |  |  |  |
| Old BOM file : E:\barreleye g2\1124\BG2-MB 1120.xls |  |  |  |  |  |  |  |  |  |
| ##### Add Parts |  |  |  |  |  |  |  |  |  |
| Item | Location | Qty | Foxconn P/N | Part Description | Manufacturer Full Name | Manufacturer P/N | RoHS | Sheet |  |
| ##### Remove Parts |  |  |  |  |  |  |  |  |  |
| Item | Location | Qty | Foxconn P/N | Part Description | Manufacturer Full Name | Manufacturer P/N | RoHS | Sheet |  |
| ##### Change Parts |  |  |  |  |  |  |  |  |  |
| Item | Location | Qty | Foxconn P/N | Part Description | Manufacturer Full Name | Manufacturer P/N | RoHS | Sheet | Remark |
| 1 | U171 | 1 | 31050KL00-031-G | IC,Buffer,74HC75PW,2.0V~6.0V,G,TSSOP-16,SMD | NXP SEMICONDUCTORS | 74HC75PW | G | PWA BOM | In New BOM |
|  |  |  | 311007400-183-G | IC,Translator,CD74HC75PWRG4,2V~6V,G,TSSOP-16,SMD | TEXAS INSTRUMENTS | CD74HC75PWRG4 | G | PWA BOM | In New BOM |
|  | U171 | 1 | 31050KL00-031-G | IC,Buffer,74HC75PW,2.0V~6.0V,G,TSSOP-16,SMD | NXP SEMICONDUCTORS | 74HC75PW | G | PWA BOM | In Old BOM |
|  |  |  | 311007C00-183-G | IC,Translator,CD74HC75PWR,2V~6V,G,TSSOP-16,SMD | Texas Instruments | CD74HC75PWR | G | PWA BOM | In Old BOM |
| 2 | U24 | 1 | 410512F00-233-G | Flash,MX66L51235FMI-10G,2.7V~3.6V,512M,SPI,G,SOP-16,SMD | MACRONIX INTERNATIONAL CO.,LTD. | MX66L51235FMI-10G | G | PWA BOM | In New BOM |
|  | U24 | 1 | 41050DL00-233-G | Flash,MX25L6445EMI-10G,2.7~3.6V,64M,SPI,G,SOP-16,SMD | MACRONIX INTERNATIONAL CO.,LTD. | MX25L6445EMI-10G | G | PWA BOM | In Old BOM |
|  |  |  | 41050SF00-233-G | Flash,MX25L6435EMI-10G,2.7~3.6V,64M,SPI,G,SOP-16,SMD | MACRONIX INTERNATIONAL CO.,LTD. | MX25L6435EMI-10G | G | PWA BOM | In Old BOM |
|  |  |  | MX25L6433FMI-08G | Flash,MX25L6433FMI-08G,2.7~3.6V,64M,SPI,G,SOP-16,SMD | MACRONIX INTERNATIONAL CO.,LTD. | MX25L6433FMI-08G |  | PWA BOM | In Old BOM |
| ##### Change Revision |  |  |  |  |  |  |  |  |  |
| Sheet | REV OF BOM | CUSTOMER | CUSTOMER P/N | PWA PN | PWA DESCRIPTION | PWA REV | DATE | Remark |  |
| OOOOOOOOOOOOOOOOOOOOOOOOOOOOOOOOOOOOOOOOOOOOOOOOOOOOOOOOOOOOOOOOOOOOOOOOOOOOOOOOOOOOOOOOOO | OOOOOOOOOOOOOOOOOOOOOOOOOOOOOOOOOOOOOOOOOOOOOOOOOOOOOOOOOOOOOOOOOOOOOOOOOOOOOOOOOOOOOOOOOO | OOOOOOOOOOOOOOOOOOOOOOOOOOOOOOOOOOOOOOOOOOOOOOOOOOOOOOOOOOOOOOOOOOOOOOOOOOOOOOOOOOOOOOOOOO | OOOOOOOOOOOOOOOOOOOOOOOOOOOOOOOOOOOOOOOOOOOOOOOOOOOOOOOOOOOOOOOOOOOOOOOOOOOOOOOOOOOOOOOOOO | OOOOOOOOOOOOOOOOOOOOOOOOOOOOOOOOOOOOOOOOOOOOOOOOOOOOOOOOOOOOOOOOOOOOOOOOOOOOOOOOOOOOOOOOOO | OOOOOOOOOOOOOOOOOOOOOOOOOOOOOOOOOOOOOOOOOOOOOOOOOOOOOOOOOOOOOOOOOOOOOOOOOOOOOOOOOOOOOOOOOO | OOOOOOOOOOOOOOOOOOOOOOOOOOOOOOOOOOOOOOOOOOOOOOOOOOOOOOOOOOOOOOOOOOOOOOOOOOOOOOOOOOOOOOOOOO | OOOOOOOOOOOOOOOOOOOOOOOOOOOOOOOOOOOOOOOOOOOOOOOOOOOOOOOOOOOOOOOOOOOOOOOOOOOOOOOOOOOOOOOOOO | OOOOOOOOOOOOOOOOOOOOOOOOOOOOOOOOOOOOOOOOOOOOOOOOOOOOOOOOOOOOOOOOOOOOOOOOOOOOOOOOOOOOOOOOOO | OOOOOOOOOOOOOOOOOOOOOOOOOOOOOOOOOOOOOOOOOOOOOOOOOOOOOOOOOOOOOOOOOOOOOOOOOOOOOOOOOOOOOOOOOO |
| Second Source Change |  |  |  |  |  |  |  |  |  |
| Item | Location | Change Type | Foxconn P/N | Part Description | Manufacturer Full Name | Manufacturer P/N | RoHS | Sheet |  |
| 2 | U171 |  | 31050KL00-031-G | IC,Buffer,74HC75PW,2.0V~6.0V,G,TSSOP-16,SMD | NXP SEMICONDUCTORS | 74HC75PW | G | PWA BOM |  |
|  |  | ADD | 311007400-183-G | IC,Translator,CD74HC75PWRG4,2V~6V,G,TSSOP-16,SMD | TEXAS INSTRUMENTS | CD74HC75PWRG4 | G | PWA BOM |  |
|  |  | Delete | 311007C00-183-G | IC,Translator,CD74HC75PWR,2V~6V,G,TSSOP-16,SMD | Texas Instruments | CD74HC75PWR | G | PWA BOM |  |
| OOOOOOOOOOOOOOOOOOOOOOOOOOOOOOOOOOOOOOOOOOOOOOOOOOOOOOOOOOOOOOOOOOOOOOOOOOOOOOOOOOOOOOOOOO | OOOOOOOOOOOOOOOOOOOOOOOOOOOOOOOOOOOOOOOOOOOOOOOOOOOOOOOOOOOOOOOOOOOOOOOOOOOOOOOOOOOOOOOOOO | OOOOOOOOOOOOOOOOOOOOOOOOOOOOOOOOOOOOOOOOOOOOOOOOOOOOOOOOOOOOOOOOOOOOOOOOOOOOOOOOOOOOOOOOOO | OOOOOOOOOOOOOOOOOOOOOOOOOOOOOOOOOOOOOOOOOOOOOOOOOOOOOOOOOOOOOOOOOOOOOOOOOOOOOOOOOOOOOOOOOO | OOOOOOOOOOOOOOOOOOOOOOOOOOOOOOOOOOOOOOOOOOOOOOOOOOOOOOOOOOOOOOOOOOOOOOOOOOOOOOOOOOOOOOOOOO | OOOOOOOOOOOOOOOOOOOOOOOOOOOOOOOOOOOOOOOOOOOOOOOOOOOOOOOOOOOOOOOOOOOOOOOOOOOOOOOOOOOOOOOOOO | OOOOOOOOOOOOOOOOOOOOOOOOOOOOOOOOOOOOOOOOOOOOOOOOOOOOOOOOOOOOOOOOOOOOOOOOOOOOOOOOOOOOOOOOOO | OOOOOOOOOOOOOOOOOOOOOOOOOOOOOOOOOOOOOOOOOOOOOOOOOOOOOOOOOOOOOOOOOOOOOOOOOOOOOOOOOOOOOOOOOO | OOOOOOOOOOOOOOOOOOOOOOOOOOOOOOOOOOOOOOOOOOOOOOOOOOOOOOOOOOOOOOOOOOOOOOOOOOOOOOOOOOOOOOOOOO | OOOOOOOOOOOOOOOOOOOOOOOOOOOOOOOOOOOOOOOOOOOOOOOOOOOOOOOOOOOOOOOOOOOOOOOOOOOOOOOOOOOOOOOOOO |
| Master Materials Change |  |  |  |  |  |  |  |  |  |
| Item | Foxconn P/N | Orig._Usage | New_Usage | Part Description | Manufacturer Full Name | Manufacturer P/N | RoHS | Location | Sheet |
| 1 | 410512F00-233-G | 2 | 3 | Flash,MX66L51235FMI-10G,2.7V~3.6V,512M,SPI,G,SOP-16,SMD | MACRONIX INTERNATIONAL CO.,LTD. | MX66L51235FMI-10G | G | (+)U24 | PWA BOM |
| 2 | 41050DL00-233-G | 1 | 0 | Flash,MX25L6445EMI-10G,2.7~3.6V,64M,SPI,G,SOP-16,SMD | MACRONIX INTERNATIONAL CO.,LTD. | MX25L6445EMI-10G | G | (-)U24 | PWA BOM |
|  | 41050SF00-233-G |  |  | Flash,MX25L6435EMI-10G,2.7~3.6V,64M,SPI,G,SOP-16,SMD | MACRONIX INTERNATIONAL CO.,LTD. | MX25L6435EMI-10G |  |  | PWA BOM |
|  | MX25L6433FMI-08G |  |  | Flash,MX25L6433FMI-08G,2.7~3.6V,64M,SPI,G,SOP-16,SMD | MACRONIX INTERNATIONAL CO.,LTD. | MX25L6433FMI-08G |  |  | PWA BOM |
| OOOOOOOOOOOOOOOOOOOOOOOOOOOOOOOOOOOOOOOOOOOOOOOOOOOOOOOOOOOOOOOOOOOOOOOOOOOOOOOOOOOOOOOOOO | OOOOOOOOOOOOOOOOOOOOOOOOOOOOOOOOOOOOOOOOOOOOOOOOOOOOOOOOOOOOOOOOOOOOOOOOOOOOOOOOOOOOOOOOOO | OOOOOOOOOOOOOOOOOOOOOOOOOOOOOOOOOOOOOOOOOOOOOOOOOOOOOOOOOOOOOOOOOOOOOOOOOOOOOOOOOOOOOOOOOO | OOOOOOOOOOOOOOOOOOOOOOOOOOOOOOOOOOOOOOOOOOOOOOOOOOOOOOOOOOOOOOOOOOOOOOOOOOOOOOOOOOOOOOOOOO | OOOOOOOOOOOOOOOOOOOOOOOOOOOOOOOOOOOOOOOOOOOOOOOOOOOOOOOOOOOOOOOOOOOOOOOOOOOOOOOOOOOOOOOOOO | OOOOOOOOOOOOOOOOOOOOOOOOOOOOOOOOOOOOOOOOOOOOOOOOOOOOOOOOOOOOOOOOOOOOOOOOOOOOOOOOOOOOOOOOOO | OOOOOOOOOOOOOOOOOOOOOOOOOOOOOOOOOOOOOOOOOOOOOOOOOOOOOOOOOOOOOOOOOOOOOOOOOOOOOOOOOOOOOOOOOO | OOOOOOOOOOOOOOOOOOOOOOOOOOOOOOOOOOOOOOOOOOOOOOOOOOOOOOOOOOOOOOOOOOOOOOOOOOOOOOOOOOOOOOOOOO | OOOOOOOOOOOOOOOOOOOOOOOOOOOOOOOOOOOOOOOOOOOOOOOOOOOOOOOOOOOOOOOOOOOOOOOOOOOOOOOOOOOOOOOOOO | OOOOOOOOOOOOOOOOOOOOOOOOOOOOOOOOOOOOOOOOOOOOOOOOOOOOOOOOOOOOOOOOOOOOOOOOOOOOOOOOOOOOOOOOOO |
| TLA Parts Change |  |  |  |  |  |  |  |  |  |
| Item | Foxconn P/N | Qty | Part Description | Manufacturer Full Name | Manufacturer P/N | RoHS | Location | Remark | BOM |
| BOM Change List Date:Fri Dec 08 17:39:33 GMT+08:00 2017 |  |  |  |  |  |  |  |  |  |
| New BOM file : C:\<user>\BARRELEYE-G2-MB-PVT-HW-EBOM-20171208-1.xls |  |  |  |  |  |  |  |  |  |
| Old BOM file : C:\<user>\BARRELEYE-G2-MB-PVT-HW-EBOM-20171124-1.xls |  |  |  |  |  |  |  |  |  |
| ##### Add Parts |  |  |  |  |  |  |  |  |  |
| Item | Location | Qty | Foxconn P/N | Part Description | Manufacturer Full Name | Manufacturer P/N | RoHS | Sheet |  |
| 1 | PBAC20 | 1 | 62011J601-015-G | CAP,2.2uF,+/-10%,X7R,100V,G,SMD1210 | MURATA ELEC. NORTH AMERICA | GRM32ER72A225K |  | PWA BOM |  |
| 2 | R2045,R2046,R2047,R2048,R2049,R2050,R2051,R2052 | 8 | 610107A00-017-G | RES,0 Ohm,+/-5%,1/16W,G,SMD0402 | KOA SPEER ELECTRONICS, INC. | RK73Z1ETTP | N | PWA BOM |  |
| 3 | PAAR70,PBAR71 | 2 | 610100C00-017-G | RES,15kOhm,+/-1%,1/10W,G,SMD0603 | KOA SPEER ELECTRONICS, INC. | RK73H1JTTD1502F | N | PWA BOM |  |
| ##### Remove Parts |  |  |  |  |  |  |  |  |  |
| Item | Location | Qty | Foxconn P/N | Part Description | Manufacturer Full Name | Manufacturer P/N | RoHS | Sheet |  |
| 1 | PBAC21 | 1 | 62011J601-015-G | CAP,2.2uF,+/-10%,X7R,100V,G,SMD1210 | MURATA ELEC. NORTH AMERICA | GRM32ER72A225K |  | PWA BOM |  |
| ##### Change Parts |  |  |  |  |  |  |  |  |  |
| Item | Location | Qty | Foxconn P/N | Part Description | Manufacturer Full Name | Manufacturer P/N | RoHS | Sheet | Remark |
| 1 | J_BMC_DEBUG1,J1,J4,J5,J36,J41,J43,J48,J147,J149 | 10 | 87898-0318 | CONN,Header,Pin Header,1X3,V/T,2.54mm,30u,G,SMD-3 | MOLEX INCORPORATED | 87898-0318 |  | PWA BOM | In New BOM |
|  | J_BMC_DEBUG1,J1,J4,J5,J36,J41,J43,J48,J147,J149 | 10 | 34068LN00-317-G | CONN,Header,Pin Header,1X3,V/T,2.54mm,30u,G,SMD-3 | MOLEX INCORPORATED | 87898-0315 |  | PWA BOM | In Old BOM |
| 2 | J148 | 1 | 87898-0458 | CONN,Pin Header,1X4,V/T,Bla,2.54mm,30u,G,SMD-4 | MOLEX INCORPORATED | 87898-0458 |  | PWA BOM | In New BOM |
|  | J148 | 1 | 340672300-317-G | CONN,Pin Header,1X4,V/T,Bla,2.54mm,30u,G,SMD-4 | MOLEX INCORPORATED | 87898-0455 |  | PWA BOM | In Old BOM |
| 3 | PBAR127,PAAR127 | 2 | 61010PS00-017-G | RES,200KOhm,+/-1%,1/16W,G,SMD0402 | KOA SPEER ELECTRONICS, INC. | RK73H1ETTP2003F | N | PWA BOM | In New BOM |
|  | PBAR127,PAAR127 | 2 | 61011G600-017-G | RES,133KOhm,+/-1%,1/16W,G,SMD0402 | KOA SPEER ELECTRONICS, INC. | RK73G1ETTP1333F |  | PWA BOM | In Old BOM |
| 4 | PAAR66,PBAR67,PBAR79,PAAR79 | 4 | 61010R900-017-G | RES,27.4KOhm,+/-1%,1/10W,G,SMD0603 | KOA SPEER ELECTRONICS, INC. | RK73H1JTTD2742F | N | PWA BOM | In New BOM |
|  | PAAR66,PBAR67,PBAR79,PAAR79 | 4 | 610103D00-017-G | RES,24.3KOhm,+/-1%,1/10W,G,SMD0603 | KOA SPEER ELECTRONICS, INC. | RK73H1JTTD2432F | N | PWA BOM | In Old BOM |
| 5 | PAAR67,PBAR68 | 2 | 61010G500-017-G | RES,10KOhm,+/-1%,1/16W,G,SMD0402 | KOA SPEER ELECTRONICS, INC. | RK73H1ETTP1002F | N | PWA BOM | In New BOM |
|  | PAAR67,PBAR68 | 2 | 610107A00-017-G | RES,0 Ohm,+/-5%,1/16W,G,SMD0402 | KOA SPEER ELECTRONICS, INC. | RK73Z1ETTP | N | PWA BOM | In Old BOM |
| 6 | PBAR80,PAAR80 | 2 | 610100C00-017-G | RES,15kOhm,+/-1%,1/10W,G,SMD0603 | KOA SPEER ELECTRONICS, INC. | RK73H1JTTD1502F | N | PWA BOM | In New BOM |
|  | PBAR80,PAAR80 | 2 | 61010DG00-017-G | RES,4.99KOhm,+/-1%,1/10W,G,SMD0603 | KOA SPEER ELECTRONICS, INC. | RK73H1JTTD4991F | N | PWA BOM | In Old BOM |
| 7 | PBER65,PAFR65,PAER65,PBFR66 | 4 | 610606H00-017-G | RES,50mOhm,+/-1%,1.5W,G,SMD2512 | KOA | SLW1TTE50L0F |  | PWA BOM | In New BOM |
|  | PBER65,PAFR65,PAER65,PBFR66 | 4 | SLW1TTE50L0F | RES,50mOhm,+/-1%,1.5W,G,SMD2512 | KOA | SLW1TTE50L0F |  | PWA BOM | In Old BOM |
| 8 | PBMR34,PAMR34 | 2 | 61100YW00-017-G | RES,316 Ohm,+/-0.1%,1/16W,G,SMD0402 | KOA SPEER ELECTRONICS, INC. | RN731ETTP3160B25 |  | PWA BOM | In New BOM |
|  | PBMR34,PAMR34 | 2 | RN731ETTP3160B25 | RES,316 Ohm,+/-0.1%,1/16W,G,SMD0402 | KOA SPEER ELECTRONICS, INC. | RN731ETTP3160B25 | N | PWA BOM | In Old BOM |
| 9 | PBMR65,PAMR65 | 2 | 610606J00-017-G | RES,75mOhm,+/-1%,1.5W,G,SMD2512 | KOA | SLW1TTE75L0F |  | PWA BOM | In New BOM |
|  | PBMR65,PAMR65 | 2 | SLW1TTE75L0F | RES,75mOhm,+/-1%,1.5W,G,SMD2512 | KOA | SLW1TTE75L0F |  | PWA BOM | In Old BOM |
| 10 | PHAC3 | 1 | 62011DB01-015-G | CAP,1nF,+/-10%,X7R,100V,G,SMD0402 | MURATA ELEC. NORTH AMERICA | GRM155R72A102KA01D | Y | PWA BOM | In New BOM |
|  | PHAC3 | 1 | 62011DB01-015-G | CAP,1nF,+/-10%,X7R,100V,G,SMD0402 | MURATA ELEC. NORTH AMERICA | GRM155R72A102K | Y | PWA BOM | In Old BOM |
| 11 | PSUQ1 | 1 | 510301N00-223-G | MOS N,2N7002LT1G,60V,0.115A,7.5ohm@5V,G,SOT23-3,SMD | ON SEMICONDUCTOR CORP | 2N7002LT1G | N | PWA BOM | In New BOM |
|  | PSUQ1 | 1 | 51030CQ00-185-G | MOS N,2N7002,60V,115mA,7.5ohm@5V,G,SOT23-3,SMD | FAIRCHILD SEMICONDUCTOR CORP | 2N7002 | N | PWA BOM | In Old BOM |
| 12 | PBAR34,PAAR34 | 2 | KOA_RN731ETTP5900B25 | RES,590Ohm,+/-0.1%,1/16W,G,SMD0402 | KOA SPEER ELECTRONICS, INC. | RN731ETTP5900B25 | Y | PWA BOM | In New BOM |
|  | PBAR34,PAAR34 | 2 | 611003D00-017-G | RES,1KOhm,+/-0.1%,1/16W,G,SMD0402 | KOA SPEER ELECTRONICS, INC. | RN731ETTP1001B25 | Y | PWA BOM | In Old BOM |
| 13 | U1,U10 | 2 | 340109B00-600-G | POWER9 CPU Socket for LGA3899-HYBRID | FOXCONN TECHNOLOGY CO.,LTD. | PE38993-51BC1-1H |  | PWA BOM | In New BOM |
|  | U1,U10 | 2 | PE38993-51BC1-1H | POWER9 CPU Socket for LGA3899-HYBRID | FOXCONN TECHNOLOGY CO.,LTD. | PE38993-51BC1-1H |  | PWA BOM | In Old BOM |
| ##### Change Revision |  |  |  |  |  |  |  |  |  |
| Sheet | REV OF BOM | CUSTOMER | CUSTOMER P/N | PWA PN | PWA DESCRIPTION | PWA REV | DATE | Remark |  |
| OOOOOOOOOOOOOOOOOOOOOOOOOOOOOOOOOOOOOOOOOOOOOOOOOOOOOOOOOOOOOOOOOOOOOOOOOOOOOOOOOOOOOOOOOO | OOOOOOOOOOOOOOOOOOOOOOOOOOOOOOOOOOOOOOOOOOOOOOOOOOOOOOOOOOOOOOOOOOOOOOOOOOOOOOOOOOOOOOOOOO | OOOOOOOOOOOOOOOOOOOOOOOOOOOOOOOOOOOOOOOOOOOOOOOOOOOOOOOOOOOOOOOOOOOOOOOOOOOOOOOOOOOOOOOOOO | OOOOOOOOOOOOOOOOOOOOOOOOOOOOOOOOOOOOOOOOOOOOOOOOOOOOOOOOOOOOOOOOOOOOOOOOOOOOOOOOOOOOOOOOOO | OOOOOOOOOOOOOOOOOOOOOOOOOOOOOOOOOOOOOOOOOOOOOOOOOOOOOOOOOOOOOOOOOOOOOOOOOOOOOOOOOOOOOOOOOO | OOOOOOOOOOOOOOOOOOOOOOOOOOOOOOOOOOOOOOOOOOOOOOOOOOOOOOOOOOOOOOOOOOOOOOOOOOOOOOOOOOOOOOOOOO | OOOOOOOOOOOOOOOOOOOOOOOOOOOOOOOOOOOOOOOOOOOOOOOOOOOOOOOOOOOOOOOOOOOOOOOOOOOOOOOOOOOOOOOOOO | OOOOOOOOOOOOOOOOOOOOOOOOOOOOOOOOOOOOOOOOOOOOOOOOOOOOOOOOOOOOOOOOOOOOOOOOOOOOOOOOOOOOOOOOOO | OOOOOOOOOOOOOOOOOOOOOOOOOOOOOOOOOOOOOOOOOOOOOOOOOOOOOOOOOOOOOOOOOOOOOOOOOOOOOOOOOOOOOOOOOO | OOOOOOOOOOOOOOOOOOOOOOOOOOOOOOOOOOOOOOOOOOOOOOOOOOOOOOOOOOOOOOOOOOOOOOOOOOOOOOOOOOOOOOOOOO |
| Second Source Change |  |  |  |  |  |  |  |  |  |
| Item | Location | Change Type | Foxconn P/N | Part Description | Manufacturer Full Name | Manufacturer P/N | RoHS | Sheet |  |
| OOOOOOOOOOOOOOOOOOOOOOOOOOOOOOOOOOOOOOOOOOOOOOOOOOOOOOOOOOOOOOOOOOOOOOOOOOOOOOOOOOOOOOOOOO | OOOOOOOOOOOOOOOOOOOOOOOOOOOOOOOOOOOOOOOOOOOOOOOOOOOOOOOOOOOOOOOOOOOOOOOOOOOOOOOOOOOOOOOOOO | OOOOOOOOOOOOOOOOOOOOOOOOOOOOOOOOOOOOOOOOOOOOOOOOOOOOOOOOOOOOOOOOOOOOOOOOOOOOOOOOOOOOOOOOOO | OOOOOOOOOOOOOOOOOOOOOOOOOOOOOOOOOOOOOOOOOOOOOOOOOOOOOOOOOOOOOOOOOOOOOOOOOOOOOOOOOOOOOOOOOO | OOOOOOOOOOOOOOOOOOOOOOOOOOOOOOOOOOOOOOOOOOOOOOOOOOOOOOOOOOOOOOOOOOOOOOOOOOOOOOOOOOOOOOOOOO | OOOOOOOOOOOOOOOOOOOOOOOOOOOOOOOOOOOOOOOOOOOOOOOOOOOOOOOOOOOOOOOOOOOOOOOOOOOOOOOOOOOOOOOOOO | OOOOOOOOOOOOOOOOOOOOOOOOOOOOOOOOOOOOOOOOOOOOOOOOOOOOOOOOOOOOOOOOOOOOOOOOOOOOOOOOOOOOOOOOOO | OOOOOOOOOOOOOOOOOOOOOOOOOOOOOOOOOOOOOOOOOOOOOOOOOOOOOOOOOOOOOOOOOOOOOOOOOOOOOOOOOOOOOOOOOO | OOOOOOOOOOOOOOOOOOOOOOOOOOOOOOOOOOOOOOOOOOOOOOOOOOOOOOOOOOOOOOOOOOOOOOOOOOOOOOOOOOOOOOOOOO | OOOOOOOOOOOOOOOOOOOOOOOOOOOOOOOOOOOOOOOOOOOOOOOOOOOOOOOOOOOOOOOOOOOOOOOOOOOOOOOOOOOOOOOOOO |
| Master Materials Change |  |  |  |  |  |  |  |  |  |
| Item | Foxconn P/N | Orig._Usage | New_Usage | Part Description | Manufacturer Full Name | Manufacturer P/N | RoHS | Location | Sheet |
| 1 | 87898-0318 | 0 | 10 | CONN,Header,Pin Header,1X3,V/T,2.54mm,30u,G,SMD-3 | MOLEX INCORPORATED | 87898-0318 |  | (+)J_BMC_DEBUG1,J1,J4,J5,J36,J41,J43,J48,J147,J149 | PWA BOM |
| 2 | 87898-0458 | 0 | 1 | CONN,Pin Header,1X4,V/T,Bla,2.54mm,30u,G,SMD-4 | MOLEX INCORPORATED | 87898-0458 |  | (+)J148 | PWA BOM |
| 3 | 610107A00-017-G | 713 | 719 | RES,0 Ohm,+/-5%,1/16W,G,SMD0402 | KOA SPEER ELECTRONICS, INC. | RK73Z1ETTP | N | (+)R2045,R2046,R2047,R2048,R2049,R2050,R2051,R2052 (-)PAAR67,PBAR68 | PWA BOM |
| 4 | 61010PS00-017-G | 48 | 50 | RES,200KOhm,+/-1%,1/16W,G,SMD0402 | KOA SPEER ELECTRONICS, INC. | RK73H1ETTP2003F | N | (+)PBAR127,PAAR127 | PWA BOM |
| 5 | 611003D00-017-G | 10 | 8 | RES,1KOhm,+/-0.1%,1/16W,G,SMD0402 | KOA SPEER ELECTRONICS, INC. | RN731ETTP1001B25 | Y | (-)PBAR34,PAAR34 | PWA BOM |
| 6 | 61010R900-017-G | 4 | 8 | RES,27.4KOhm,+/-1%,1/10W,G,SMD0603 | KOA SPEER ELECTRONICS, INC. | RK73H1JTTD2742F | N | (+)PAAR66,PBAR67,PBAR79,PAAR79 | PWA BOM |
| 7 | 61010G500-017-G | 101 | 103 | RES,10KOhm,+/-1%,1/16W,G,SMD0402 | KOA SPEER ELECTRONICS, INC. | RK73H1ETTP1002F | N | (+)PAAR67,PBAR68 | PWA BOM |
| 8 | 610100C00-017-G | 0 | 4 | RES,15kOhm,+/-1%,1/10W,G,SMD0603 | KOA SPEER ELECTRONICS, INC. | RK73H1JTTD1502F | N | (+)PAAR70,PBAR71,PBAR80,PAAR80 | PWA BOM |
| 9 | 610606H00-017-G | 0 | 4 | RES,50mOhm,+/-1%,1.5W,G,SMD2512 | KOA | SLW1TTE50L0F |  | (+)PBER65,PAFR65,PAER65,PBFR66 | PWA BOM |
| 10 | 61100YW00-017-G | 0 | 2 | RES,316 Ohm,+/-0.1%,1/16W,G,SMD0402 | KOA SPEER ELECTRONICS, INC. | RN731ETTP3160B25 |  | (+)PBMR34,PAMR34 | PWA BOM |
| 11 | 610606J00-017-G | 0 | 2 | RES,75mOhm,+/-1%,1.5W,G,SMD2512 | KOA | SLW1TTE75L0F |  | (+)PBMR65,PAMR65 | PWA BOM |
| 12 | 510301N00-223-G | 5 | 6 | MOS N,2N7002LT1G,60V,0.115A,7.5ohm@5V,G,SOT23-3,SMD | ON SEMICONDUCTOR CORP | 2N7002LT1G | N | (+)PSUQ1 | PWA BOM |
| 13 | KOA_RN731ETTP5900B25 | 0 | 2 | RES,590Ohm,+/-0.1%,1/16W,G,SMD0402 | KOA SPEER ELECTRONICS, INC. | RN731ETTP5900B25 | Y | (+)PBAR34,PAAR34 | PWA BOM |
| 14 | 340109B00-600-G | 0 | 2 | POWER9 CPU Socket for LGA3899-HYBRID | FOXCONN TECHNOLOGY CO.,LTD. | PE38993-51BC1-1H |  | (+)U1,U10 | PWA BOM |
| 15 | 610103D00-017-G | 4 | 0 | RES,24.3KOhm,+/-1%,1/10W,G,SMD0603 | KOA SPEER ELECTRONICS, INC. | RK73H1JTTD2432F | N | (-)PAAR66,PBAR67,PBAR79,PAAR79 | PWA BOM |
| 16 | 61010DG00-017-G | 2 | 0 | RES,4.99KOhm,+/-1%,1/10W,G,SMD0603 | KOA SPEER ELECTRONICS, INC. | RK73H1JTTD4991F | N | (-)PBAR80,PAAR80 | PWA BOM |
| 17 | 61011G600-017-G | 2 | 0 | RES,133KOhm,+/-1%,1/16W,G,SMD0402 | KOA SPEER ELECTRONICS, INC. | RK73G1ETTP1333F |  | (-)PBAR127,PAAR127 | PWA BOM |
| 18 | 51030CQ00-185-G | 1 | 0 | MOS N,2N7002,60V,115mA,7.5ohm@5V,G,SOT23-3,SMD | FAIRCHILD SEMICONDUCTOR CORP | 2N7002 | N | (-)PSUQ1 | PWA BOM |
| 19 | 34068LN00-317-G | 10 | 0 | CONN,Header,Pin Header,1X3,V/T,2.54mm,30u,G,SMD-3 | MOLEX INCORPORATED | 87898-0315 |  | (-)J_BMC_DEBUG1,J1,J4,J5,J36,J41,J43,J48,J147,J149 | PWA BOM |
| 20 | 340672300-317-G | 1 | 0 | CONN,Pin Header,1X4,V/T,Bla,2.54mm,30u,G,SMD-4 | MOLEX INCORPORATED | 87898-0455 |  | (-)J148 | PWA BOM |
| 21 | SLW1TTE50L0F | 4 | 0 | RES,50mOhm,+/-1%,1.5W,G,SMD2512 | KOA | SLW1TTE50L0F |  | (-)PBER65,PAFR65,PAER65,PBFR66 | PWA BOM |
| 22 | RN731ETTP3160B25 | 2 | 0 | RES,316 Ohm,+/-0.1%,1/16W,G,SMD0402 | KOA SPEER ELECTRONICS, INC. | RN731ETTP3160B25 | N | (-)PBMR34,PAMR34 | PWA BOM |
| 23 | SLW1TTE75L0F | 2 | 0 | RES,75mOhm,+/-1%,1.5W,G,SMD2512 | KOA | SLW1TTE75L0F |  | (-)PBMR65,PAMR65 | PWA BOM |
| 24 | PE38993-51BC1-1H | 2 | 0 | POWER9 CPU Socket for LGA3899-HYBRID | FOXCONN TECHNOLOGY CO.,LTD. | PE38993-51BC1-1H |  | (-)U1,U10 | PWA BOM |
| OOOOOOOOOOOOOOOOOOOOOOOOOOOOOOOOOOOOOOOOOOOOOOOOOOOOOOOOOOOOOOOOOOOOOOOOOOOOOOOOOOOOOOOOOO | OOOOOOOOOOOOOOOOOOOOOOOOOOOOOOOOOOOOOOOOOOOOOOOOOOOOOOOOOOOOOOOOOOOOOOOOOOOOOOOOOOOOOOOOOO | OOOOOOOOOOOOOOOOOOOOOOOOOOOOOOOOOOOOOOOOOOOOOOOOOOOOOOOOOOOOOOOOOOOOOOOOOOOOOOOOOOOOOOOOOO | OOOOOOOOOOOOOOOOOOOOOOOOOOOOOOOOOOOOOOOOOOOOOOOOOOOOOOOOOOOOOOOOOOOOOOOOOOOOOOOOOOOOOOOOOO | OOOOOOOOOOOOOOOOOOOOOOOOOOOOOOOOOOOOOOOOOOOOOOOOOOOOOOOOOOOOOOOOOOOOOOOOOOOOOOOOOOOOOOOOOO | OOOOOOOOOOOOOOOOOOOOOOOOOOOOOOOOOOOOOOOOOOOOOOOOOOOOOOOOOOOOOOOOOOOOOOOOOOOOOOOOOOOOOOOOOO | OOOOOOOOOOOOOOOOOOOOOOOOOOOOOOOOOOOOOOOOOOOOOOOOOOOOOOOOOOOOOOOOOOOOOOOOOOOOOOOOOOOOOOOOOO | OOOOOOOOOOOOOOOOOOOOOOOOOOOOOOOOOOOOOOOOOOOOOOOOOOOOOOOOOOOOOOOOOOOOOOOOOOOOOOOOOOOOOOOOOO | OOOOOOOOOOOOOOOOOOOOOOOOOOOOOOOOOOOOOOOOOOOOOOOOOOOOOOOOOOOOOOOOOOOOOOOOOOOOOOOOOOOOOOOOOO |  |
| TLA Parts Change |  |  |  |  |  |  |  |  |  |
| Item | Foxconn P/N | Qty | Part Description | Manufacturer Full Name | Manufacturer P/N | RoHS | Location | Remark |  |
| BOM Change List Date:Sat Dec 09 11:16:23 GMT+08:00 2017 |  |  |  |  |  |  |  |  |  |
| New BOM file : E:\barreleye g2\1209\BARRELEYE_G2-MB-PVT-X04-HW-BOM-X22_20171209.xls |  |  |  |  |  |  |  |  |  |
| Old BOM file : E:\barreleye g2\1209\BG2 1127.xls |  |  |  |  |  |  |  |  |  |
| ##### Add Parts |  |  |  |  |  |  |  |  |  |
| Item | Location | Qty | Foxconn P/N | Part Description | Manufacturer Full Name | Manufacturer P/N | RoHS | Sheet |  |
| 1 | PBAC20 | 1 | 62011J601-015-G | CAP,2.2uF,+/-10%,X7R,100V,G,SMD1210 | MURATA ELEC. NORTH AMERICA | GRM32ER72A225K | G | PWA BOM |  |
|  |  |  | 62011J600-026-G | CAP,2.2uF,+/-10%,X7R,100V,G,SMD1210 | SAMSUNG SEMICONDUCTOR | CL32B225KCJSNNE | G | PWA BOM |  |
| 2 | R2045,R2046,R2047,R2048,R2049,R2050,R2051,R2052 | 8 | 610107A00-017-G | RES,0 Ohm,+/-5%,1/16W,G,SMD0402 | KOA SPEER ELECTRONICS, INC. | RK73Z1ETTP | G | PWA BOM |  |
|  |  |  | 610107A00-012-G | RES,0 Ohm,+/-5%,1/16W,G,SMD0402 | WALSIN TECHNOLOGY CORPORATION | WR04X000PTL | G | PWA BOM |  |
|  |  |  | 610107A00-011-G | RES,0 Ohm,+/-5%,1/16W,G,SMD0402 | YAGEO CORPORATION COMPONENT | RC0402JR-070RL | G | PWA BOM |  |
|  |  |  | 610107A00-044-G | RES,0 Ohm,+/-5%,1/16W,G,SMD0402 | TA-I TECHNOLOGY CO., LTD | RM04JTN0 | G | PWA BOM |  |
|  |  |  | 610107A00-024-G | RES,0 Ohm,+/-5%,1/16W,G,SMD0402 | PANASONIC INDUSTRIAL CO.,LTD. | ERJ2GE0R00X | G | PWA BOM |  |
|  |  |  | 610107A00-029-G | RES,0 Ohm,+/-5%,1/16W,G,SMD0402 | VISHAY ENTER TECHNO LOGY.INC | CRCW04020000Z0ED | G | PWA BOM |  |
| 3 | PAAR70,PBAR71 | 2 | 610100C00-017-G | RES,15kOhm,+/-1%,1/10W,G,SMD0603 | KOA SPEER ELECTRONICS, INC. | RK73H1JTTD1502F | G | PWA BOM |  |
|  |  |  | 610100C00-011-G | RES,15KOhm,+/-1%,1/10W,G,SMD0603 | YAGEO CORPORATION COMPONENT | RC0603FR-0715KL | G | PWA BOM |  |
|  |  |  | 610100C00-012-G | RES,15KOhm,+/-1%,1/10W,G,SMD0603 | WALSIN TECHNOLOGY CORPORATION | WR06X1502FTL | G | PWA BOM |  |
|  |  |  | 610100C00-044-G | RES,15KOhm,+/-1%,1/10W,G,SMD0603 | TA-I TECHNOLOGY CO., LTD | RM06FTN1502 | G | PWA BOM |  |
| ##### Remove Parts |  |  |  |  |  |  |  |  |  |
| Item | Location | Qty | Foxconn P/N | Part Description | Manufacturer Full Name | Manufacturer P/N | RoHS | Sheet |  |
| 1 | PBAC21 | 1 | 62011J601-015-G | CAP,2.2uF,+/-10%,X7R,100V,G,SMD1210 | MURATA ELEC. NORTH AMERICA | GRM32ER72A225K | G | PWA BOM |  |
|  |  |  | 62011J600-026-G | CAP,2.2uF,+/-10%,X7R,100V,G,SMD1210 | SAMSUNG SEMICONDUCTOR | CL32B225KCJSNNE | G | PWA BOM |  |
| ##### Change Parts |  |  |  |  |  |  |  |  |  |
| Item | Location | Qty | Foxconn P/N | Part Description | Manufacturer Full Name | Manufacturer P/N | RoHS | Sheet | Remark |
| 1 | D14 | 1 | 520305J00-223-G | DIODE,Schottky,MBR130LSFT1G,30V,1A,G,SOD123FL-2,SMD | ON SEMICONDUCTOR CORP | MBR130LSFT1G | G | PWA BOM | In New BOM |
|  |  |  | 52030GG00-031-G | Diode,Schottky,PMEG3010ER,30V,1A,SOD-123,2P,G | NXP SEMICONDUCTORS | PMEG3010ER | G | PWA BOM | In New BOM |
|  | D14 | 1 | 520305J00-223-G | DIODE,Schottky,MBR130LSFT1G,30V,1A,G,SOD123FL-2,SMD | ON SEMICONDUCTOR CORP | MBR130LSFT1G | G | PWA BOM | In Old BOM |
| 2 | J28,J31 | 2 | 34071BR00-245-G | CONN,SAS,V/T,0.6mm,30u,G,SMD-74 | AMPHENOL SHANGHAI CORP. | U10-K074-260T | G | PWA BOM | In New BOM |
|  |  |  | U10-K274-260T | CONN,SAS,V/T,0.6mm,30u,G,SMD-74 | AMPHENOL SHANGHAI CORP. | U10-K274-260T | G | PWA BOM | In New BOM |
|  | J28,J31 | 2 | 34071BR00-245-G | CONN,SAS,V/T,0.6mm,30u,G,SMD-74 | AMPHENOL SHANGHAI CORP. | U10-K074-260T | G | PWA BOM | In Old BOM |
| 3 | J30,J33 | 2 | 34071BS00-245-G | CONN,SAS,V/T,0.6mm,30u,G,SMD-74 | AMPHENOL SHANGHAI CORP. | U10-K074-26BT | G | PWA BOM | In New BOM |
|  |  |  | U10-K274-26BT | CONN,SAS,V/T,0.6mm,30u,G,SMD-74 | AMPHENOL SHANGHAI CORP. | U10-K274-26BT | G | PWA BOM | In New BOM |
|  | J30,J33 | 2 | 34071BS00-245-G | CONN,SAS,V/T,0.6mm,30u,G,SMD-74 | AMPHENOL SHANGHAI CORP. | U10-K074-26BT | G | PWA BOM | In Old BOM |
| 4 | PBAR127,PAAR127 | 2 | 61010PS00-017-G | RES,200KOhm,+/-1%,1/16W,G,SMD0402 | KOA SPEER ELECTRONICS, INC. | RK73H1ETTP2003F | G | PWA BOM | In New BOM |
|  |  |  | 61010PS00-012-G | RES,200KOhm,+/-1%,1/16W,G,SMD0402 | WALSIN TECHNOLOGY CORPORATION | WR04X2003FTL | G | PWA BOM | In New BOM |
|  |  |  | 61010PS00-011-G | RES,200KOhm,+/-1%,1/16W,G,SMD0402 | YAGEO CORPORATION COMPONENT | RC0402FR-07200KL | G | PWA BOM | In New BOM |
|  |  |  | 61010PS00-044-G | RES,200KOhm,+/-1%,1/16W,G,SMD0402 | TA-I TECHNOLOGY CO., LTD | RM04FTN2003 | G | PWA BOM | In New BOM |
|  | PBAR127,PAAR127 | 2 | 61011G600-017-G | RES,133KOhm,+/-1%,1/16W,G,SMD0402 | KOA SPEER ELECTRONICS, INC. | RK73G1ETTP1333F | G | PWA BOM | In Old BOM |
|  |  |  | 61011G600-011-G | RES,133KOhm,+/-1%,1/16W,G,SMD0402 | YAGEO CORPORATION COMPONENT | RC0402FR-07133KL | G | PWA BOM | In Old BOM |
|  |  |  | 61011G600-012-G | RES,133KOhm,+/-1%,1/16W,G,SMD0402 | WALSIN TECHNOLOGY CORPORATION | WR04X1333FTL | G | PWA BOM | In Old BOM |
|  |  |  | 61011G600-044-G | RES,133KOhm,+/-1%,1/16W,G,SMD0402 | TA-I TECHNOLOGY CO., LTD | RM04FTN1333 | G | PWA BOM | In Old BOM |
| 5 | PAAR66,PBAR67,PBAR79,PAAR79 | 4 | 61010R900-017-G | RES,27.4KOhm,+/-1%,1/10W,G,SMD0603 | KOA SPEER ELECTRONICS, INC. | RK73H1JTTD2742F | G | PWA BOM | In New BOM |
|  |  |  | 61010R900-012-G | RES,27.4KOhm,+/-1%,1/10W,G,SMD0603 | WALSIN TECHNOLOGY CORPORATION | WR06X2742FTL | G | PWA BOM | In New BOM |
|  |  |  | 61010R900-011-G | RES,27.4KOhm,+/-1%,1/10W,G,SMD0603 | YAGEO CORPORATION COMPONENT | RC0603FR-0727K4L | G | PWA BOM | In New BOM |
|  | PAAR66,PBAR67,PBAR79,PAAR79 | 4 | 610103D00-017-G | RES,24.3KOhm,+/-1%,1/10W,G,SMD0603 | KOA SPEER ELECTRONICS, INC. | RK73H1JTTD2432F | G | PWA BOM | In Old BOM |
|  |  |  | 610103D00-011-G | RES,24.3KOhm,+/-1%,1/10W,G,SMD0603 | YAGEO CORPORATION COMPONENT | RC0603FR-0724K3L | G | PWA BOM | In Old BOM |
|  |  |  | 610103D00-012-G | RES,24.3KOhm,+/-1%,1/10W,G,SMD0603 | WALSIN TECHNOLOGY CORPORATION | WR06X2432FTL | G | PWA BOM | In Old BOM |
| 6 | PAAR67,PBAR68 | 2 | 61010G500-017-G | RES,10KOhm,+/-1%,1/16W,G,SMD0402 | KOA SPEER ELECTRONICS, INC. | RK73H1ETTP1002F | G | PWA BOM | In New BOM |
|  |  |  | 61010G500-012-G | RES,10KOhm,+/-1%,1/16W,G,SMD0402 | WALSIN TECHNOLOGY CORPORATION | WR04X1002FTL | G | PWA BOM | In New BOM |
|  |  |  | 61010G500-011-G | RES,10KOhm,+/-1%,1/16W,G,SMD0402 | YAGEO CORPORATION COMPONENT | RC0402FR-0710KL | G | PWA BOM | In New BOM |
|  |  |  | 61010G500-044-G | RES,10KOhm,+/-1%,1/16W,G,SMD0402 | TA-I TECHNOLOGY CO., LTD | RM04FTN1002 | G | PWA BOM | In New BOM |
|  |  |  | 61010G500-029-G | RES,10KOhm,+/-1%,1/16W,G,SMD0402 | VISHAY ENTER TECHNO LOGY.INC | CRCW040210K0FKED | G | PWA BOM | In New BOM |
|  |  |  | 61010G500-024-G | RES,10KOhm,+/-1%,1/16W,G,SMD0402 | PANASONIC INDUSTRIAL CO.,LTD. | ERJ2RKF1002X | G | PWA BOM | In New BOM |
|  | PAAR67,PBAR68 | 2 | 610107A00-017-G | RES,0 Ohm,+/-5%,1/16W,G,SMD0402 | KOA SPEER ELECTRONICS, INC. | RK73Z1ETTP | G | PWA BOM | In Old BOM |
|  |  |  | 610107A00-012-G | RES,0 Ohm,+/-5%,1/16W,G,SMD0402 | WALSIN TECHNOLOGY CORPORATION | WR04X000PTL | G | PWA BOM | In Old BOM |
|  |  |  | 610107A00-011-G | RES,0 Ohm,+/-5%,1/16W,G,SMD0402 | YAGEO CORPORATION COMPONENT | RC0402JR-070RL | G | PWA BOM | In Old BOM |
|  |  |  | 610107A00-044-G | RES,0 Ohm,+/-5%,1/16W,G,SMD0402 | TA-I TECHNOLOGY CO., LTD | RM04JTN0 | G | PWA BOM | In Old BOM |
|  |  |  | 610107A00-024-G | RES,0 Ohm,+/-5%,1/16W,G,SMD0402 | PANASONIC INDUSTRIAL CO.,LTD. | ERJ2GE0R00X | G | PWA BOM | In Old BOM |
|  |  |  | 610107A00-029-G | RES,0 Ohm,+/-5%,1/16W,G,SMD0402 | VISHAY ENTER TECHNO LOGY.INC | CRCW04020000Z0ED | G | PWA BOM | In Old BOM |
| 7 | PBAR80,PAAR80 | 2 | 610100C00-017-G | RES,15kOhm,+/-1%,1/10W,G,SMD0603 | KOA SPEER ELECTRONICS, INC. | RK73H1JTTD1502F | G | PWA BOM | In New BOM |
|  |  |  | 610100C00-011-G | RES,15KOhm,+/-1%,1/10W,G,SMD0603 | YAGEO CORPORATION COMPONENT | RC0603FR-0715KL | G | PWA BOM | In New BOM |
|  |  |  | 610100C00-012-G | RES,15KOhm,+/-1%,1/10W,G,SMD0603 | WALSIN TECHNOLOGY CORPORATION | WR06X1502FTL | G | PWA BOM | In New BOM |
|  |  |  | 610100C00-044-G | RES,15KOhm,+/-1%,1/10W,G,SMD0603 | TA-I TECHNOLOGY CO., LTD | RM06FTN1502 | G | PWA BOM | In New BOM |
|  | PBAR80,PAAR80 | 2 | 61010DG00-017-G | RES,4.99KOhm,+/-1%,1/10W,G,SMD0603 | KOA SPEER ELECTRONICS, INC. | RK73H1JTTD4991F | G | PWA BOM | In Old BOM |
|  |  |  | 61010DG00-011-G | RES,4.99KOhm,+/-1%,1/10W,G,SMD0603 | YAGEO CORPORATION COMPONENT | RC0603FR-074K99L | G | PWA BOM | In Old BOM |
|  |  |  | 61010DG00-044-G | RES,4.99KOhm,+/-1%,1/10W,G,SMD0603 | TA-I TECHNOLOGY CO., LTD | RM06FTN4991 | G | PWA BOM | In Old BOM |
|  |  |  | 61010DG00-012-G | RES,4.99KOhm,+/-1%,1/10W,G,SMD0603 | WALSIN TECHNOLOGY CORPORATION | WR06X4991FTL | G | PWA BOM | In Old BOM |
| 8 | PBER65,PAFR65,PAER65,PBFR66 | 4 | 610606H00-017-G | RES,50mOhm,+/-1%,1.5W,G,SMD2512 | KOA | SLW1TTE50L0F | G | PWA BOM | In New BOM |
|  |  |  | 610606E00-125-G | RES,50mOhm,+/-1%,1W,G,SMD2512 | INTERNATIONAL RESISTIVE COMPANY, INC. | LRMAP2512-R05FT4 | G | PWA BOM | In New BOM |
|  | PBER65,PAFR65,PAER65,PBFR66 | 4 | 610606H00-017-G | RES,50mOhm,+/-1%,1.5W,G,SMD2512 | KOA SPEER ELECTRONICS, INC. | SLW1TTE50L0F | G | PWA BOM | In Old BOM |
|  |  |  | 610606E00-125-G | RES,50mOhm,+/-1%,1W,G,SMD2512 | INTERNATIONAL RESISTIVE COMPANY, INC. | LRMAP2512-R05FT4 | G | PWA BOM | In Old BOM |
| 9 | PBMR65,PAMR65 | 2 | 610606J00-017-G | RES,75mOhm,+/-1%,1.5W,G,SMD2512 | KOA | SLW1TTE75L0F | G | PWA BOM | In New BOM |
|  |  |  | 610606D00-125-G | RES,75mOhm,+/-1%,1W,G,SMD2512 | INTERNATIONAL RESISTIVE COMPANY, INC. | LRMAP2512-R075FT4 | G | PWA BOM | In New BOM |
|  | PBMR65,PAMR65 | 2 | 610606J00-017-G | RES,75mOhm,+/-1%,1.5W,G,SMD2512 | KOA SPEER ELECTRONICS, INC. | SLW1TTE75L0F | G | PWA BOM | In Old BOM |
|  |  |  | 610606D00-125-G | RES,75mOhm,+/-1%,1W,G,SMD2512 | INTERNATIONAL RESISTIVE COMPANY, INC. | LRMAP2512-R075FT4 | G | PWA BOM | In Old BOM |
| 10 | PBAR34,PAAR34 | 2 | KOA_RN731ETTP5900B25 | RES,590Ohm,+/-0.1%,1/16W,G,SMD0402 | KOA SPEER ELECTRONICS, INC. | RN731ETTP5900B25 | G | PWA BOM | In New BOM |
|  |  |  | TNPW0402590RBEED | RES,590Ohm,+/-0.1%,1/16W,G,SMD0402 | VISHAY ENTER TECHNO LOGY.INC | TNPW0402590RBEED | G | PWA BOM | In New BOM |
|  |  |  | ERA2AEB5900X | RES,590Ohm,+/-0.1%,1/16W,G,SMD0402 | PANASONIC INDUSTRIAL CO.,LTD. | ERA2AEB5900X | G | PWA BOM | In New BOM |
|  |  |  | RT0402BRD07590RL | RES,590Ohm,+/-0.1%,1/16W,G,SMD0402 | YAGEO CORPORATION COMPONENT | RT0402BRD07590RL | G | PWA BOM | In New BOM |
|  | PBAR34,PAAR34 | 2 | 611003D00-017-G | RES,1KOhm,+/-0.1%,1/16W,G,SMD0402 | KOA SPEER ELECTRONICS, INC. | RN731ETTP1001B25 | G | PWA BOM | In Old BOM |
|  |  |  | 611003D02-011-G | RES,1KOhm,+/-0.1%,1/16W,G,SMD0402 | YAGEO CORPORATION COMPONENT | RT0402BRD071KL | G | PWA BOM | In Old BOM |
|  |  |  | 611003D00-044-G | RES,1KOhm,+/-0.1%,1/16W,G,SMD0402 | TA-I TECHNOLOGY CO., LTD | RB04BTS1001 | G | PWA BOM | In Old BOM |
|  |  |  | 611003D03-012-G | RES,1KOhm,+/-0.1%,1/16W,G,SMD0402 | WALSIN TECHNOLOGY CORPORATION | WF04U1001BTL | G | PWA BOM | In Old BOM |
| 11 | U1,U10 | 2 | 340109B00-600-G | POWER9 CPU Socket for LGA3899-HYBRID | FOXCONN TECHNOLOGY CO.,LTD. | PE38993-51BC1-1H | G | PWA BOM | In New BOM |
|  | U1,U10 | 2 | 340109B00-600-G | CONN,CPU Socket,0.75mm,30u,G,SMD-3899 | FOXCONN TECHNOLOGY CO.,LTD. | PE38993-51BC1-1H | G | PWA BOM | In Old BOM |
| ##### Change Revision |  |  |  |  |  |  |  |  |  |
| Sheet | REV OF BOM | CUSTOMER | CUSTOMER P/N | PWA PN | PWA DESCRIPTION | PWA REV | DATE | Remark |  |
| PWA BOM | X23 | Customer |  |  |  |  | 12/9/17 | In New BOM |  |
| PWA BOM |  | Customer |  |  |  |  |  | In Old BOM |  |
| OOOOOOOOOOOOOOOOOOOOOOOOOOOOOOOOOOOOOOOOOOOOOOOOOOOOOOOOOOOOOOOOOOOOOOOOOOOOOOOOOOOOOOOOOO | OOOOOOOOOOOOOOOOOOOOOOOOOOOOOOOOOOOOOOOOOOOOOOOOOOOOOOOOOOOOOOOOOOOOOOOOOOOOOOOOOOOOOOOOOO | OOOOOOOOOOOOOOOOOOOOOOOOOOOOOOOOOOOOOOOOOOOOOOOOOOOOOOOOOOOOOOOOOOOOOOOOOOOOOOOOOOOOOOOOOO | OOOOOOOOOOOOOOOOOOOOOOOOOOOOOOOOOOOOOOOOOOOOOOOOOOOOOOOOOOOOOOOOOOOOOOOOOOOOOOOOOOOOOOOOOO | OOOOOOOOOOOOOOOOOOOOOOOOOOOOOOOOOOOOOOOOOOOOOOOOOOOOOOOOOOOOOOOOOOOOOOOOOOOOOOOOOOOOOOOOOO | OOOOOOOOOOOOOOOOOOOOOOOOOOOOOOOOOOOOOOOOOOOOOOOOOOOOOOOOOOOOOOOOOOOOOOOOOOOOOOOOOOOOOOOOOO | OOOOOOOOOOOOOOOOOOOOOOOOOOOOOOOOOOOOOOOOOOOOOOOOOOOOOOOOOOOOOOOOOOOOOOOOOOOOOOOOOOOOOOOOOO | OOOOOOOOOOOOOOOOOOOOOOOOOOOOOOOOOOOOOOOOOOOOOOOOOOOOOOOOOOOOOOOOOOOOOOOOOOOOOOOOOOOOOOOOOO | OOOOOOOOOOOOOOOOOOOOOOOOOOOOOOOOOOOOOOOOOOOOOOOOOOOOOOOOOOOOOOOOOOOOOOOOOOOOOOOOOOOOOOOOOO | OOOOOOOOOOOOOOOOOOOOOOOOOOOOOOOOOOOOOOOOOOOOOOOOOOOOOOOOOOOOOOOOOOOOOOOOOOOOOOOOOOOOOOOOOO |
| Second Source Change |  |  |  |  |  |  |  |  |  |
| Item | Location | Change Type | Foxconn P/N | Part Description | Manufacturer Full Name | Manufacturer P/N | RoHS | Sheet |  |
| 1 | D14 |  | 520305J00-223-G | DIODE,Schottky,MBR130LSFT1G,30V,1A,G,SOD123FL-2,SMD | ON SEMICONDUCTOR CORP | MBR130LSFT1G | G | PWA BOM |  |
|  |  | ADD | 52030GG00-031-G | Diode,Schottky,PMEG3010ER,30V,1A,SOD-123,2P,G | NXP SEMICONDUCTORS | PMEG3010ER | G | PWA BOM |  |
| 2 | J28,J31 |  | 34071BR00-245-G | CONN,SAS,V/T,0.6mm,30u,G,SMD-74 | AMPHENOL SHANGHAI CORP. | U10-K074-260T | G | PWA BOM |  |
|  |  | ADD | U10-K274-260T | CONN,SAS,V/T,0.6mm,30u,G,SMD-74 | AMPHENOL SHANGHAI CORP. | U10-K274-260T | G | PWA BOM |  |
| 3 | J30,J33 |  | 34071BS00-245-G | CONN,SAS,V/T,0.6mm,30u,G,SMD-74 | AMPHENOL SHANGHAI CORP. | U10-K074-26BT | G | PWA BOM |  |
|  |  | ADD | U10-K274-26BT | CONN,SAS,V/T,0.6mm,30u,G,SMD-74 | AMPHENOL SHANGHAI CORP. | U10-K274-26BT | G | PWA BOM |  |
| OOOOOOOOOOOOOOOOOOOOOOOOOOOOOOOOOOOOOOOOOOOOOOOOOOOOOOOOOOOOOOOOOOOOOOOOOOOOOOOOOOOOOOOOOO | OOOOOOOOOOOOOOOOOOOOOOOOOOOOOOOOOOOOOOOOOOOOOOOOOOOOOOOOOOOOOOOOOOOOOOOOOOOOOOOOOOOOOOOOOO | OOOOOOOOOOOOOOOOOOOOOOOOOOOOOOOOOOOOOOOOOOOOOOOOOOOOOOOOOOOOOOOOOOOOOOOOOOOOOOOOOOOOOOOOOO | OOOOOOOOOOOOOOOOOOOOOOOOOOOOOOOOOOOOOOOOOOOOOOOOOOOOOOOOOOOOOOOOOOOOOOOOOOOOOOOOOOOOOOOOOO | OOOOOOOOOOOOOOOOOOOOOOOOOOOOOOOOOOOOOOOOOOOOOOOOOOOOOOOOOOOOOOOOOOOOOOOOOOOOOOOOOOOOOOOOOO | OOOOOOOOOOOOOOOOOOOOOOOOOOOOOOOOOOOOOOOOOOOOOOOOOOOOOOOOOOOOOOOOOOOOOOOOOOOOOOOOOOOOOOOOOO | OOOOOOOOOOOOOOOOOOOOOOOOOOOOOOOOOOOOOOOOOOOOOOOOOOOOOOOOOOOOOOOOOOOOOOOOOOOOOOOOOOOOOOOOOO | OOOOOOOOOOOOOOOOOOOOOOOOOOOOOOOOOOOOOOOOOOOOOOOOOOOOOOOOOOOOOOOOOOOOOOOOOOOOOOOOOOOOOOOOOO | OOOOOOOOOOOOOOOOOOOOOOOOOOOOOOOOOOOOOOOOOOOOOOOOOOOOOOOOOOOOOOOOOOOOOOOOOOOOOOOOOOOOOOOOOO | OOOOOOOOOOOOOOOOOOOOOOOOOOOOOOOOOOOOOOOOOOOOOOOOOOOOOOOOOOOOOOOOOOOOOOOOOOOOOOOOOOOOOOOOOO |
| Master Materials Change |  |  |  |  |  |  |  |  |  |
| Item | Foxconn P/N | Orig._Usage | New_Usage | Part Description | Manufacturer Full Name | Manufacturer P/N | RoHS | Location | Sheet |
| 1 | 610107A00-017-G | 713 | 719 | RES,0 Ohm,+/-5%,1/16W,G,SMD0402 | KOA SPEER ELECTRONICS, INC. | RK73Z1ETTP | G | (+)R2045,R2046,R2047,R2048,R2049,R2050,R2051,R2052 (-)PAAR67,PBAR68 | PWA BOM |
|  | 610107A00-012-G |  |  | RES,0 Ohm,+/-5%,1/16W,G,SMD0402 | WALSIN TECHNOLOGY CORPORATION | WR04X000PTL |  |  | PWA BOM |
|  | 610107A00-011-G |  |  | RES,0 Ohm,+/-5%,1/16W,G,SMD0402 | YAGEO CORPORATION COMPONENT | RC0402JR-070RL |  |  | PWA BOM |
|  | 610107A00-044-G |  |  | RES,0 Ohm,+/-5%,1/16W,G,SMD0402 | TA-I TECHNOLOGY CO., LTD | RM04JTN0 |  |  | PWA BOM |
|  | 610107A00-024-G |  |  | RES,0 Ohm,+/-5%,1/16W,G,SMD0402 | PANASONIC INDUSTRIAL CO.,LTD. | ERJ2GE0R00X |  |  | PWA BOM |
|  | 610107A00-029-G |  |  | RES,0 Ohm,+/-5%,1/16W,G,SMD0402 | VISHAY ENTER TECHNO LOGY.INC | CRCW04020000Z0ED |  |  | PWA BOM |
| 2 | 61010PS00-017-G | 48 | 50 | RES,200KOhm,+/-1%,1/16W,G,SMD0402 | KOA SPEER ELECTRONICS, INC. | RK73H1ETTP2003F | G | (+)PBAR127,PAAR127 | PWA BOM |
|  | 61010PS00-012-G |  |  | RES,200KOhm,+/-1%,1/16W,G,SMD0402 | WALSIN TECHNOLOGY CORPORATION | WR04X2003FTL |  |  | PWA BOM |
|  | 61010PS00-011-G |  |  | RES,200KOhm,+/-1%,1/16W,G,SMD0402 | YAGEO CORPORATION COMPONENT | RC0402FR-07200KL |  |  | PWA BOM |
|  | 61010PS00-044-G |  |  | RES,200KOhm,+/-1%,1/16W,G,SMD0402 | TA-I TECHNOLOGY CO., LTD | RM04FTN2003 |  |  | PWA BOM |
| 3 | 611003D00-017-G | 10 | 8 | RES,1KOhm,+/-0.1%,1/16W,G,SMD0402 | KOA SPEER ELECTRONICS, INC. | RN731ETTP1001B25 | G | (-)PBAR34,PAAR34 | PWA BOM |
|  | 611003D02-011-G |  |  | RES,1KOhm,+/-0.1%,1/16W,G,SMD0402 | YAGEO CORPORATION COMPONENT | RT0402BRD071KL |  |  | PWA BOM |
|  | 611003D00-044-G |  |  | RES,1KOhm,+/-0.1%,1/16W,G,SMD0402 | TA-I TECHNOLOGY CO., LTD | RB04BTS1001 |  |  | PWA BOM |
|  | 611003D03-012-G |  |  | RES,1KOhm,+/-0.1%,1/16W,G,SMD0402 | WALSIN TECHNOLOGY CORPORATION | WF04U1001BTL |  |  | PWA BOM |
| 4 | 61010R900-017-G | 4 | 8 | RES,27.4KOhm,+/-1%,1/10W,G,SMD0603 | KOA SPEER ELECTRONICS, INC. | RK73H1JTTD2742F | G | (+)PAAR66,PBAR67,PBAR79,PAAR79 | PWA BOM |
|  | 61010R900-012-G |  |  | RES,27.4KOhm,+/-1%,1/10W,G,SMD0603 | WALSIN TECHNOLOGY CORPORATION | WR06X2742FTL |  |  | PWA BOM |
|  | 61010R900-011-G |  |  | RES,27.4KOhm,+/-1%,1/10W,G,SMD0603 | YAGEO CORPORATION COMPONENT | RC0603FR-0727K4L |  |  | PWA BOM |
| 5 | 61010G500-017-G | 101 | 103 | RES,10KOhm,+/-1%,1/16W,G,SMD0402 | KOA SPEER ELECTRONICS, INC. | RK73H1ETTP1002F | G | (+)PAAR67,PBAR68 | PWA BOM |
|  | 61010G500-012-G |  |  | RES,10KOhm,+/-1%,1/16W,G,SMD0402 | WALSIN TECHNOLOGY CORPORATION | WR04X1002FTL |  |  | PWA BOM |
|  | 61010G500-011-G |  |  | RES,10KOhm,+/-1%,1/16W,G,SMD0402 | YAGEO CORPORATION COMPONENT | RC0402FR-0710KL |  |  | PWA BOM |
|  | 61010G500-044-G |  |  | RES,10KOhm,+/-1%,1/16W,G,SMD0402 | TA-I TECHNOLOGY CO., LTD | RM04FTN1002 |  |  | PWA BOM |
|  | 61010G500-029-G |  |  | RES,10KOhm,+/-1%,1/16W,G,SMD0402 | VISHAY ENTER TECHNO LOGY.INC | CRCW040210K0FKED |  |  | PWA BOM |
|  | 61010G500-024-G |  |  | RES,10KOhm,+/-1%,1/16W,G,SMD0402 | PANASONIC INDUSTRIAL CO.,LTD. | ERJ2RKF1002X |  |  | PWA BOM |
| 6 | 610100C00-017-G | 0 | 4 | RES,15kOhm,+/-1%,1/10W,G,SMD0603 | KOA SPEER ELECTRONICS, INC. | RK73H1JTTD1502F | G | (+)PAAR70,PBAR71,PBAR80,PAAR80 | PWA BOM |
|  | 610100C00-011-G |  |  | RES,15KOhm,+/-1%,1/10W,G,SMD0603 | YAGEO CORPORATION COMPONENT | RC0603FR-0715KL |  |  | PWA BOM |
|  | 610100C00-012-G |  |  | RES,15KOhm,+/-1%,1/10W,G,SMD0603 | WALSIN TECHNOLOGY CORPORATION | WR06X1502FTL |  |  | PWA BOM |
|  | 610100C00-044-G |  |  | RES,15KOhm,+/-1%,1/10W,G,SMD0603 | TA-I TECHNOLOGY CO., LTD | RM06FTN1502 |  |  | PWA BOM |
| 7 | KOA_RN731ETTP5900B25 | 0 | 2 | RES,590Ohm,+/-0.1%,1/16W,G,SMD0402 | KOA SPEER ELECTRONICS, INC. | RN731ETTP5900B25 | G | (+)PBAR34,PAAR34 | PWA BOM |
|  | TNPW0402590RBEED |  |  | RES,590Ohm,+/-0.1%,1/16W,G,SMD0402 | VISHAY ENTER TECHNO LOGY.INC | TNPW0402590RBEED |  |  | PWA BOM |
|  | ERA2AEB5900X |  |  | RES,590Ohm,+/-0.1%,1/16W,G,SMD0402 | PANASONIC INDUSTRIAL CO.,LTD. | ERA2AEB5900X |  |  | PWA BOM |
|  | RT0402BRD07590RL |  |  | RES,590Ohm,+/-0.1%,1/16W,G,SMD0402 | YAGEO CORPORATION COMPONENT | RT0402BRD07590RL |  |  | PWA BOM |
| 8 | 610103D00-017-G | 4 | 0 | RES,24.3KOhm,+/-1%,1/10W,G,SMD0603 | KOA SPEER ELECTRONICS, INC. | RK73H1JTTD2432F | G | (-)PAAR66,PBAR67,PBAR79,PAAR79 | PWA BOM |
|  | 610103D00-011-G |  |  | RES,24.3KOhm,+/-1%,1/10W,G,SMD0603 | YAGEO CORPORATION COMPONENT | RC0603FR-0724K3L |  |  | PWA BOM |
|  | 610103D00-012-G |  |  | RES,24.3KOhm,+/-1%,1/10W,G,SMD0603 | WALSIN TECHNOLOGY CORPORATION | WR06X2432FTL |  |  | PWA BOM |
| 9 | 61010DG00-017-G | 2 | 0 | RES,4.99KOhm,+/-1%,1/10W,G,SMD0603 | KOA SPEER ELECTRONICS, INC. | RK73H1JTTD4991F | G | (-)PBAR80,PAAR80 | PWA BOM |
|  | 61010DG00-011-G |  |  | RES,4.99KOhm,+/-1%,1/10W,G,SMD0603 | YAGEO CORPORATION COMPONENT | RC0603FR-074K99L |  |  | PWA BOM |
|  | 61010DG00-044-G |  |  | RES,4.99KOhm,+/-1%,1/10W,G,SMD0603 | TA-I TECHNOLOGY CO., LTD | RM06FTN4991 |  |  | PWA BOM |
|  | 61010DG00-012-G |  |  | RES,4.99KOhm,+/-1%,1/10W,G,SMD0603 | WALSIN TECHNOLOGY CORPORATION | WR06X4991FTL |  |  | PWA BOM |
| 10 | 61011G600-017-G | 2 | 0 | RES,133KOhm,+/-1%,1/16W,G,SMD0402 | KOA SPEER ELECTRONICS, INC. | RK73G1ETTP1333F | G | (-)PBAR127,PAAR127 | PWA BOM |
|  | 61011G600-011-G |  |  | RES,133KOhm,+/-1%,1/16W,G,SMD0402 | YAGEO CORPORATION COMPONENT | RC0402FR-07133KL |  |  | PWA BOM |
|  | 61011G600-012-G |  |  | RES,133KOhm,+/-1%,1/16W,G,SMD0402 | WALSIN TECHNOLOGY CORPORATION | WR04X1333FTL |  |  | PWA BOM |
|  | 61011G600-044-G |  |  | RES,133KOhm,+/-1%,1/16W,G,SMD0402 | TA-I TECHNOLOGY CO., LTD | RM04FTN1333 |  |  | PWA BOM |
| OOOOOOOOOOOOOOOOOOOOOOOOOOOOOOOOOOOOOOOOOOOOOOOOOOOOOOOOOOOOOOOOOOOOOOOOOOOOOOOOOOOOOOOOOO | OOOOOOOOOOOOOOOOOOOOOOOOOOOOOOOOOOOOOOOOOOOOOOOOOOOOOOOOOOOOOOOOOOOOOOOOOOOOOOOOOOOOOOOOOO | OOOOOOOOOOOOOOOOOOOOOOOOOOOOOOOOOOOOOOOOOOOOOOOOOOOOOOOOOOOOOOOOOOOOOOOOOOOOOOOOOOOOOOOOOO | OOOOOOOOOOOOOOOOOOOOOOOOOOOOOOOOOOOOOOOOOOOOOOOOOOOOOOOOOOOOOOOOOOOOOOOOOOOOOOOOOOOOOOOOOO | OOOOOOOOOOOOOOOOOOOOOOOOOOOOOOOOOOOOOOOOOOOOOOOOOOOOOOOOOOOOOOOOOOOOOOOOOOOOOOOOOOOOOOOOOO | OOOOOOOOOOOOOOOOOOOOOOOOOOOOOOOOOOOOOOOOOOOOOOOOOOOOOOOOOOOOOOOOOOOOOOOOOOOOOOOOOOOOOOOOOO | OOOOOOOOOOOOOOOOOOOOOOOOOOOOOOOOOOOOOOOOOOOOOOOOOOOOOOOOOOOOOOOOOOOOOOOOOOOOOOOOOOOOOOOOOO | OOOOOOOOOOOOOOOOOOOOOOOOOOOOOOOOOOOOOOOOOOOOOOOOOOOOOOOOOOOOOOOOOOOOOOOOOOOOOOOOOOOOOOOOOO | OOOOOOOOOOOOOOOOOOOOOOOOOOOOOOOOOOOOOOOOOOOOOOOOOOOOOOOOOOOOOOOOOOOOOOOOOOOOOOOOOOOOOOOOOO |  |
| TLA Parts Change |  |  |  |  |  |  |  |  |  |
| Item | Foxconn P/N | Qty | Part Description | Manufacturer Full Name | Manufacturer P/N | RoHS | Location | Remark |  |
| BOM Change List Date:Mon Dec 18 16:37:08 GMT+08:00 2017 |  |  |  |  |  |  |  |  |  |
| New BOM file : C:\<user>\BARRELEYE-G2-MB-PVT-HW-EBOM-20171218.xls |  |  |  |  |  |  |  |  |  |
| Old BOM file : C:\<user>\BARRELEYE-G2-MB-PVT-HW-EBOM-20171208-1.xls |  |  |  |  |  |  |  |  |  |
| ##### Add Parts |  |  |  |  |  |  |  |  |  |
| Item | Location | Qty | Foxconn P/N | Part Description | Manufacturer Full Name | Manufacturer P/N | RoHS | Sheet |  |
| ##### Remove Parts |  |  |  |  |  |  |  |  |  |
| Item | Location | Qty | Foxconn P/N | Part Description | Manufacturer Full Name | Manufacturer P/N | RoHS | Sheet |  |
| ##### Change Parts |  |  |  |  |  |  |  |  |  |
| Item | Location | Qty | Foxconn P/N | Part Description | Manufacturer Full Name | Manufacturer P/N | RoHS | Sheet | Remark |
| 1 | R925,R927,R929 | 3 | 610115J00-017-G | RES,33 Ohm,+/-1%,1/16W,G,SMD0402 | KOA SPEER ELECTRONICS, INC. | RK73H1ETTP33R0F | N | PWA BOM | In New BOM |
|  | R925,R927,R929 | 3 | 610102600-017-G | RES,56 Ohm,+/-1%,1/16W,G,SMD0402 | KOA SPEER ELECTRONICS, INC. | RK73H1ETTP56R0F | N | PWA BOM | In Old BOM |
| ##### Change Revision |  |  |  |  |  |  |  |  |  |
| Sheet | REV OF BOM | CUSTOMER | CUSTOMER P/N | PWA PN | PWA DESCRIPTION | PWA REV | DATE | Remark |  |
| OOOOOOOOOOOOOOOOOOOOOOOOOOOOOOOOOOOOOOOOOOOOOOOOOOOOOOOOOOOOOOOOOOOOOOOOOOOOOOOOOOOOOOOOOO | OOOOOOOOOOOOOOOOOOOOOOOOOOOOOOOOOOOOOOOOOOOOOOOOOOOOOOOOOOOOOOOOOOOOOOOOOOOOOOOOOOOOOOOOOO | OOOOOOOOOOOOOOOOOOOOOOOOOOOOOOOOOOOOOOOOOOOOOOOOOOOOOOOOOOOOOOOOOOOOOOOOOOOOOOOOOOOOOOOOOO | OOOOOOOOOOOOOOOOOOOOOOOOOOOOOOOOOOOOOOOOOOOOOOOOOOOOOOOOOOOOOOOOOOOOOOOOOOOOOOOOOOOOOOOOOO | OOOOOOOOOOOOOOOOOOOOOOOOOOOOOOOOOOOOOOOOOOOOOOOOOOOOOOOOOOOOOOOOOOOOOOOOOOOOOOOOOOOOOOOOOO | OOOOOOOOOOOOOOOOOOOOOOOOOOOOOOOOOOOOOOOOOOOOOOOOOOOOOOOOOOOOOOOOOOOOOOOOOOOOOOOOOOOOOOOOOO | OOOOOOOOOOOOOOOOOOOOOOOOOOOOOOOOOOOOOOOOOOOOOOOOOOOOOOOOOOOOOOOOOOOOOOOOOOOOOOOOOOOOOOOOOO | OOOOOOOOOOOOOOOOOOOOOOOOOOOOOOOOOOOOOOOOOOOOOOOOOOOOOOOOOOOOOOOOOOOOOOOOOOOOOOOOOOOOOOOOOO | OOOOOOOOOOOOOOOOOOOOOOOOOOOOOOOOOOOOOOOOOOOOOOOOOOOOOOOOOOOOOOOOOOOOOOOOOOOOOOOOOOOOOOOOOO | OOOOOOOOOOOOOOOOOOOOOOOOOOOOOOOOOOOOOOOOOOOOOOOOOOOOOOOOOOOOOOOOOOOOOOOOOOOOOOOOOOOOOOOOOO |
| Second Source Change |  |  |  |  |  |  |  |  |  |
| Item | Location | Change Type | Foxconn P/N | Part Description | Manufacturer Full Name | Manufacturer P/N | RoHS | Sheet |  |
| OOOOOOOOOOOOOOOOOOOOOOOOOOOOOOOOOOOOOOOOOOOOOOOOOOOOOOOOOOOOOOOOOOOOOOOOOOOOOOOOOOOOOOOOOO | OOOOOOOOOOOOOOOOOOOOOOOOOOOOOOOOOOOOOOOOOOOOOOOOOOOOOOOOOOOOOOOOOOOOOOOOOOOOOOOOOOOOOOOOOO | OOOOOOOOOOOOOOOOOOOOOOOOOOOOOOOOOOOOOOOOOOOOOOOOOOOOOOOOOOOOOOOOOOOOOOOOOOOOOOOOOOOOOOOOOO | OOOOOOOOOOOOOOOOOOOOOOOOOOOOOOOOOOOOOOOOOOOOOOOOOOOOOOOOOOOOOOOOOOOOOOOOOOOOOOOOOOOOOOOOOO | OOOOOOOOOOOOOOOOOOOOOOOOOOOOOOOOOOOOOOOOOOOOOOOOOOOOOOOOOOOOOOOOOOOOOOOOOOOOOOOOOOOOOOOOOO | OOOOOOOOOOOOOOOOOOOOOOOOOOOOOOOOOOOOOOOOOOOOOOOOOOOOOOOOOOOOOOOOOOOOOOOOOOOOOOOOOOOOOOOOOO | OOOOOOOOOOOOOOOOOOOOOOOOOOOOOOOOOOOOOOOOOOOOOOOOOOOOOOOOOOOOOOOOOOOOOOOOOOOOOOOOOOOOOOOOOO | OOOOOOOOOOOOOOOOOOOOOOOOOOOOOOOOOOOOOOOOOOOOOOOOOOOOOOOOOOOOOOOOOOOOOOOOOOOOOOOOOOOOOOOOOO | OOOOOOOOOOOOOOOOOOOOOOOOOOOOOOOOOOOOOOOOOOOOOOOOOOOOOOOOOOOOOOOOOOOOOOOOOOOOOOOOOOOOOOOOOO | OOOOOOOOOOOOOOOOOOOOOOOOOOOOOOOOOOOOOOOOOOOOOOOOOOOOOOOOOOOOOOOOOOOOOOOOOOOOOOOOOOOOOOOOOO |
| Master Materials Change |  |  |  |  |  |  |  |  |  |
| Item | Foxconn P/N | Orig._Usage | New_Usage | Part Description | Manufacturer Full Name | Manufacturer P/N | RoHS | Location | Sheet |
| 1 | 610115J00-017-G | 8 | 11 | RES,33 Ohm,+/-1%,1/16W,G,SMD0402 | KOA SPEER ELECTRONICS, INC. | RK73H1ETTP33R0F | N | (+)R925,R927,R929 | PWA BOM |
| 2 | 610102600-017-G | 3 | 0 | RES,56 Ohm,+/-1%,1/16W,G,SMD0402 | KOA SPEER ELECTRONICS, INC. | RK73H1ETTP56R0F | N | (-)R925,R927,R929 | PWA BOM |
| OOOOOOOOOOOOOOOOOOOOOOOOOOOOOOOOOOOOOOOOOOOOOOOOOOOOOOOOOOOOOOOOOOOOOOOOOOOOOOOOOOOOOOOOOO | OOOOOOOOOOOOOOOOOOOOOOOOOOOOOOOOOOOOOOOOOOOOOOOOOOOOOOOOOOOOOOOOOOOOOOOOOOOOOOOOOOOOOOOOOO | OOOOOOOOOOOOOOOOOOOOOOOOOOOOOOOOOOOOOOOOOOOOOOOOOOOOOOOOOOOOOOOOOOOOOOOOOOOOOOOOOOOOOOOOOO | OOOOOOOOOOOOOOOOOOOOOOOOOOOOOOOOOOOOOOOOOOOOOOOOOOOOOOOOOOOOOOOOOOOOOOOOOOOOOOOOOOOOOOOOOO | OOOOOOOOOOOOOOOOOOOOOOOOOOOOOOOOOOOOOOOOOOOOOOOOOOOOOOOOOOOOOOOOOOOOOOOOOOOOOOOOOOOOOOOOOO | OOOOOOOOOOOOOOOOOOOOOOOOOOOOOOOOOOOOOOOOOOOOOOOOOOOOOOOOOOOOOOOOOOOOOOOOOOOOOOOOOOOOOOOOOO | OOOOOOOOOOOOOOOOOOOOOOOOOOOOOOOOOOOOOOOOOOOOOOOOOOOOOOOOOOOOOOOOOOOOOOOOOOOOOOOOOOOOOOOOOO | OOOOOOOOOOOOOOOOOOOOOOOOOOOOOOOOOOOOOOOOOOOOOOOOOOOOOOOOOOOOOOOOOOOOOOOOOOOOOOOOOOOOOOOOOO | OOOOOOOOOOOOOOOOOOOOOOOOOOOOOOOOOOOOOOOOOOOOOOOOOOOOOOOOOOOOOOOOOOOOOOOOOOOOOOOOOOOOOOOOOO |  |
| TLA Parts Change |  |  |  |  |  |  |  |  |  |
| Item | Foxconn P/N | Qty | Part Description | Manufacturer Full Name | Manufacturer P/N | RoHS | Location | Remark |  |
| BOM Change List Date:Tue Dec 19 14:31:38 GMT+08:00 2017 |  |  |  |  |  |  |  |  |  |
| New BOM file : E:\barreleye g2\1219\BARRELEYE_G2-MB-PVT-X04-HW-BOM-X24_20171219.xls |  |  |  |  |  |  |  |  |  |
| Old BOM file : E:\barreleye g2\1219\BG2 1209.xls |  |  |  |  |  |  |  |  |  |
| ##### Add Parts |  |  |  |  |  |  |  |  |  |
| Item | Location | Qty | Foxconn P/N | Part Description | Manufacturer Full Name | Manufacturer P/N | RoHS | Sheet |  |
| ##### Remove Parts |  |  |  |  |  |  |  |  |  |
| Item | Location | Qty | Foxconn P/N | Part Description | Manufacturer Full Name | Manufacturer P/N | RoHS | Sheet |  |
| ##### Change Parts |  |  |  |  |  |  |  |  |  |
| Item | Location | Qty | Foxconn P/N | Part Description | Manufacturer Full Name | Manufacturer P/N | RoHS | Sheet | Remark |
| 1 | PCB | 1 | 0101FBQ00-000-G | PCB | GCE | 0101FBQ00-000-G | G | PWA BOM | In New BOM |
|  |  |  | 0101FBQ00-000-G | PCB,Zaius-MB PVT-X04,OSP,Gre,22L,22.20*13.00,G | ZHUHAI FOUNDER PRINTED CIRCUIT BOARD_x0008_HK	 DEVELOPMENT LIMITED | 0101FBQ00-000-G | G | PWA BOM | In New BOM |
|  | PCB | 1 | 0101FBQ00-000-G | PCB,Zaius-MB PVT-X04,OSP,Gre,22L,22.20*13.00,G | GOLD CIRCUIT ELECTRONICS LTD. | 0101FBQ00-000-G | G | PWA BOM | In Old BOM |
|  |  |  | 0101FBQ00-000-G | PCB,Zaius-MB PVT-X04,OSP,Gre,22L,22.20*13.00,G | ZHUHAI FOUNDER PRINTED CIRCUIT BOARD_x0008_HK	 DEVELOPMENT LIMITED | 0101FBQ00-000-G | G | PWA BOM | In Old BOM |
| 2 | C1424,C1427,C1451,C1455,C1459,C1464,C1466,C1468,C1470,C1499,C1533,C1577,C1585,C1596 | 14 | 620109S00-015-G | CAP,4.7uF,+/-10%,X7R,10V,G,SMD0805 | MURATA ELEC. NORTH AMERICA | GRM21BR71A475K | G | PWA BOM | In New BOM |
|  | C1424,C1427,C1451,C1455,C1459,C1464,C1466,C1468,C1470,C1499,C1533,C1577,C1585,C1596 | 14 | 620109S00-023-G | CAP,4.7uF,+/-10%,X7R,10V,G,SMD0805 | TAIYO ELECTRIC IND.CO.LTD | LMK212B7475KG-T | G | PWA BOM | In Old BOM |
|  |  |  | 620109S00-026-G | CAP,4.7uF,+/-10%,X7R,10V,G,SMD0805 | SAMSUNG SEMICONDUCTOR | CL21B475KPFNNNE | G | PWA BOM | In Old BOM |
|  |  |  | 620109S00-015-G | CAP,4.7uF,+/-10%,X7R,10V,G,SMD0805 | MURATA ELEC. NORTH AMERICA | GRM21BR71A475K | G | PWA BOM | In Old BOM |
| 3 | R925,R927,R929 | 3 | 610115J00-017-G | RES,33 Ohm,+/-1%,1/16W,G,SMD0402 | KOA SPEER ELECTRONICS, INC. | RK73H1ETTP33R0F | G | PWA BOM | In New BOM |
|  |  |  | 610115J00-012-G | RES,33 Ohm,+/-1%,1/16W,G,SMD0402 | WALSIN TECHNOLOGY CORPORATION | WR04X33R0FTL | G | PWA BOM | In New BOM |
|  |  |  | 610115J00-011-G | RES,33 Ohm,+/-1%,1/16W,G,SMD0402 | YAGEO CORPORATION COMPONENT | RC0402FR-0733RL | G | PWA BOM | In New BOM |
|  |  |  | 610115J00-044-G | RES,33 Ohm,+/-1%,1/16W,G,SMD0402 | TA-I TECHNOLOGY CO., LTD | RM04FTN33R0 | G | PWA BOM | In New BOM |
|  |  |  | 610115J00-024-G | RES,33 Ohm,+/-1%,1/16W,G,SMD0402 | PANASONIC INDUSTRIAL CO.,LTD. | ERJ2RKF33R0X | G | PWA BOM | In New BOM |
|  | R925,R927,R929 | 3 | 610102600-017-G | RES,56 Ohm,+/-1%,1/16W,G,SMD0402 | KOA SPEER ELECTRONICS, INC. | RK73H1ETTP56R0F | G | PWA BOM | In Old BOM |
|  |  |  | 610102600-012-G | RES,56 Ohm,+/-1%,1/16W,G,SMD0402 | WALSIN TECHNOLOGY CORPORATION | WR04X56R0FTL | G | PWA BOM | In Old BOM |
|  |  |  | 610102600-011-G | RES,56 Ohm,+/-1%,1/16W,G,SMD0402 | YAGEO CORPORATION COMPONENT | RC0402FR-0756RL | G | PWA BOM | In Old BOM |
|  |  |  | 610102600-044-G | RES,56 Ohm,+/-1%,1/16W,G,SMD0402 | TA-I TECHNOLOGY CO., LTD | RM04FTN56R0 | G | PWA BOM | In Old BOM |
|  |  |  | 610102600-024-G | RES,56 Ohm,+/-1%,1/16W,G,SMD0402 | PANASONIC INDUSTRIAL CO.,LTD. | ERJ2RKF56R0X | G | PWA BOM | In Old BOM |
| 4 | U60 | 1 | 21050P200-031-G | IC,NXP,PCF8523TK,G,HVSON-8,SMD | NXP SEMICONDUCTORS | PCF8523TK | G | PWA BOM | In New BOM |
|  | U60 | 1 | PCF8523TK/1 | IC,NXP,PCF8523TK/1,G,HVSON-8,SMD | NXP SEMICONDUCTORS | PCF8523TK/1 | G | PWA BOM | In Old BOM |
| ##### Change Revision |  |  |  |  |  |  |  |  |  |
| Sheet | REV OF BOM | CUSTOMER | CUSTOMER P/N | PWA PN | PWA DESCRIPTION | PWA REV | DATE | Remark |  |
| OOOOOOOOOOOOOOOOOOOOOOOOOOOOOOOOOOOOOOOOOOOOOOOOOOOOOOOOOOOOOOOOOOOOOOOOOOOOOOOOOOOOOOOOOO | OOOOOOOOOOOOOOOOOOOOOOOOOOOOOOOOOOOOOOOOOOOOOOOOOOOOOOOOOOOOOOOOOOOOOOOOOOOOOOOOOOOOOOOOOO | OOOOOOOOOOOOOOOOOOOOOOOOOOOOOOOOOOOOOOOOOOOOOOOOOOOOOOOOOOOOOOOOOOOOOOOOOOOOOOOOOOOOOOOOOO | OOOOOOOOOOOOOOOOOOOOOOOOOOOOOOOOOOOOOOOOOOOOOOOOOOOOOOOOOOOOOOOOOOOOOOOOOOOOOOOOOOOOOOOOOO | OOOOOOOOOOOOOOOOOOOOOOOOOOOOOOOOOOOOOOOOOOOOOOOOOOOOOOOOOOOOOOOOOOOOOOOOOOOOOOOOOOOOOOOOOO | OOOOOOOOOOOOOOOOOOOOOOOOOOOOOOOOOOOOOOOOOOOOOOOOOOOOOOOOOOOOOOOOOOOOOOOOOOOOOOOOOOOOOOOOOO | OOOOOOOOOOOOOOOOOOOOOOOOOOOOOOOOOOOOOOOOOOOOOOOOOOOOOOOOOOOOOOOOOOOOOOOOOOOOOOOOOOOOOOOOOO | OOOOOOOOOOOOOOOOOOOOOOOOOOOOOOOOOOOOOOOOOOOOOOOOOOOOOOOOOOOOOOOOOOOOOOOOOOOOOOOOOOOOOOOOOO | OOOOOOOOOOOOOOOOOOOOOOOOOOOOOOOOOOOOOOOOOOOOOOOOOOOOOOOOOOOOOOOOOOOOOOOOOOOOOOOOOOOOOOOOOO | OOOOOOOOOOOOOOOOOOOOOOOOOOOOOOOOOOOOOOOOOOOOOOOOOOOOOOOOOOOOOOOOOOOOOOOOOOOOOOOOOOOOOOOOOO |
| Second Source Change |  |  |  |  |  |  |  |  |  |
| Item | Location | Change Type | Foxconn P/N | Part Description | Manufacturer Full Name | Manufacturer P/N | RoHS | Sheet |  |
| OOOOOOOOOOOOOOOOOOOOOOOOOOOOOOOOOOOOOOOOOOOOOOOOOOOOOOOOOOOOOOOOOOOOOOOOOOOOOOOOOOOOOOOOOO | OOOOOOOOOOOOOOOOOOOOOOOOOOOOOOOOOOOOOOOOOOOOOOOOOOOOOOOOOOOOOOOOOOOOOOOOOOOOOOOOOOOOOOOOOO | OOOOOOOOOOOOOOOOOOOOOOOOOOOOOOOOOOOOOOOOOOOOOOOOOOOOOOOOOOOOOOOOOOOOOOOOOOOOOOOOOOOOOOOOOO | OOOOOOOOOOOOOOOOOOOOOOOOOOOOOOOOOOOOOOOOOOOOOOOOOOOOOOOOOOOOOOOOOOOOOOOOOOOOOOOOOOOOOOOOOO | OOOOOOOOOOOOOOOOOOOOOOOOOOOOOOOOOOOOOOOOOOOOOOOOOOOOOOOOOOOOOOOOOOOOOOOOOOOOOOOOOOOOOOOOOO | OOOOOOOOOOOOOOOOOOOOOOOOOOOOOOOOOOOOOOOOOOOOOOOOOOOOOOOOOOOOOOOOOOOOOOOOOOOOOOOOOOOOOOOOOO | OOOOOOOOOOOOOOOOOOOOOOOOOOOOOOOOOOOOOOOOOOOOOOOOOOOOOOOOOOOOOOOOOOOOOOOOOOOOOOOOOOOOOOOOOO | OOOOOOOOOOOOOOOOOOOOOOOOOOOOOOOOOOOOOOOOOOOOOOOOOOOOOOOOOOOOOOOOOOOOOOOOOOOOOOOOOOOOOOOOOO | OOOOOOOOOOOOOOOOOOOOOOOOOOOOOOOOOOOOOOOOOOOOOOOOOOOOOOOOOOOOOOOOOOOOOOOOOOOOOOOOOOOOOOOOOO | OOOOOOOOOOOOOOOOOOOOOOOOOOOOOOOOOOOOOOOOOOOOOOOOOOOOOOOOOOOOOOOOOOOOOOOOOOOOOOOOOOOOOOOOOO |
| Master Materials Change |  |  |  |  |  |  |  |  |  |
| Item | Foxconn P/N | Orig._Usage | New_Usage | Part Description | Manufacturer Full Name | Manufacturer P/N | RoHS | Location | Sheet |
| 1 | 620109S00-015-G | 0 | 14 | CAP,4.7uF,+/-10%,X7R,10V,G,SMD0805 | MURATA ELEC. NORTH AMERICA | GRM21BR71A475K | G | (+)C1424,C1427,C1451,C1455,C1459,C1464,C1466,C1468,C1470,C1499,C1533,C1577,C1585,C1596 | PWA BOM |
| 2 | 610115J00-017-G | 8 | 11 | RES,33 Ohm,+/-1%,1/16W,G,SMD0402 | KOA SPEER ELECTRONICS, INC. | RK73H1ETTP33R0F | G | (+)R925,R927,R929 | PWA BOM |
|  | 610115J00-012-G |  |  | RES,33 Ohm,+/-1%,1/16W,G,SMD0402 | WALSIN TECHNOLOGY CORPORATION | WR04X33R0FTL |  |  | PWA BOM |
|  | 610115J00-011-G |  |  | RES,33 Ohm,+/-1%,1/16W,G,SMD0402 | YAGEO CORPORATION COMPONENT | RC0402FR-0733RL |  |  | PWA BOM |
|  | 610115J00-044-G |  |  | RES,33 Ohm,+/-1%,1/16W,G,SMD0402 | TA-I TECHNOLOGY CO., LTD | RM04FTN33R0 |  |  | PWA BOM |
|  | 610115J00-024-G |  |  | RES,33 Ohm,+/-1%,1/16W,G,SMD0402 | PANASONIC INDUSTRIAL CO.,LTD. | ERJ2RKF33R0X |  |  | PWA BOM |
| 3 | 21050P200-031-G | 0 | 1 | IC,NXP,PCF8523TK,G,HVSON-8,SMD | NXP SEMICONDUCTORS | PCF8523TK | G | (+)U60 | PWA BOM |
| 4 | 620109S00-023-G | 14 | 0 | CAP,4.7uF,+/-10%,X7R,10V,G,SMD0805 | TAIYO ELECTRIC IND.CO.LTD | LMK212B7475KG-T | G | (-)C1424,C1427,C1451,C1455,C1459,C1464,C1466,C1468,C1470,C1499,C1533,C1577,C1585,C1596 | PWA BOM |
|  | 620109S00-026-G |  |  | CAP,4.7uF,+/-10%,X7R,10V,G,SMD0805 | SAMSUNG SEMICONDUCTOR | CL21B475KPFNNNE |  |  | PWA BOM |
|  | 620109S00-015-G |  |  | CAP,4.7uF,+/-10%,X7R,10V,G,SMD0805 | MURATA ELEC. NORTH AMERICA | GRM21BR71A475K |  |  | PWA BOM |
| 5 | 610102600-017-G | 3 | 0 | RES,56 Ohm,+/-1%,1/16W,G,SMD0402 | KOA SPEER ELECTRONICS, INC. | RK73H1ETTP56R0F | G | (-)R925,R927,R929 | PWA BOM |
|  | 610102600-012-G |  |  | RES,56 Ohm,+/-1%,1/16W,G,SMD0402 | WALSIN TECHNOLOGY CORPORATION | WR04X56R0FTL |  |  | PWA BOM |
|  | 610102600-011-G |  |  | RES,56 Ohm,+/-1%,1/16W,G,SMD0402 | YAGEO CORPORATION COMPONENT | RC0402FR-0756RL |  |  | PWA BOM |
|  | 610102600-044-G |  |  | RES,56 Ohm,+/-1%,1/16W,G,SMD0402 | TA-I TECHNOLOGY CO., LTD | RM04FTN56R0 |  |  | PWA BOM |
|  | 610102600-024-G |  |  | RES,56 Ohm,+/-1%,1/16W,G,SMD0402 | PANASONIC INDUSTRIAL CO.,LTD. | ERJ2RKF56R0X |  |  | PWA BOM |
| 6 | PCF8523TK/1 | 1 | 0 | IC,NXP,PCF8523TK/1,G,HVSON-8,SMD | NXP SEMICONDUCTORS | PCF8523TK/1 | G | (-)U60 | PWA BOM |
| OOOOOOOOOOOOOOOOOOOOOOOOOOOOOOOOOOOOOOOOOOOOOOOOOOOOOOOOOOOOOOOOOOOOOOOOOOOOOOOOOOOOOOOOOO | OOOOOOOOOOOOOOOOOOOOOOOOOOOOOOOOOOOOOOOOOOOOOOOOOOOOOOOOOOOOOOOOOOOOOOOOOOOOOOOOOOOOOOOOOO | OOOOOOOOOOOOOOOOOOOOOOOOOOOOOOOOOOOOOOOOOOOOOOOOOOOOOOOOOOOOOOOOOOOOOOOOOOOOOOOOOOOOOOOOOO | OOOOOOOOOOOOOOOOOOOOOOOOOOOOOOOOOOOOOOOOOOOOOOOOOOOOOOOOOOOOOOOOOOOOOOOOOOOOOOOOOOOOOOOOOO | OOOOOOOOOOOOOOOOOOOOOOOOOOOOOOOOOOOOOOOOOOOOOOOOOOOOOOOOOOOOOOOOOOOOOOOOOOOOOOOOOOOOOOOOOO | OOOOOOOOOOOOOOOOOOOOOOOOOOOOOOOOOOOOOOOOOOOOOOOOOOOOOOOOOOOOOOOOOOOOOOOOOOOOOOOOOOOOOOOOOO | OOOOOOOOOOOOOOOOOOOOOOOOOOOOOOOOOOOOOOOOOOOOOOOOOOOOOOOOOOOOOOOOOOOOOOOOOOOOOOOOOOOOOOOOOO | OOOOOOOOOOOOOOOOOOOOOOOOOOOOOOOOOOOOOOOOOOOOOOOOOOOOOOOOOOOOOOOOOOOOOOOOOOOOOOOOOOOOOOOOOO | OOOOOOOOOOOOOOOOOOOOOOOOOOOOOOOOOOOOOOOOOOOOOOOOOOOOOOOOOOOOOOOOOOOOOOOOOOOOOOOOOOOOOOOOOO |  |
| TLA Parts Change |  |  |  |  |  |  |  |  |  |
| Item | Foxconn P/N | Qty | Part Description | Manufacturer Full Name | Manufacturer P/N | RoHS | Location | Remark |  |
| BOM Change List Date:Fri Dec 22 16:42:09 GMT+08:00 2017 |  |  |  |  |  |  |  |  |  |
| New BOM file : E:\barreleye g2\1221\BG2 1222.xls |  |  |  |  |  |  |  |  |  |
| Old BOM file : E:\barreleye g2\1221\BG2 1219.xls |  |  |  |  |  |  |  |  |  |
| ##### Add Parts |  |  |  |  |  |  |  |  |  |
| Item | Location | Qty | Foxconn P/N | Part Description | Manufacturer Full Name | Manufacturer P/N | RoHS | Sheet |  |
| ##### Remove Parts |  |  |  |  |  |  |  |  |  |
| Item | Location | Qty | Foxconn P/N | Part Description | Manufacturer Full Name | Manufacturer P/N | RoHS | Sheet |  |
| ##### Change Parts |  |  |  |  |  |  |  |  |  |
| Item | Location | Qty | Foxconn P/N | Part Description | Manufacturer Full Name | Manufacturer P/N | RoHS | Sheet | Remark |
| 1 | U_TMP | 1 | 320403K00-183-G | IC,Temp Sensor,TMP75AIDR,3°C,G,SOIC-8,SMD | TEXAS INSTRUMENTS | TMP75AIDR | G | PWA BOM | In New BOM |
|  |  |  | 320403Q00-173-G | IC,Temp Sensor,DS75S+T&R,3°C,G,SO-8,SMD | MAXIM INTEGRATED PRODUCTS, INC. | DS75S+T&R | G | PWA BOM | In New BOM |
|  |  |  | 320405300-214-G | IC,Temp Sensor,STLM75M2F,±0.5°C,G,SO-8,SMD | ST MICRO ELECTRONICS,INC | STLM75M2F | G | PWA BOM | In New BOM |
|  |  |  | 32040SL00-223-G | IC,Temperature Sensor,NCT75DR2G,G,SOIC-8,SMD | ON SEMICONDUCTOR CORP | NCT75DR2G | G | PWA BOM | In New BOM |
|  |  |  | PCT2075D | IC,Temperature Sensor,PCT2075D,SO-8,SMD | NXP SEMICONDUCTORS | PCT2075D | G | PWA BOM | In New BOM |
|  | U_TMP | 1 | 320403K00-183-G | IC,Temp Sensor,TMP75AIDR,3°C,G,SOIC-8,SMD | TEXAS INSTRUMENTS | TMP75AIDR | G | PWA BOM | In Old BOM |
|  |  |  | 320403Q00-173-G | IC,Temp Sensor,DS75S+T&R,3°C,G,SO-8,SMD | MAXIM INTEGRATED PRODUCTS, INC. | DS75S+T&R | G | PWA BOM | In Old BOM |
|  |  |  | 320405300-214-G | IC,Temp Sensor,STLM75M2F,±0.5°C,G,SO-8,SMD | ST MICRO ELECTRONICS,INC | STLM75M2F | G | PWA BOM | In Old BOM |
|  |  |  | 32040SL00-223-G | IC,Temperature Sensor,NCT75DR2G,G,SOIC-8,SMD | ON SEMICONDUCTOR CORP | NCT75DR2G | G | PWA BOM | In Old BOM |
|  |  |  | 32040FL00-031-G | IC,Temperature Sensor,LM75BD,G,SO-8,SMD | NXP SEMICONDUCTORS | LM75BD | G | PWA BOM | In Old BOM |
| ##### Change Revision |  |  |  |  |  |  |  |  |  |
| Sheet | REV OF BOM | CUSTOMER | CUSTOMER P/N | PWA PN | PWA DESCRIPTION | PWA REV | DATE | Remark |  |
| OOOOOOOOOOOOOOOOOOOOOOOOOOOOOOOOOOOOOOOOOOOOOOOOOOOOOOOOOOOOOOOOOOOOOOOOOOOOOOOOOOOOOOOOOO | OOOOOOOOOOOOOOOOOOOOOOOOOOOOOOOOOOOOOOOOOOOOOOOOOOOOOOOOOOOOOOOOOOOOOOOOOOOOOOOOOOOOOOOOOO | OOOOOOOOOOOOOOOOOOOOOOOOOOOOOOOOOOOOOOOOOOOOOOOOOOOOOOOOOOOOOOOOOOOOOOOOOOOOOOOOOOOOOOOOOO | OOOOOOOOOOOOOOOOOOOOOOOOOOOOOOOOOOOOOOOOOOOOOOOOOOOOOOOOOOOOOOOOOOOOOOOOOOOOOOOOOOOOOOOOOO | OOOOOOOOOOOOOOOOOOOOOOOOOOOOOOOOOOOOOOOOOOOOOOOOOOOOOOOOOOOOOOOOOOOOOOOOOOOOOOOOOOOOOOOOOO | OOOOOOOOOOOOOOOOOOOOOOOOOOOOOOOOOOOOOOOOOOOOOOOOOOOOOOOOOOOOOOOOOOOOOOOOOOOOOOOOOOOOOOOOOO | OOOOOOOOOOOOOOOOOOOOOOOOOOOOOOOOOOOOOOOOOOOOOOOOOOOOOOOOOOOOOOOOOOOOOOOOOOOOOOOOOOOOOOOOOO | OOOOOOOOOOOOOOOOOOOOOOOOOOOOOOOOOOOOOOOOOOOOOOOOOOOOOOOOOOOOOOOOOOOOOOOOOOOOOOOOOOOOOOOOOO | OOOOOOOOOOOOOOOOOOOOOOOOOOOOOOOOOOOOOOOOOOOOOOOOOOOOOOOOOOOOOOOOOOOOOOOOOOOOOOOOOOOOOOOOOO | OOOOOOOOOOOOOOOOOOOOOOOOOOOOOOOOOOOOOOOOOOOOOOOOOOOOOOOOOOOOOOOOOOOOOOOOOOOOOOOOOOOOOOOOOO |
| Second Source Change |  |  |  |  |  |  |  |  |  |
| Item | Location | Change Type | Foxconn P/N | Part Description | Manufacturer Full Name | Manufacturer P/N | RoHS | Sheet |  |
| 1 | U_TMP |  | 320403K00-183-G | IC,Temp Sensor,TMP75AIDR,3°C,G,SOIC-8,SMD | TEXAS INSTRUMENTS | TMP75AIDR | G | PWA BOM |  |
|  |  | NO | 320403Q00-173-G | IC,Temp Sensor,DS75S+T&R,3°C,G,SO-8,SMD | MAXIM INTEGRATED PRODUCTS, INC. | DS75S+T&R | G | PWA BOM |  |
|  |  | NO | 320405300-214-G | IC,Temp Sensor,STLM75M2F,±0.5°C,G,SO-8,SMD | ST MICRO ELECTRONICS,INC | STLM75M2F | G | PWA BOM |  |
|  |  | NO | 32040SL00-223-G | IC,Temperature Sensor,NCT75DR2G,G,SOIC-8,SMD | ON SEMICONDUCTOR CORP | NCT75DR2G | G | PWA BOM |  |
|  |  | ADD | PCT2075D | IC,Temperature Sensor,PCT2075D,SO-8,SMD | NXP SEMICONDUCTORS | PCT2075D | G | PWA BOM |  |
|  |  | Delete | 32040FL00-031-G | IC,Temperature Sensor,LM75BD,G,SO-8,SMD | NXP SEMICONDUCTORS | LM75BD | G | PWA BOM |  |
| OOOOOOOOOOOOOOOOOOOOOOOOOOOOOOOOOOOOOOOOOOOOOOOOOOOOOOOOOOOOOOOOOOOOOOOOOOOOOOOOOOOOOOOOOO | OOOOOOOOOOOOOOOOOOOOOOOOOOOOOOOOOOOOOOOOOOOOOOOOOOOOOOOOOOOOOOOOOOOOOOOOOOOOOOOOOOOOOOOOOO | OOOOOOOOOOOOOOOOOOOOOOOOOOOOOOOOOOOOOOOOOOOOOOOOOOOOOOOOOOOOOOOOOOOOOOOOOOOOOOOOOOOOOOOOOO | OOOOOOOOOOOOOOOOOOOOOOOOOOOOOOOOOOOOOOOOOOOOOOOOOOOOOOOOOOOOOOOOOOOOOOOOOOOOOOOOOOOOOOOOOO | OOOOOOOOOOOOOOOOOOOOOOOOOOOOOOOOOOOOOOOOOOOOOOOOOOOOOOOOOOOOOOOOOOOOOOOOOOOOOOOOOOOOOOOOOO | OOOOOOOOOOOOOOOOOOOOOOOOOOOOOOOOOOOOOOOOOOOOOOOOOOOOOOOOOOOOOOOOOOOOOOOOOOOOOOOOOOOOOOOOOO | OOOOOOOOOOOOOOOOOOOOOOOOOOOOOOOOOOOOOOOOOOOOOOOOOOOOOOOOOOOOOOOOOOOOOOOOOOOOOOOOOOOOOOOOOO | OOOOOOOOOOOOOOOOOOOOOOOOOOOOOOOOOOOOOOOOOOOOOOOOOOOOOOOOOOOOOOOOOOOOOOOOOOOOOOOOOOOOOOOOOO | OOOOOOOOOOOOOOOOOOOOOOOOOOOOOOOOOOOOOOOOOOOOOOOOOOOOOOOOOOOOOOOOOOOOOOOOOOOOOOOOOOOOOOOOOO | OOOOOOOOOOOOOOOOOOOOOOOOOOOOOOOOOOOOOOOOOOOOOOOOOOOOOOOOOOOOOOOOOOOOOOOOOOOOOOOOOOOOOOOOOO |
| Master Materials Change |  |  |  |  |  |  |  |  |  |
| Item | Foxconn P/N | Orig._Usage | New_Usage | Part Description | Manufacturer Full Name | Manufacturer P/N | RoHS | Location | Sheet |
| OOOOOOOOOOOOOOOOOOOOOOOOOOOOOOOOOOOOOOOOOOOOOOOOOOOOOOOOOOOOOOOOOOOOOOOOOOOOOOOOOOOOOOOOOO | OOOOOOOOOOOOOOOOOOOOOOOOOOOOOOOOOOOOOOOOOOOOOOOOOOOOOOOOOOOOOOOOOOOOOOOOOOOOOOOOOOOOOOOOOO | OOOOOOOOOOOOOOOOOOOOOOOOOOOOOOOOOOOOOOOOOOOOOOOOOOOOOOOOOOOOOOOOOOOOOOOOOOOOOOOOOOOOOOOOOO | OOOOOOOOOOOOOOOOOOOOOOOOOOOOOOOOOOOOOOOOOOOOOOOOOOOOOOOOOOOOOOOOOOOOOOOOOOOOOOOOOOOOOOOOOO | OOOOOOOOOOOOOOOOOOOOOOOOOOOOOOOOOOOOOOOOOOOOOOOOOOOOOOOOOOOOOOOOOOOOOOOOOOOOOOOOOOOOOOOOOO | OOOOOOOOOOOOOOOOOOOOOOOOOOOOOOOOOOOOOOOOOOOOOOOOOOOOOOOOOOOOOOOOOOOOOOOOOOOOOOOOOOOOOOOOOO | OOOOOOOOOOOOOOOOOOOOOOOOOOOOOOOOOOOOOOOOOOOOOOOOOOOOOOOOOOOOOOOOOOOOOOOOOOOOOOOOOOOOOOOOOO | OOOOOOOOOOOOOOOOOOOOOOOOOOOOOOOOOOOOOOOOOOOOOOOOOOOOOOOOOOOOOOOOOOOOOOOOOOOOOOOOOOOOOOOOOO | OOOOOOOOOOOOOOOOOOOOOOOOOOOOOOOOOOOOOOOOOOOOOOOOOOOOOOOOOOOOOOOOOOOOOOOOOOOOOOOOOOOOOOOOOO | OOOOOOOOOOOOOOOOOOOOOOOOOOOOOOOOOOOOOOOOOOOOOOOOOOOOOOOOOOOOOOOOOOOOOOOOOOOOOOOOOOOOOOOOOO |
| TLA Parts Change |  |  |  |  |  |  |  |  |  |
| Item | Foxconn P/N | Qty | Part Description | Manufacturer Full Name | Manufacturer P/N | RoHS | Location | Remark | BOM |
| BOM Change List Date:Thu Dec 28 17:06:19 GMT+08:00 2017 |  |  |  |  |  |  |  |  |  |
| New BOM file : C:\<user>\BARRELEYE-G2-MB-PVT-HW-EBOM-20171228.xls |  |  |  |  |  |  |  |  |  |
| Old BOM file : C:\<user>\BARRELEYE-G2-MB-PVT-HW-EBOM-20171218.xls |  |  |  |  |  |  |  |  |  |
| ##### Add Parts |  |  |  |  |  |  |  |  |  |
| Item | Location | Qty | Foxconn P/N | Part Description | Manufacturer Full Name | Manufacturer P/N | RoHS | Sheet |  |
| 1 | PBAR5,PAAR5,PAAR6,PBAR14 | 4 | 610107A00-017-G | RES,0 Ohm,+/-5%,1/16W,G,SMD0402 | KOA SPEER ELECTRONICS, INC. | RK73Z1ETTP | N | PWA BOM |  |
| 2 | PBAR8,PAAR9 | 2 | 61010PS00-017-G | RES,200KOhm,+/-1%,1/16W,G,SMD0402 | KOA SPEER ELECTRONICS, INC. | RK73H1ETTP2003F | N | PWA BOM |  |
| ##### Remove Parts |  |  |  |  |  |  |  |  |  |
| Item | Location | Qty | Foxconn P/N | Part Description | Manufacturer Full Name | Manufacturer P/N | RoHS | Sheet |  |
| 1 | PBAR6,PAAR7,PBAR313,PAAR313 | 4 | 610107A00-017-G | RES,0 Ohm,+/-5%,1/16W,G,SMD0402 | KOA SPEER ELECTRONICS, INC. | RK73Z1ETTP | N | PWA BOM |  |
| ##### Change Parts |  |  |  |  |  |  |  |  |  |
| Item | Location | Qty | Foxconn P/N | Part Description | Manufacturer Full Name | Manufacturer P/N | RoHS | Sheet | Remark |
| 1 | PBAC4,PAAC4 | 2 | 620108000-015-G | CAP,100pF,+/-5%,NPO(C0G),50V,G,SMD0402 | MURATA ELEC. NORTH AMERICA | GRM1555C1H101J | Y | PWA BOM | In New BOM |
|  | PBAC4,PAAC4 | 2 | 62010FF00-015-G | CAP,47pF,+/-5%,NPO(C0G),50V,G,SMD0402 | MURATA ELEC. NORTH AMERICA | GRM1555C1H470J | Y | PWA BOM | In Old BOM |
| ##### Change Revision |  |  |  |  |  |  |  |  |  |
| Sheet | REV OF BOM | CUSTOMER | CUSTOMER P/N | PWA PN | PWA DESCRIPTION | PWA REV | DATE | Remark |  |
| OOOOOOOOOOOOOOOOOOOOOOOOOOOOOOOOOOOOOOOOOOOOOOOOOOOOOOOOOOOOOOOOOOOOOOOOOOOOOOOOOOOOOOOOOO | OOOOOOOOOOOOOOOOOOOOOOOOOOOOOOOOOOOOOOOOOOOOOOOOOOOOOOOOOOOOOOOOOOOOOOOOOOOOOOOOOOOOOOOOOO | OOOOOOOOOOOOOOOOOOOOOOOOOOOOOOOOOOOOOOOOOOOOOOOOOOOOOOOOOOOOOOOOOOOOOOOOOOOOOOOOOOOOOOOOOO | OOOOOOOOOOOOOOOOOOOOOOOOOOOOOOOOOOOOOOOOOOOOOOOOOOOOOOOOOOOOOOOOOOOOOOOOOOOOOOOOOOOOOOOOOO | OOOOOOOOOOOOOOOOOOOOOOOOOOOOOOOOOOOOOOOOOOOOOOOOOOOOOOOOOOOOOOOOOOOOOOOOOOOOOOOOOOOOOOOOOO | OOOOOOOOOOOOOOOOOOOOOOOOOOOOOOOOOOOOOOOOOOOOOOOOOOOOOOOOOOOOOOOOOOOOOOOOOOOOOOOOOOOOOOOOOO | OOOOOOOOOOOOOOOOOOOOOOOOOOOOOOOOOOOOOOOOOOOOOOOOOOOOOOOOOOOOOOOOOOOOOOOOOOOOOOOOOOOOOOOOOO | OOOOOOOOOOOOOOOOOOOOOOOOOOOOOOOOOOOOOOOOOOOOOOOOOOOOOOOOOOOOOOOOOOOOOOOOOOOOOOOOOOOOOOOOOO | OOOOOOOOOOOOOOOOOOOOOOOOOOOOOOOOOOOOOOOOOOOOOOOOOOOOOOOOOOOOOOOOOOOOOOOOOOOOOOOOOOOOOOOOOO | OOOOOOOOOOOOOOOOOOOOOOOOOOOOOOOOOOOOOOOOOOOOOOOOOOOOOOOOOOOOOOOOOOOOOOOOOOOOOOOOOOOOOOOOOO |
| Second Source Change |  |  |  |  |  |  |  |  |  |
| Item | Location | Change Type | Foxconn P/N | Part Description | Manufacturer Full Name | Manufacturer P/N | RoHS | Sheet |  |
| OOOOOOOOOOOOOOOOOOOOOOOOOOOOOOOOOOOOOOOOOOOOOOOOOOOOOOOOOOOOOOOOOOOOOOOOOOOOOOOOOOOOOOOOOO | OOOOOOOOOOOOOOOOOOOOOOOOOOOOOOOOOOOOOOOOOOOOOOOOOOOOOOOOOOOOOOOOOOOOOOOOOOOOOOOOOOOOOOOOOO | OOOOOOOOOOOOOOOOOOOOOOOOOOOOOOOOOOOOOOOOOOOOOOOOOOOOOOOOOOOOOOOOOOOOOOOOOOOOOOOOOOOOOOOOOO | OOOOOOOOOOOOOOOOOOOOOOOOOOOOOOOOOOOOOOOOOOOOOOOOOOOOOOOOOOOOOOOOOOOOOOOOOOOOOOOOOOOOOOOOOO | OOOOOOOOOOOOOOOOOOOOOOOOOOOOOOOOOOOOOOOOOOOOOOOOOOOOOOOOOOOOOOOOOOOOOOOOOOOOOOOOOOOOOOOOOO | OOOOOOOOOOOOOOOOOOOOOOOOOOOOOOOOOOOOOOOOOOOOOOOOOOOOOOOOOOOOOOOOOOOOOOOOOOOOOOOOOOOOOOOOOO | OOOOOOOOOOOOOOOOOOOOOOOOOOOOOOOOOOOOOOOOOOOOOOOOOOOOOOOOOOOOOOOOOOOOOOOOOOOOOOOOOOOOOOOOOO | OOOOOOOOOOOOOOOOOOOOOOOOOOOOOOOOOOOOOOOOOOOOOOOOOOOOOOOOOOOOOOOOOOOOOOOOOOOOOOOOOOOOOOOOOO | OOOOOOOOOOOOOOOOOOOOOOOOOOOOOOOOOOOOOOOOOOOOOOOOOOOOOOOOOOOOOOOOOOOOOOOOOOOOOOOOOOOOOOOOOO | OOOOOOOOOOOOOOOOOOOOOOOOOOOOOOOOOOOOOOOOOOOOOOOOOOOOOOOOOOOOOOOOOOOOOOOOOOOOOOOOOOOOOOOOOO |
| Master Materials Change |  |  |  |  |  |  |  |  |  |
| Item | Foxconn P/N | Orig._Usage | New_Usage | Part Description | Manufacturer Full Name | Manufacturer P/N | RoHS | Location | Sheet |
| 1 | 620108000-015-G | 26 | 28 | CAP,100pF,+/-5%,NPO(C0G),50V,G,SMD0402 | MURATA ELEC. NORTH AMERICA | GRM1555C1H101J | Y | (+)PBAC4,PAAC4 | PWA BOM |
| 2 | 61010PS00-017-G | 50 | 52 | RES,200KOhm,+/-1%,1/16W,G,SMD0402 | KOA SPEER ELECTRONICS, INC. | RK73H1ETTP2003F | N | (+)PBAR8,PAAR9 | PWA BOM |
| 3 | 62010FF00-015-G | 6 | 4 | CAP,47pF,+/-5%,NPO(C0G),50V,G,SMD0402 | MURATA ELEC. NORTH AMERICA | GRM1555C1H470J | Y | (-)PBAC4,PAAC4 | PWA BOM |
| OOOOOOOOOOOOOOOOOOOOOOOOOOOOOOOOOOOOOOOOOOOOOOOOOOOOOOOOOOOOOOOOOOOOOOOOOOOOOOOOOOOOOOOOOO | OOOOOOOOOOOOOOOOOOOOOOOOOOOOOOOOOOOOOOOOOOOOOOOOOOOOOOOOOOOOOOOOOOOOOOOOOOOOOOOOOOOOOOOOOO | OOOOOOOOOOOOOOOOOOOOOOOOOOOOOOOOOOOOOOOOOOOOOOOOOOOOOOOOOOOOOOOOOOOOOOOOOOOOOOOOOOOOOOOOOO | OOOOOOOOOOOOOOOOOOOOOOOOOOOOOOOOOOOOOOOOOOOOOOOOOOOOOOOOOOOOOOOOOOOOOOOOOOOOOOOOOOOOOOOOOO | OOOOOOOOOOOOOOOOOOOOOOOOOOOOOOOOOOOOOOOOOOOOOOOOOOOOOOOOOOOOOOOOOOOOOOOOOOOOOOOOOOOOOOOOOO | OOOOOOOOOOOOOOOOOOOOOOOOOOOOOOOOOOOOOOOOOOOOOOOOOOOOOOOOOOOOOOOOOOOOOOOOOOOOOOOOOOOOOOOOOO | OOOOOOOOOOOOOOOOOOOOOOOOOOOOOOOOOOOOOOOOOOOOOOOOOOOOOOOOOOOOOOOOOOOOOOOOOOOOOOOOOOOOOOOOOO | OOOOOOOOOOOOOOOOOOOOOOOOOOOOOOOOOOOOOOOOOOOOOOOOOOOOOOOOOOOOOOOOOOOOOOOOOOOOOOOOOOOOOOOOOO | OOOOOOOOOOOOOOOOOOOOOOOOOOOOOOOOOOOOOOOOOOOOOOOOOOOOOOOOOOOOOOOOOOOOOOOOOOOOOOOOOOOOOOOOOO |  |
| TLA Parts Change |  |  |  |  |  |  |  |  |  |
| Item | Foxconn P/N | Qty | Part Description | Manufacturer Full Name | Manufacturer P/N | RoHS | Location | Remark |  |
| BOM Change List Date:Fri Dec 29 09:51:10 CST 2017 |  |  |  |  |  |  |  |  |  |
| New BOM file : E:\barreleye g2\1228\BARRELEYE_G2-MB-PVT-X04-HW-BOM-X25_20171229.xls |  |  |  |  |  |  |  |  |  |
| Old BOM file : E:\barreleye g2\1228\BG2 1222.xls |  |  |  |  |  |  |  |  |  |
| ##### Add Parts |  |  |  |  |  |  |  |  |  |
| Item | Location | Qty | Foxconn P/N | Part Description | Manufacturer Full Name | Manufacturer P/N | RoHS | Sheet |  |
| 1 | PBAR5,PAAR5,PAAR6,PBAR14 | 4 | 610107A00-017-G | RES,0 Ohm,+/-5%,1/16W,G,SMD0402 | KOA SPEER ELECTRONICS, INC. | RK73Z1ETTP | G | PWA BOM |  |
|  |  |  | 610107A00-012-G | RES,0 Ohm,+/-5%,1/16W,G,SMD0402 | WALSIN TECHNOLOGY CORPORATION | WR04X000PTL | G | PWA BOM |  |
|  |  |  | 610107A00-011-G | RES,0 Ohm,+/-5%,1/16W,G,SMD0402 | YAGEO CORPORATION COMPONENT | RC0402JR-070RL | G | PWA BOM |  |
|  |  |  | 610107A00-044-G | RES,0 Ohm,+/-5%,1/16W,G,SMD0402 | TA-I TECHNOLOGY CO., LTD | RM04JTN0 | G | PWA BOM |  |
|  |  |  | 610107A00-024-G | RES,0 Ohm,+/-5%,1/16W,G,SMD0402 | PANASONIC INDUSTRIAL CO.,LTD. | ERJ2GE0R00X | G | PWA BOM |  |
|  |  |  | 610107A00-029-G | RES,0 Ohm,+/-5%,1/16W,G,SMD0402 | VISHAY ENTER TECHNO LOGY.INC | CRCW04020000Z0ED | G | PWA BOM |  |
| 2 | PBAR8,PAAR9 | 2 | 61010PS00-017-G | RES,200KOhm,+/-1%,1/16W,G,SMD0402 | KOA SPEER ELECTRONICS, INC. | RK73H1ETTP2003F | G | PWA BOM |  |
|  |  |  | 61010PS00-012-G | RES,200KOhm,+/-1%,1/16W,G,SMD0402 | WALSIN TECHNOLOGY CORPORATION | WR04X2003FTL | G | PWA BOM |  |
|  |  |  | 61010PS00-011-G | RES,200KOhm,+/-1%,1/16W,G,SMD0402 | YAGEO CORPORATION COMPONENT | RC0402FR-07200KL | G | PWA BOM |  |
|  |  |  | 61010PS00-044-G | RES,200KOhm,+/-1%,1/16W,G,SMD0402 | TA-I TECHNOLOGY CO., LTD | RM04FTN2003 | G | PWA BOM |  |
| ##### Remove Parts |  |  |  |  |  |  |  |  |  |
| Item | Location | Qty | Foxconn P/N | Part Description | Manufacturer Full Name | Manufacturer P/N | RoHS | Sheet |  |
| 1 | PBAR6,PAAR7,PBAR313,PAAR313 | 4 | 610107A00-017-G | RES,0 Ohm,+/-5%,1/16W,G,SMD0402 | KOA SPEER ELECTRONICS, INC. | RK73Z1ETTP | G | PWA BOM |  |
|  |  |  | 610107A00-012-G | RES,0 Ohm,+/-5%,1/16W,G,SMD0402 | WALSIN TECHNOLOGY CORPORATION | WR04X000PTL | G | PWA BOM |  |
|  |  |  | 610107A00-011-G | RES,0 Ohm,+/-5%,1/16W,G,SMD0402 | YAGEO CORPORATION COMPONENT | RC0402JR-070RL | G | PWA BOM |  |
|  |  |  | 610107A00-044-G | RES,0 Ohm,+/-5%,1/16W,G,SMD0402 | TA-I TECHNOLOGY CO., LTD | RM04JTN0 | G | PWA BOM |  |
|  |  |  | 610107A00-024-G | RES,0 Ohm,+/-5%,1/16W,G,SMD0402 | PANASONIC INDUSTRIAL CO.,LTD. | ERJ2GE0R00X | G | PWA BOM |  |
|  |  |  | 610107A00-029-G | RES,0 Ohm,+/-5%,1/16W,G,SMD0402 | VISHAY ENTER TECHNO LOGY.INC | CRCW04020000Z0ED | G | PWA BOM |  |
| ##### Change Parts |  |  |  |  |  |  |  |  |  |
| Item | Location | Qty | Foxconn P/N | Part Description | Manufacturer Full Name | Manufacturer P/N | RoHS | Sheet | Remark |
| 1 | C1424,C1427,C1451,C1455,C1459,C1464,C1466,C1468,C1470,C1499,C1533,C1577,C1585,C1596 | 14 | 620109S00-015-G | CAP,4.7uF,+/-10%,X7R,10V,G,SMD0805 | MURATA ELEC. NORTH AMERICA | GRM21BR71A475K | G | PWA BOM | In New BOM |
|  | C1424,C1427,C1451,C1455,C1459,C1464,C1466,C1468,C1470,C1499,C1533,C1577,C1585,C1596 | 14 | 620109S00-023-G | CAP,4.7uF,+/-10%,X7R,10V,G,SMD0805 | TAIYO ELECTRIC IND.CO.LTD | LMK212B7475KG-T | G | PWA BOM | In Old BOM |
|  |  |  | 620109S00-026-G | CAP,4.7uF,+/-10%,X7R,10V,G,SMD0805 | SAMSUNG SEMICONDUCTOR | CL21B475KPFNNNE | G | PWA BOM | In Old BOM |
|  |  |  | 620109S00-015-G | CAP,4.7uF,+/-10%,X7R,10V,G,SMD0805 | MURATA ELEC. NORTH AMERICA | GRM21BR71A475K | G | PWA BOM | In Old BOM |
| 2 | PBAC4,PAAC4 | 2 | 620108000-015-G | CAP,100pF,+/-5%,NPO(C0G),50V,G,SMD0402 | MURATA ELEC. NORTH AMERICA | GRM1555C1H101J | G | PWA BOM | In New BOM |
|  |  |  | 62010800A-012-G | CAP,100pF,+/-5%,NPO(C0G),50V,G,SMD0402 | WALSIN TECHNOLOGY CORPORATION | 0402N101J500CT | G | PWA BOM | In New BOM |
|  |  |  | 620108000-026-G | CAP,100pF,+/-5%,NPO(C0G),50V,G,SMD0402 | SAMSUNG SEMICONDUCTOR | CL05C101JB5NNNC | G | PWA BOM | In New BOM |
|  |  |  | 620108000-023-G | CAP,100pF,+/-5%,NPO(C0G),50V,G,SMD0402 | TAIYO ELECTRIC IND.CO.LTD | UMK105CG101JV-F | G | PWA BOM | In New BOM |
|  | PBAC4,PAAC4 | 2 | 62010FF00-015-G | CAP,47pF,+/-5%,NPO(C0G),50V,G,SMD0402 | MURATA ELEC. NORTH AMERICA | GRM1555C1H470J | G | PWA BOM | In Old BOM |
|  |  |  | 62010FF06-012-G | CAP,47pF,+/-5%,NPO(C0G),50V,G,SMD0402 | WALSIN TECHNOLOGY CORPORATION | 0402N470J500CT | G | PWA BOM | In Old BOM |
|  |  |  | 62010FF00-026-G | CAP,47pF,+/-5%,NPO(C0G),50V,G,SMD0402 | SAMSUNG SEMICONDUCTOR | CL05C470JB5NNNC | G | PWA BOM | In Old BOM |
|  |  |  | 62010FF00-023-G | CAP,47pF,+/-5%,NPO(C0G),50V,G,SMD0402 | TAIYO ELECTRIC IND.CO.LTD | UMK105CG470JV-F | G | PWA BOM | In Old BOM |
| 3 | U60 | 1 | 21050P200-031-G | IC,NXP,PCF8523TK,G,HVSON-8,SMD | NXP SEMICONDUCTORS | PCF8523TK | G | PWA BOM | In New BOM |
|  | U60 | 1 | PCF8523TK/1 | IC,NXP,PCF8523TK/1,G,HVSON-8,SMD | NXP SEMICONDUCTORS | PCF8523TK/1 | G | PWA BOM | In Old BOM |
| ##### Change Revision |  |  |  |  |  |  |  |  |  |
| Sheet | REV OF BOM | CUSTOMER | CUSTOMER P/N | PWA PN | PWA DESCRIPTION | PWA REV | DATE | Remark |  |
| OOOOOOOOOOOOOOOOOOOOOOOOOOOOOOOOOOOOOOOOOOOOOOOOOOOOOOOOOOOOOOOOOOOOOOOOOOOOOOOOOOOOOOOOOO | OOOOOOOOOOOOOOOOOOOOOOOOOOOOOOOOOOOOOOOOOOOOOOOOOOOOOOOOOOOOOOOOOOOOOOOOOOOOOOOOOOOOOOOOOO | OOOOOOOOOOOOOOOOOOOOOOOOOOOOOOOOOOOOOOOOOOOOOOOOOOOOOOOOOOOOOOOOOOOOOOOOOOOOOOOOOOOOOOOOOO | OOOOOOOOOOOOOOOOOOOOOOOOOOOOOOOOOOOOOOOOOOOOOOOOOOOOOOOOOOOOOOOOOOOOOOOOOOOOOOOOOOOOOOOOOO | OOOOOOOOOOOOOOOOOOOOOOOOOOOOOOOOOOOOOOOOOOOOOOOOOOOOOOOOOOOOOOOOOOOOOOOOOOOOOOOOOOOOOOOOOO | OOOOOOOOOOOOOOOOOOOOOOOOOOOOOOOOOOOOOOOOOOOOOOOOOOOOOOOOOOOOOOOOOOOOOOOOOOOOOOOOOOOOOOOOOO | OOOOOOOOOOOOOOOOOOOOOOOOOOOOOOOOOOOOOOOOOOOOOOOOOOOOOOOOOOOOOOOOOOOOOOOOOOOOOOOOOOOOOOOOOO | OOOOOOOOOOOOOOOOOOOOOOOOOOOOOOOOOOOOOOOOOOOOOOOOOOOOOOOOOOOOOOOOOOOOOOOOOOOOOOOOOOOOOOOOOO | OOOOOOOOOOOOOOOOOOOOOOOOOOOOOOOOOOOOOOOOOOOOOOOOOOOOOOOOOOOOOOOOOOOOOOOOOOOOOOOOOOOOOOOOOO | OOOOOOOOOOOOOOOOOOOOOOOOOOOOOOOOOOOOOOOOOOOOOOOOOOOOOOOOOOOOOOOOOOOOOOOOOOOOOOOOOOOOOOOOOO |
| Second Source Change |  |  |  |  |  |  |  |  |  |
| Item | Location | Change Type | Foxconn P/N | Part Description | Manufacturer Full Name | Manufacturer P/N | RoHS | Sheet |  |
| OOOOOOOOOOOOOOOOOOOOOOOOOOOOOOOOOOOOOOOOOOOOOOOOOOOOOOOOOOOOOOOOOOOOOOOOOOOOOOOOOOOOOOOOOO | OOOOOOOOOOOOOOOOOOOOOOOOOOOOOOOOOOOOOOOOOOOOOOOOOOOOOOOOOOOOOOOOOOOOOOOOOOOOOOOOOOOOOOOOOO | OOOOOOOOOOOOOOOOOOOOOOOOOOOOOOOOOOOOOOOOOOOOOOOOOOOOOOOOOOOOOOOOOOOOOOOOOOOOOOOOOOOOOOOOOO | OOOOOOOOOOOOOOOOOOOOOOOOOOOOOOOOOOOOOOOOOOOOOOOOOOOOOOOOOOOOOOOOOOOOOOOOOOOOOOOOOOOOOOOOOO | OOOOOOOOOOOOOOOOOOOOOOOOOOOOOOOOOOOOOOOOOOOOOOOOOOOOOOOOOOOOOOOOOOOOOOOOOOOOOOOOOOOOOOOOOO | OOOOOOOOOOOOOOOOOOOOOOOOOOOOOOOOOOOOOOOOOOOOOOOOOOOOOOOOOOOOOOOOOOOOOOOOOOOOOOOOOOOOOOOOOO | OOOOOOOOOOOOOOOOOOOOOOOOOOOOOOOOOOOOOOOOOOOOOOOOOOOOOOOOOOOOOOOOOOOOOOOOOOOOOOOOOOOOOOOOOO | OOOOOOOOOOOOOOOOOOOOOOOOOOOOOOOOOOOOOOOOOOOOOOOOOOOOOOOOOOOOOOOOOOOOOOOOOOOOOOOOOOOOOOOOOO | OOOOOOOOOOOOOOOOOOOOOOOOOOOOOOOOOOOOOOOOOOOOOOOOOOOOOOOOOOOOOOOOOOOOOOOOOOOOOOOOOOOOOOOOOO | OOOOOOOOOOOOOOOOOOOOOOOOOOOOOOOOOOOOOOOOOOOOOOOOOOOOOOOOOOOOOOOOOOOOOOOOOOOOOOOOOOOOOOOOOO |
| Master Materials Change |  |  |  |  |  |  |  |  |  |
| Item | Foxconn P/N | Orig._Usage | New_Usage | Part Description | Manufacturer Full Name | Manufacturer P/N | RoHS | Location | Sheet |
| 1 | 620109S00-015-G | 0 | 14 | CAP,4.7uF,+/-10%,X7R,10V,G,SMD0805 | MURATA ELEC. NORTH AMERICA | GRM21BR71A475K | G | (+)C1424,C1427,C1451,C1455,C1459,C1464,C1466,C1468,C1470,C1499,C1533,C1577,C1585,C1596 | PWA BOM |
| 2 | 620108000-015-G | 26 | 28 | CAP,100pF,+/-5%,NPO(C0G),50V,G,SMD0402 | MURATA ELEC. NORTH AMERICA | GRM1555C1H101J | G | (+)PBAC4,PAAC4 | PWA BOM |
|  | 62010800A-012-G |  |  | CAP,100pF,+/-5%,NPO(C0G),50V,G,SMD0402 | WALSIN TECHNOLOGY CORPORATION | 0402N101J500CT |  |  | PWA BOM |
|  | 620108000-026-G |  |  | CAP,100pF,+/-5%,NPO(C0G),50V,G,SMD0402 | SAMSUNG SEMICONDUCTOR | CL05C101JB5NNNC |  |  | PWA BOM |
|  | 620108000-023-G |  |  | CAP,100pF,+/-5%,NPO(C0G),50V,G,SMD0402 | TAIYO ELECTRIC IND.CO.LTD | UMK105CG101JV-F |  |  | PWA BOM |
| 3 | 61010PS00-017-G | 50 | 52 | RES,200KOhm,+/-1%,1/16W,G,SMD0402 | KOA SPEER ELECTRONICS, INC. | RK73H1ETTP2003F | G | (+)PBAR8,PAAR9 | PWA BOM |
|  | 61010PS00-012-G |  |  | RES,200KOhm,+/-1%,1/16W,G,SMD0402 | WALSIN TECHNOLOGY CORPORATION | WR04X2003FTL |  |  | PWA BOM |
|  | 61010PS00-011-G |  |  | RES,200KOhm,+/-1%,1/16W,G,SMD0402 | YAGEO CORPORATION COMPONENT | RC0402FR-07200KL |  |  | PWA BOM |
|  | 61010PS00-044-G |  |  | RES,200KOhm,+/-1%,1/16W,G,SMD0402 | TA-I TECHNOLOGY CO., LTD | RM04FTN2003 |  |  | PWA BOM |
| 4 | 62010FF00-015-G | 6 | 4 | CAP,47pF,+/-5%,NPO(C0G),50V,G,SMD0402 | MURATA ELEC. NORTH AMERICA | GRM1555C1H470J | G | (-)PBAC4,PAAC4 | PWA BOM |
|  | 62010FF06-012-G |  |  | CAP,47pF,+/-5%,NPO(C0G),50V,G,SMD0402 | WALSIN TECHNOLOGY CORPORATION | 0402N470J500CT |  |  | PWA BOM |
|  | 62010FF00-026-G |  |  | CAP,47pF,+/-5%,NPO(C0G),50V,G,SMD0402 | SAMSUNG SEMICONDUCTOR | CL05C470JB5NNNC |  |  | PWA BOM |
|  | 62010FF00-023-G |  |  | CAP,47pF,+/-5%,NPO(C0G),50V,G,SMD0402 | TAIYO ELECTRIC IND.CO.LTD | UMK105CG470JV-F |  |  | PWA BOM |
| 5 | 21050P200-031-G | 0 | 1 | IC,NXP,PCF8523TK,G,HVSON-8,SMD | NXP SEMICONDUCTORS | PCF8523TK | G | (+)U60 | PWA BOM |
| 6 | 620109S00-023-G | 14 | 0 | CAP,4.7uF,+/-10%,X7R,10V,G,SMD0805 | TAIYO ELECTRIC IND.CO.LTD | LMK212B7475KG-T | G | (-)C1424,C1427,C1451,C1455,C1459,C1464,C1466,C1468,C1470,C1499,C1533,C1577,C1585,C1596 | PWA BOM |
|  | 620109S00-026-G |  |  | CAP,4.7uF,+/-10%,X7R,10V,G,SMD0805 | SAMSUNG SEMICONDUCTOR | CL21B475KPFNNNE |  |  | PWA BOM |
|  | 620109S00-015-G |  |  | CAP,4.7uF,+/-10%,X7R,10V,G,SMD0805 | MURATA ELEC. NORTH AMERICA | GRM21BR71A475K |  |  | PWA BOM |
| 7 | PCF8523TK/1 | 1 | 0 | IC,NXP,PCF8523TK/1,G,HVSON-8,SMD | NXP SEMICONDUCTORS | PCF8523TK/1 | G | (-)U60 | PWA BOM |
| OOOOOOOOOOOOOOOOOOOOOOOOOOOOOOOOOOOOOOOOOOOOOOOOOOOOOOOOOOOOOOOOOOOOOOOOOOOOOOOOOOOOOOOOOO | OOOOOOOOOOOOOOOOOOOOOOOOOOOOOOOOOOOOOOOOOOOOOOOOOOOOOOOOOOOOOOOOOOOOOOOOOOOOOOOOOOOOOOOOOO | OOOOOOOOOOOOOOOOOOOOOOOOOOOOOOOOOOOOOOOOOOOOOOOOOOOOOOOOOOOOOOOOOOOOOOOOOOOOOOOOOOOOOOOOOO | OOOOOOOOOOOOOOOOOOOOOOOOOOOOOOOOOOOOOOOOOOOOOOOOOOOOOOOOOOOOOOOOOOOOOOOOOOOOOOOOOOOOOOOOOO | OOOOOOOOOOOOOOOOOOOOOOOOOOOOOOOOOOOOOOOOOOOOOOOOOOOOOOOOOOOOOOOOOOOOOOOOOOOOOOOOOOOOOOOOOO | OOOOOOOOOOOOOOOOOOOOOOOOOOOOOOOOOOOOOOOOOOOOOOOOOOOOOOOOOOOOOOOOOOOOOOOOOOOOOOOOOOOOOOOOOO | OOOOOOOOOOOOOOOOOOOOOOOOOOOOOOOOOOOOOOOOOOOOOOOOOOOOOOOOOOOOOOOOOOOOOOOOOOOOOOOOOOOOOOOOOO | OOOOOOOOOOOOOOOOOOOOOOOOOOOOOOOOOOOOOOOOOOOOOOOOOOOOOOOOOOOOOOOOOOOOOOOOOOOOOOOOOOOOOOOOOO | OOOOOOOOOOOOOOOOOOOOOOOOOOOOOOOOOOOOOOOOOOOOOOOOOOOOOOOOOOOOOOOOOOOOOOOOOOOOOOOOOOOOOOOOOO | OOOOOOOOOOOOOOOOOOOOOOOOOOOOOOOOOOOOOOOOOOOOOOOOOOOOOOOOOOOOOOOOOOOOOOOOOOOOOOOOOOOOOOOOOO |
| TLA Parts Change |  |  |  |  |  |  |  |  |  |
| Item | Foxconn P/N | Qty | Part Description | Manufacturer Full Name | Manufacturer P/N | RoHS | Location | Remark | BOM |
| BOM Change List Date:Tue Jan 16 16:08:22 GMT+08:00 2018 |  |  |  |  |  |  |  |  |  |
| New BOM file : C:\<user>\BARRELEYE-G2-MB-PVT-HW-EBOM-20180116.xls |  |  |  |  |  |  |  |  |  |
| Old BOM file : C:\<user>\BARRELEYE-G2-MB-PVT-HW-EBOM-20171228.xls |  |  |  |  |  |  |  |  |  |
| ##### Add Parts |  |  |  |  |  |  |  |  |  |
| Item | Location | Qty | Foxconn P/N | Part Description | Manufacturer Full Name | Manufacturer P/N | RoHS | Sheet |  |
| ##### Remove Parts |  |  |  |  |  |  |  |  |  |
| Item | Location | Qty | Foxconn P/N | Part Description | Manufacturer Full Name | Manufacturer P/N | RoHS | Sheet |  |
| ##### Change Parts |  |  |  |  |  |  |  |  |  |
| Item | Location | Qty | Foxconn P/N | Part Description | Manufacturer Full Name | Manufacturer P/N | RoHS | Sheet | Remark |
| 1 | PBAC125,PAAC125 | 2 | 620107500-015-G | CAP,3.9nF,+/-10%,X7R,50V,G,SMD0402 | MURATA ELEC. NORTH AMERICA | GRM155R71H392K | N | PWA BOM | In New BOM |
|  | PBAC125,PAAC125 | 2 | 620109700-015-G | CAP,3.3nF,+/-10%,X7R,50V,G,SMD0402 | MURATA ELEC. NORTH AMERICA | GRM155R71H332K | N | PWA BOM | In Old BOM |
| 2 | PAAR70,PBAR71 | 2 | 610108U00-017-G | RES,10KOhm,+/-1%,1/10W,G,SMD0603 | KOA SPEER ELECTRONICS, INC. | RK73H1JTTD1002F | N | PWA BOM | In New BOM |
|  | PAAR70,PBAR71 | 2 | 610100C00-017-G | RES,15kOhm,+/-1%,1/10W,G,SMD0603 | KOA SPEER ELECTRONICS, INC. | RK73H1JTTD1502F | N | PWA BOM | In Old BOM |
| 3 | PBER72,PAFR72,PAER72,PBFR73,PBMR74,PAMR74,PBAR77,PAAR77 | 8 | 610108U00-017-G | RES,10KOhm,+/-1%,1/10W,G,SMD0603 | KOA SPEER ELECTRONICS, INC. | RK73H1JTTD1002F | N | PWA BOM | In New BOM |
|  | PBER72,PAFR72,PAER72,PBFR73,PBMR74,PAMR74,PBAR77,PAAR77 | 8 | 610108U00-017-G | RES,10KOhm,+/-1%,1/10W,G,SMD0603 | KOA SPEER ELECTRONICS, INC. | RK73H1JTTD1002F |  | PWA BOM | In Old BOM |
| 4 | PBAR109,PAAR109 | 2 | 61100M100-017-G | RES,4.75KOhm,+/-1%,1/16W,G,SMD0402 | KOA SPEER ELECTRONICS, INC. | RN731ETTP4751F50 |  | PWA BOM | In New BOM |
|  | PBAR109,PAAR109 | 2 | 610107A00-017-G | RES,0 Ohm,+/-5%,1/16W,G,SMD0402 | KOA SPEER ELECTRONICS, INC. | RK73Z1ETTP | N | PWA BOM | In Old BOM |
| 5 | PBNU1,PANU1 | 2 | IR38064MTRP=GZS | IC,Regulator,IR38064MTRP=GZS ,ADJ,35A,G,QFN-26,SMD | INTERNATIONAL RECTIFIER | IR38064MTRP=GZS |  | PWA BOM | In New BOM |
|  | PBNU1,PANU1 | 2 | 320147Q00-238-G | IC,Regulator,IR38064MTRPBF,ADJ,35A,G,QFN-26,SMD | INTERNATIONAL RECTIFIER | IR38064MTRPBF |  | PWA BOM | In Old BOM |
| ##### Change Revision |  |  |  |  |  |  |  |  |  |
| Sheet | REV OF BOM | CUSTOMER | CUSTOMER P/N | PWA PN | PWA DESCRIPTION | PWA REV | DATE | Remark |  |
| OOOOOOOOOOOOOOOOOOOOOOOOOOOOOOOOOOOOOOOOOOOOOOOOOOOOOOOOOOOOOOOOOOOOOOOOOOOOOOOOOOOOOOOOOO | OOOOOOOOOOOOOOOOOOOOOOOOOOOOOOOOOOOOOOOOOOOOOOOOOOOOOOOOOOOOOOOOOOOOOOOOOOOOOOOOOOOOOOOOOO | OOOOOOOOOOOOOOOOOOOOOOOOOOOOOOOOOOOOOOOOOOOOOOOOOOOOOOOOOOOOOOOOOOOOOOOOOOOOOOOOOOOOOOOOOO | OOOOOOOOOOOOOOOOOOOOOOOOOOOOOOOOOOOOOOOOOOOOOOOOOOOOOOOOOOOOOOOOOOOOOOOOOOOOOOOOOOOOOOOOOO | OOOOOOOOOOOOOOOOOOOOOOOOOOOOOOOOOOOOOOOOOOOOOOOOOOOOOOOOOOOOOOOOOOOOOOOOOOOOOOOOOOOOOOOOOO | OOOOOOOOOOOOOOOOOOOOOOOOOOOOOOOOOOOOOOOOOOOOOOOOOOOOOOOOOOOOOOOOOOOOOOOOOOOOOOOOOOOOOOOOOO | OOOOOOOOOOOOOOOOOOOOOOOOOOOOOOOOOOOOOOOOOOOOOOOOOOOOOOOOOOOOOOOOOOOOOOOOOOOOOOOOOOOOOOOOOO | OOOOOOOOOOOOOOOOOOOOOOOOOOOOOOOOOOOOOOOOOOOOOOOOOOOOOOOOOOOOOOOOOOOOOOOOOOOOOOOOOOOOOOOOOO | OOOOOOOOOOOOOOOOOOOOOOOOOOOOOOOOOOOOOOOOOOOOOOOOOOOOOOOOOOOOOOOOOOOOOOOOOOOOOOOOOOOOOOOOOO | OOOOOOOOOOOOOOOOOOOOOOOOOOOOOOOOOOOOOOOOOOOOOOOOOOOOOOOOOOOOOOOOOOOOOOOOOOOOOOOOOOOOOOOOOO |
| Second Source Change |  |  |  |  |  |  |  |  |  |
| Item | Location | Change Type | Foxconn P/N | Part Description | Manufacturer Full Name | Manufacturer P/N | RoHS | Sheet |  |
| OOOOOOOOOOOOOOOOOOOOOOOOOOOOOOOOOOOOOOOOOOOOOOOOOOOOOOOOOOOOOOOOOOOOOOOOOOOOOOOOOOOOOOOOOO | OOOOOOOOOOOOOOOOOOOOOOOOOOOOOOOOOOOOOOOOOOOOOOOOOOOOOOOOOOOOOOOOOOOOOOOOOOOOOOOOOOOOOOOOOO | OOOOOOOOOOOOOOOOOOOOOOOOOOOOOOOOOOOOOOOOOOOOOOOOOOOOOOOOOOOOOOOOOOOOOOOOOOOOOOOOOOOOOOOOOO | OOOOOOOOOOOOOOOOOOOOOOOOOOOOOOOOOOOOOOOOOOOOOOOOOOOOOOOOOOOOOOOOOOOOOOOOOOOOOOOOOOOOOOOOOO | OOOOOOOOOOOOOOOOOOOOOOOOOOOOOOOOOOOOOOOOOOOOOOOOOOOOOOOOOOOOOOOOOOOOOOOOOOOOOOOOOOOOOOOOOO | OOOOOOOOOOOOOOOOOOOOOOOOOOOOOOOOOOOOOOOOOOOOOOOOOOOOOOOOOOOOOOOOOOOOOOOOOOOOOOOOOOOOOOOOOO | OOOOOOOOOOOOOOOOOOOOOOOOOOOOOOOOOOOOOOOOOOOOOOOOOOOOOOOOOOOOOOOOOOOOOOOOOOOOOOOOOOOOOOOOOO | OOOOOOOOOOOOOOOOOOOOOOOOOOOOOOOOOOOOOOOOOOOOOOOOOOOOOOOOOOOOOOOOOOOOOOOOOOOOOOOOOOOOOOOOOO | OOOOOOOOOOOOOOOOOOOOOOOOOOOOOOOOOOOOOOOOOOOOOOOOOOOOOOOOOOOOOOOOOOOOOOOOOOOOOOOOOOOOOOOOOO | OOOOOOOOOOOOOOOOOOOOOOOOOOOOOOOOOOOOOOOOOOOOOOOOOOOOOOOOOOOOOOOOOOOOOOOOOOOOOOOOOOOOOOOOOO |
| Master Materials Change |  |  |  |  |  |  |  |  |  |
| Item | Foxconn P/N | Orig._Usage | New_Usage | Part Description | Manufacturer Full Name | Manufacturer P/N | RoHS | Location | Sheet |
| 1 | 620107500-015-G | 0 | 2 | CAP,3.9nF,+/-10%,X7R,50V,G,SMD0402 | MURATA ELEC. NORTH AMERICA | GRM155R71H392K | N | (+)PBAC125,PAAC125 | PWA BOM |
| 2 | 610107A00-017-G | 719 | 717 | RES,0 Ohm,+/-5%,1/16W,G,SMD0402 | KOA SPEER ELECTRONICS, INC. | RK73Z1ETTP | N | (-)PBAR109,PAAR109 | PWA BOM |
| 3 | 610108U00-017-G | 8 | 10 | RES,10KOhm,+/-1%,1/10W,G,SMD0603 | KOA SPEER ELECTRONICS, INC. | RK73H1JTTD1002F | N | (+)PAAR70,PBAR71 | PWA BOM |
| 4 | 610100C00-017-G | 4 | 2 | RES,15kOhm,+/-1%,1/10W,G,SMD0603 | KOA SPEER ELECTRONICS, INC. | RK73H1JTTD1502F | N | (-)PAAR70,PBAR71 | PWA BOM |
| 5 | 61100M100-017-G | 0 | 2 | RES,4.75KOhm,+/-1%,1/16W,G,SMD0402 | KOA SPEER ELECTRONICS, INC. | RN731ETTP4751F50 |  | (+)PBAR109,PAAR109 | PWA BOM |
| 6 | 620109700-015-G | 23 | 21 | CAP,3.3nF,+/-10%,X7R,50V,G,SMD0402 | MURATA ELEC. NORTH AMERICA | GRM155R71H332K | N | (-)PBAC125,PAAC125 | PWA BOM |
| 7 | IR38064MTRP=GZS | 0 | 2 | IC,Regulator,IR38064MTRP=GZS ,ADJ,35A,G,QFN-26,SMD | INTERNATIONAL RECTIFIER | IR38064MTRP=GZS |  | (+)PBNU1,PANU1 | PWA BOM |
| 8 | 320147Q00-238-G | 2 | 0 | IC,Regulator,IR38064MTRPBF,ADJ,35A,G,QFN-26,SMD | INTERNATIONAL RECTIFIER | IR38064MTRPBF |  | (-)PBNU1,PANU1 | PWA BOM |
| OOOOOOOOOOOOOOOOOOOOOOOOOOOOOOOOOOOOOOOOOOOOOOOOOOOOOOOOOOOOOOOOOOOOOOOOOOOOOOOOOOOOOOOOOO | OOOOOOOOOOOOOOOOOOOOOOOOOOOOOOOOOOOOOOOOOOOOOOOOOOOOOOOOOOOOOOOOOOOOOOOOOOOOOOOOOOOOOOOOOO | OOOOOOOOOOOOOOOOOOOOOOOOOOOOOOOOOOOOOOOOOOOOOOOOOOOOOOOOOOOOOOOOOOOOOOOOOOOOOOOOOOOOOOOOOO | OOOOOOOOOOOOOOOOOOOOOOOOOOOOOOOOOOOOOOOOOOOOOOOOOOOOOOOOOOOOOOOOOOOOOOOOOOOOOOOOOOOOOOOOOO | OOOOOOOOOOOOOOOOOOOOOOOOOOOOOOOOOOOOOOOOOOOOOOOOOOOOOOOOOOOOOOOOOOOOOOOOOOOOOOOOOOOOOOOOOO | OOOOOOOOOOOOOOOOOOOOOOOOOOOOOOOOOOOOOOOOOOOOOOOOOOOOOOOOOOOOOOOOOOOOOOOOOOOOOOOOOOOOOOOOOO | OOOOOOOOOOOOOOOOOOOOOOOOOOOOOOOOOOOOOOOOOOOOOOOOOOOOOOOOOOOOOOOOOOOOOOOOOOOOOOOOOOOOOOOOOO | OOOOOOOOOOOOOOOOOOOOOOOOOOOOOOOOOOOOOOOOOOOOOOOOOOOOOOOOOOOOOOOOOOOOOOOOOOOOOOOOOOOOOOOOOO | OOOOOOOOOOOOOOOOOOOOOOOOOOOOOOOOOOOOOOOOOOOOOOOOOOOOOOOOOOOOOOOOOOOOOOOOOOOOOOOOOOOOOOOOOO |  |
| TLA Parts Change |  |  |  |  |  |  |  |  |  |
| Item | Foxconn P/N | Qty | Part Description | Manufacturer Full Name | Manufacturer P/N | RoHS | Location | Remark |  |
| BOM Change List Date:Wed Jan 17 15:21:45 CST 2018 |  |  |  |  |  |  |  |  |  |
| New BOM file : E:\barreleye g2\0117\BARRELEYE_G2-MB-PVT-X04-HW-BOM-X26_20180117.xls |  |  |  |  |  |  |  |  |  |
| Old BOM file : E:\barreleye g2\0117\BG2 0112.xls |  |  |  |  |  |  |  |  |  |
| ##### Add Parts |  |  |  |  |  |  |  |  |  |
| Item | Location | Qty | Foxconn P/N | Part Description | Manufacturer Full Name | Manufacturer P/N | RoHS | Sheet |  |
| ##### Remove Parts |  |  |  |  |  |  |  |  |  |
| Item | Location | Qty | Foxconn P/N | Part Description | Manufacturer Full Name | Manufacturer P/N | RoHS | Sheet |  |
| ##### Change Parts |  |  |  |  |  |  |  |  |  |
| Item | Location | Qty | Foxconn P/N | Part Description | Manufacturer Full Name | Manufacturer P/N | RoHS | Sheet | Remark |
| 1 | PBAC125,PAAC125 | 2 | 620107500-015-G | CAP,3.9nF,+/-10%,X7R,50V,G,SMD0402 | MURATA ELEC. NORTH AMERICA | GRM155R71H392K | G | PWA BOM | In New BOM |
|  |  |  | 620107500-026-G | CAP,3.9nF,+/-10%,X7R,50V,G,SMD0402 | SAMSUNG SEMICONDUCTOR | CL05B392KB5NNNC | G | PWA BOM | In New BOM |
|  |  |  | 620107500-011-G | CAP,3.9nF,+/-10%,X7R,50V,G,SMD0402 | YAGEO CORPORATION COMPONENT | CC0402KRX7R9BB392 | G | PWA BOM | In New BOM |
|  |  |  | 620107500-023-G | CAP,3.9nF,+/-10%,X7R,50V,G,SMD0402 | TAIYO ELECTRIC IND.CO.LTD | UMK105B7392KV-F | G | PWA BOM | In New BOM |
|  | PBAC125,PAAC125 | 2 | 620109700-015-G | CAP,3.3nF,+/-10%,X7R,50V,G,SMD0402 | MURATA ELEC. NORTH AMERICA | GRM155R71H332K | G | PWA BOM | In Old BOM |
|  |  |  | 620109700-012-G | CAP,3.3nF,+/-10%,X7R,50V,G,SMD0402 | WALSIN TECHNOLOGY CORPORATION | 0402B332K500CT | G | PWA BOM | In Old BOM |
|  |  |  | 620109700-026-G | CAP,3.3nF,+/-10%,X7R,50V,G,SMD0402 | SAMSUNG SEMICONDUCTOR | CL05B332KB5NNNC | G | PWA BOM | In Old BOM |
| 2 | PAAR70,PBAR71 | 2 | 610108U00-017-G | RES,10KOhm,+/-1%,1/10W,G,SMD0603 | KOA SPEER ELECTRONICS, INC. | RK73H1JTTD1002F | G | PWA BOM | In New BOM |
|  |  |  | 610108U00-012-G | RES,10KOhm,+/-1%,1/10W,G,SMD0603 | WALSIN TECHNOLOGY CORPORATION | WR06X1002FTL | G | PWA BOM | In New BOM |
|  |  |  | 610108U00-011-G | RES,10KOhm,+/-1%,1/10W,G,SMD0603 | YAGEO CORPORATION COMPONENT | RC0603FR-0710KL | G | PWA BOM | In New BOM |
|  |  |  | 610108U00-044-G | RES,10KOhm,+/-1%,1/10W,G,SMD0603 | TA-I TECHNOLOGY CO., LTD | RM06FTN1002 | G | PWA BOM | In New BOM |
|  |  |  | 610108U00-024-G | RES,10KOhm,+/-1%,1/10W,G,SMD0603 | PANASONIC INDUSTRIAL CO.,LTD. | ERJ3EKF1002V | G | PWA BOM | In New BOM |
|  | PAAR70,PBAR71 | 2 | 610100C00-017-G | RES,15kOhm,+/-1%,1/10W,G,SMD0603 | KOA SPEER ELECTRONICS, INC. | RK73H1JTTD1502F | G | PWA BOM | In Old BOM |
|  |  |  | 610100C00-011-G | RES,15KOhm,+/-1%,1/10W,G,SMD0603 | YAGEO CORPORATION COMPONENT | RC0603FR-0715KL | G | PWA BOM | In Old BOM |
|  |  |  | 610100C00-012-G | RES,15KOhm,+/-1%,1/10W,G,SMD0603 | WALSIN TECHNOLOGY CORPORATION | WR06X1502FTL | G | PWA BOM | In Old BOM |
|  |  |  | 610100C00-044-G | RES,15KOhm,+/-1%,1/10W,G,SMD0603 | TA-I TECHNOLOGY CO., LTD | RM06FTN1502 | G | PWA BOM | In Old BOM |
| 3 | PBAR109,PAAR109 | 2 | 61100M100-017-G | RES,4.75KOhm,+/-1%,1/16W,G,SMD0402 | KOA SPEER ELECTRONICS, INC. | RN731ETTP4751F50 | G | PWA BOM | In New BOM |
|  |  |  | 61100M100-011-G | RES,4.75KOhm,+/-1%,1/16W,G,SMD0402 | YAGEO CORPORATION COMPONENT | RT0402FRE074K75L | G | PWA BOM | In New BOM |
|  |  |  | 61100M100-012-G | RES,4.75KOhm,+/-1%,1/16W,G,SMD0402 | WALSIN TECHNOLOGY CORPORATION | WF04T4751FTL | G | PWA BOM | In New BOM |
|  |  |  | 61100M100-044-G | RES,4.75KOhm,+/-1%,1/16W,G,SMD0402 | TA-I TECHNOLOGY CO., LTD | RB04FTS4751 | G | PWA BOM | In New BOM |
|  | PBAR109,PAAR109 | 2 | 610107A00-017-G | RES,0 Ohm,+/-5%,1/16W,G,SMD0402 | KOA SPEER ELECTRONICS, INC. | RK73Z1ETTP | G | PWA BOM | In Old BOM |
|  |  |  | 610107A00-012-G | RES,0 Ohm,+/-5%,1/16W,G,SMD0402 | WALSIN TECHNOLOGY CORPORATION | WR04X000PTL | G | PWA BOM | In Old BOM |
|  |  |  | 610107A00-011-G | RES,0 Ohm,+/-5%,1/16W,G,SMD0402 | YAGEO CORPORATION COMPONENT | RC0402JR-070RL | G | PWA BOM | In Old BOM |
|  |  |  | 610107A00-044-G | RES,0 Ohm,+/-5%,1/16W,G,SMD0402 | TA-I TECHNOLOGY CO., LTD | RM04JTN0 | G | PWA BOM | In Old BOM |
|  |  |  | 610107A00-024-G | RES,0 Ohm,+/-5%,1/16W,G,SMD0402 | PANASONIC INDUSTRIAL CO.,LTD. | ERJ2GE0R00X | G | PWA BOM | In Old BOM |
|  |  |  | 610107A00-029-G | RES,0 Ohm,+/-5%,1/16W,G,SMD0402 | VISHAY ENTER TECHNO LOGY.INC | CRCW04020000Z0ED | G | PWA BOM | In Old BOM |
| ##### Change Revision |  |  |  |  |  |  |  |  |  |
| Sheet | REV OF BOM | CUSTOMER | CUSTOMER P/N | PWA PN | PWA DESCRIPTION | PWA REV | DATE | Remark |  |
| OOOOOOOOOOOOOOOOOOOOOOOOOOOOOOOOOOOOOOOOOOOOOOOOOOOOOOOOOOOOOOOOOOOOOOOOOOOOOOOOOOOOOOOOOO | OOOOOOOOOOOOOOOOOOOOOOOOOOOOOOOOOOOOOOOOOOOOOOOOOOOOOOOOOOOOOOOOOOOOOOOOOOOOOOOOOOOOOOOOOO | OOOOOOOOOOOOOOOOOOOOOOOOOOOOOOOOOOOOOOOOOOOOOOOOOOOOOOOOOOOOOOOOOOOOOOOOOOOOOOOOOOOOOOOOOO | OOOOOOOOOOOOOOOOOOOOOOOOOOOOOOOOOOOOOOOOOOOOOOOOOOOOOOOOOOOOOOOOOOOOOOOOOOOOOOOOOOOOOOOOOO | OOOOOOOOOOOOOOOOOOOOOOOOOOOOOOOOOOOOOOOOOOOOOOOOOOOOOOOOOOOOOOOOOOOOOOOOOOOOOOOOOOOOOOOOOO | OOOOOOOOOOOOOOOOOOOOOOOOOOOOOOOOOOOOOOOOOOOOOOOOOOOOOOOOOOOOOOOOOOOOOOOOOOOOOOOOOOOOOOOOOO | OOOOOOOOOOOOOOOOOOOOOOOOOOOOOOOOOOOOOOOOOOOOOOOOOOOOOOOOOOOOOOOOOOOOOOOOOOOOOOOOOOOOOOOOOO | OOOOOOOOOOOOOOOOOOOOOOOOOOOOOOOOOOOOOOOOOOOOOOOOOOOOOOOOOOOOOOOOOOOOOOOOOOOOOOOOOOOOOOOOOO | OOOOOOOOOOOOOOOOOOOOOOOOOOOOOOOOOOOOOOOOOOOOOOOOOOOOOOOOOOOOOOOOOOOOOOOOOOOOOOOOOOOOOOOOOO | OOOOOOOOOOOOOOOOOOOOOOOOOOOOOOOOOOOOOOOOOOOOOOOOOOOOOOOOOOOOOOOOOOOOOOOOOOOOOOOOOOOOOOOOOO |
| Second Source Change |  |  |  |  |  |  |  |  |  |
| Item | Location | Change Type | Foxconn P/N | Part Description | Manufacturer Full Name | Manufacturer P/N | RoHS | Sheet |  |
| OOOOOOOOOOOOOOOOOOOOOOOOOOOOOOOOOOOOOOOOOOOOOOOOOOOOOOOOOOOOOOOOOOOOOOOOOOOOOOOOOOOOOOOOOO | OOOOOOOOOOOOOOOOOOOOOOOOOOOOOOOOOOOOOOOOOOOOOOOOOOOOOOOOOOOOOOOOOOOOOOOOOOOOOOOOOOOOOOOOOO | OOOOOOOOOOOOOOOOOOOOOOOOOOOOOOOOOOOOOOOOOOOOOOOOOOOOOOOOOOOOOOOOOOOOOOOOOOOOOOOOOOOOOOOOOO | OOOOOOOOOOOOOOOOOOOOOOOOOOOOOOOOOOOOOOOOOOOOOOOOOOOOOOOOOOOOOOOOOOOOOOOOOOOOOOOOOOOOOOOOOO | OOOOOOOOOOOOOOOOOOOOOOOOOOOOOOOOOOOOOOOOOOOOOOOOOOOOOOOOOOOOOOOOOOOOOOOOOOOOOOOOOOOOOOOOOO | OOOOOOOOOOOOOOOOOOOOOOOOOOOOOOOOOOOOOOOOOOOOOOOOOOOOOOOOOOOOOOOOOOOOOOOOOOOOOOOOOOOOOOOOOO | OOOOOOOOOOOOOOOOOOOOOOOOOOOOOOOOOOOOOOOOOOOOOOOOOOOOOOOOOOOOOOOOOOOOOOOOOOOOOOOOOOOOOOOOOO | OOOOOOOOOOOOOOOOOOOOOOOOOOOOOOOOOOOOOOOOOOOOOOOOOOOOOOOOOOOOOOOOOOOOOOOOOOOOOOOOOOOOOOOOOO | OOOOOOOOOOOOOOOOOOOOOOOOOOOOOOOOOOOOOOOOOOOOOOOOOOOOOOOOOOOOOOOOOOOOOOOOOOOOOOOOOOOOOOOOOO | OOOOOOOOOOOOOOOOOOOOOOOOOOOOOOOOOOOOOOOOOOOOOOOOOOOOOOOOOOOOOOOOOOOOOOOOOOOOOOOOOOOOOOOOOO |
| Master Materials Change |  |  |  |  |  |  |  |  |  |
| Item | Foxconn P/N | Orig._Usage | New_Usage | Part Description | Manufacturer Full Name | Manufacturer P/N | RoHS | Location | Sheet |
| 1 | 620107500-015-G | 0 | 2 | CAP,3.9nF,+/-10%,X7R,50V,G,SMD0402 | MURATA ELEC. NORTH AMERICA | GRM155R71H392K | G | (+)PBAC125,PAAC125 | PWA BOM |
|  | 620107500-026-G |  |  | CAP,3.9nF,+/-10%,X7R,50V,G,SMD0402 | SAMSUNG SEMICONDUCTOR | CL05B392KB5NNNC |  |  | PWA BOM |
|  | 620107500-011-G |  |  | CAP,3.9nF,+/-10%,X7R,50V,G,SMD0402 | YAGEO CORPORATION COMPONENT | CC0402KRX7R9BB392 |  |  | PWA BOM |
|  | 620107500-023-G |  |  | CAP,3.9nF,+/-10%,X7R,50V,G,SMD0402 | TAIYO ELECTRIC IND.CO.LTD | UMK105B7392KV-F |  |  | PWA BOM |
| 2 | 610107A00-017-G | 719 | 717 | RES,0 Ohm,+/-5%,1/16W,G,SMD0402 | KOA SPEER ELECTRONICS, INC. | RK73Z1ETTP | G | (-)PBAR109,PAAR109 | PWA BOM |
|  | 610107A00-012-G |  |  | RES,0 Ohm,+/-5%,1/16W,G,SMD0402 | WALSIN TECHNOLOGY CORPORATION | WR04X000PTL |  |  | PWA BOM |
|  | 610107A00-011-G |  |  | RES,0 Ohm,+/-5%,1/16W,G,SMD0402 | YAGEO CORPORATION COMPONENT | RC0402JR-070RL |  |  | PWA BOM |
|  | 610107A00-044-G |  |  | RES,0 Ohm,+/-5%,1/16W,G,SMD0402 | TA-I TECHNOLOGY CO., LTD | RM04JTN0 |  |  | PWA BOM |
|  | 610107A00-024-G |  |  | RES,0 Ohm,+/-5%,1/16W,G,SMD0402 | PANASONIC INDUSTRIAL CO.,LTD. | ERJ2GE0R00X |  |  | PWA BOM |
|  | 610107A00-029-G |  |  | RES,0 Ohm,+/-5%,1/16W,G,SMD0402 | VISHAY ENTER TECHNO LOGY.INC | CRCW04020000Z0ED |  |  | PWA BOM |
| 3 | 610108U00-017-G | 8 | 10 | RES,10KOhm,+/-1%,1/10W,G,SMD0603 | KOA SPEER ELECTRONICS, INC. | RK73H1JTTD1002F | G | (+)PAAR70,PBAR71 | PWA BOM |
|  | 610108U00-012-G |  |  | RES,10KOhm,+/-1%,1/10W,G,SMD0603 | WALSIN TECHNOLOGY CORPORATION | WR06X1002FTL |  |  | PWA BOM |
|  | 610108U00-011-G |  |  | RES,10KOhm,+/-1%,1/10W,G,SMD0603 | YAGEO CORPORATION COMPONENT | RC0603FR-0710KL |  |  | PWA BOM |
|  | 610108U00-044-G |  |  | RES,10KOhm,+/-1%,1/10W,G,SMD0603 | TA-I TECHNOLOGY CO., LTD | RM06FTN1002 |  |  | PWA BOM |
|  | 610108U00-024-G |  |  | RES,10KOhm,+/-1%,1/10W,G,SMD0603 | PANASONIC INDUSTRIAL CO.,LTD. | ERJ3EKF1002V |  |  | PWA BOM |
| 4 | 610100C00-017-G | 4 | 2 | RES,15kOhm,+/-1%,1/10W,G,SMD0603 | KOA SPEER ELECTRONICS, INC. | RK73H1JTTD1502F | G | (-)PAAR70,PBAR71 | PWA BOM |
|  | 610100C00-011-G |  |  | RES,15KOhm,+/-1%,1/10W,G,SMD0603 | YAGEO CORPORATION COMPONENT | RC0603FR-0715KL |  |  | PWA BOM |
|  | 610100C00-012-G |  |  | RES,15KOhm,+/-1%,1/10W,G,SMD0603 | WALSIN TECHNOLOGY CORPORATION | WR06X1502FTL |  |  | PWA BOM |
|  | 610100C00-044-G |  |  | RES,15KOhm,+/-1%,1/10W,G,SMD0603 | TA-I TECHNOLOGY CO., LTD | RM06FTN1502 |  |  | PWA BOM |
| 5 | 61100M100-017-G | 0 | 2 | RES,4.75KOhm,+/-1%,1/16W,G,SMD0402 | KOA SPEER ELECTRONICS, INC. | RN731ETTP4751F50 | G | (+)PBAR109,PAAR109 | PWA BOM |
|  | 61100M100-011-G |  |  | RES,4.75KOhm,+/-1%,1/16W,G,SMD0402 | YAGEO CORPORATION COMPONENT | RT0402FRE074K75L |  |  | PWA BOM |
|  | 61100M100-012-G |  |  | RES,4.75KOhm,+/-1%,1/16W,G,SMD0402 | WALSIN TECHNOLOGY CORPORATION | WF04T4751FTL |  |  | PWA BOM |
|  | 61100M100-044-G |  |  | RES,4.75KOhm,+/-1%,1/16W,G,SMD0402 | TA-I TECHNOLOGY CO., LTD | RB04FTS4751 |  |  | PWA BOM |
| 6 | 620109700-015-G | 23 | 21 | CAP,3.3nF,+/-10%,X7R,50V,G,SMD0402 | MURATA ELEC. NORTH AMERICA | GRM155R71H332K | G | (-)PBAC125,PAAC125 | PWA BOM |
|  | 620109700-012-G |  |  | CAP,3.3nF,+/-10%,X7R,50V,G,SMD0402 | WALSIN TECHNOLOGY CORPORATION | 0402B332K500CT |  |  | PWA BOM |
|  | 620109700-026-G |  |  | CAP,3.3nF,+/-10%,X7R,50V,G,SMD0402 | SAMSUNG SEMICONDUCTOR | CL05B332KB5NNNC |  |  | PWA BOM |
| OOOOOOOOOOOOOOOOOOOOOOOOOOOOOOOOOOOOOOOOOOOOOOOOOOOOOOOOOOOOOOOOOOOOOOOOOOOOOOOOOOOOOOOOOO | OOOOOOOOOOOOOOOOOOOOOOOOOOOOOOOOOOOOOOOOOOOOOOOOOOOOOOOOOOOOOOOOOOOOOOOOOOOOOOOOOOOOOOOOOO | OOOOOOOOOOOOOOOOOOOOOOOOOOOOOOOOOOOOOOOOOOOOOOOOOOOOOOOOOOOOOOOOOOOOOOOOOOOOOOOOOOOOOOOOOO | OOOOOOOOOOOOOOOOOOOOOOOOOOOOOOOOOOOOOOOOOOOOOOOOOOOOOOOOOOOOOOOOOOOOOOOOOOOOOOOOOOOOOOOOOO | OOOOOOOOOOOOOOOOOOOOOOOOOOOOOOOOOOOOOOOOOOOOOOOOOOOOOOOOOOOOOOOOOOOOOOOOOOOOOOOOOOOOOOOOOO | OOOOOOOOOOOOOOOOOOOOOOOOOOOOOOOOOOOOOOOOOOOOOOOOOOOOOOOOOOOOOOOOOOOOOOOOOOOOOOOOOOOOOOOOOO | OOOOOOOOOOOOOOOOOOOOOOOOOOOOOOOOOOOOOOOOOOOOOOOOOOOOOOOOOOOOOOOOOOOOOOOOOOOOOOOOOOOOOOOOOO | OOOOOOOOOOOOOOOOOOOOOOOOOOOOOOOOOOOOOOOOOOOOOOOOOOOOOOOOOOOOOOOOOOOOOOOOOOOOOOOOOOOOOOOOOO | OOOOOOOOOOOOOOOOOOOOOOOOOOOOOOOOOOOOOOOOOOOOOOOOOOOOOOOOOOOOOOOOOOOOOOOOOOOOOOOOOOOOOOOOOO | OOOOOOOOOOOOOOOOOOOOOOOOOOOOOOOOOOOOOOOOOOOOOOOOOOOOOOOOOOOOOOOOOOOOOOOOOOOOOOOOOOOOOOOOOO |
| TLA Parts Change |  |  |  |  |  |  |  |  |  |
| Item | Foxconn P/N | Qty | Part Description | Manufacturer Full Name | Manufacturer P/N | RoHS | Location | Remark | BOM |
| BOM Change List Date:Mon Jan 22 17:50:50 CST 2018 |  |  |  |  |  |  |  |  |  |
| New BOM file : E:\barreleye g2\0120\BG2 0122.xls |  |  |  |  |  |  |  |  |  |
| Old BOM file : E:\barreleye g2\0120\BG2 0117.xls |  |  |  |  |  |  |  |  |  |
| ##### Add Parts |  |  |  |  |  |  |  |  |  |
| Item | Location | Qty | Foxconn P/N | Part Description | Manufacturer Full Name | Manufacturer P/N | RoHS | Sheet |  |
| ##### Remove Parts |  |  |  |  |  |  |  |  |  |
| Item | Location | Qty | Foxconn P/N | Part Description | Manufacturer Full Name | Manufacturer P/N | RoHS | Sheet |  |
| ##### Change Parts |  |  |  |  |  |  |  |  |  |
| Item | Location | Qty | Foxconn P/N | Part Description | Manufacturer Full Name | Manufacturer P/N | RoHS | Sheet | Remark |
| 1 | PSTC4,PSLC4,PSFC4,PSEC4,PSDC4,PQPC4,PFRC4,PEEC4,PEDC4,PSPC3003,PIPC3003,PFPC3003,PEPC3003,PSRC3010 | 14 | 62012T300-015-G | CAP,1uF,+/-10%,X7S,25V,G,SMD0402 | MURATA ELEC. NORTH AMERICA | GRM155C71E105KE11D | G | PWA BOM | In New BOM |
|  |  |  | 620138700-026-G | CAP,1uF,+/-10%,X6S,25V,G,SMD0402 | SAMSUNG SEMICONDUCTOR | CL05X105KA5NQNC | G | PWA BOM | In New BOM |
|  |  |  | 620138700-015-G | CAP,1uF,+/-10%,X6S,25V,G,SMD0402 | MURATA ELEC. NORTH AMERICA | GRM155C81E105KE11D | G | PWA BOM | In New BOM |
|  | PSTC4,PSLC4,PSFC4,PSEC4,PSDC4,PQPC4,PFRC4,PEEC4,PEDC4,PSPC3003,PIPC3003,PFPC3003,PEPC3003,PSRC3010 | 14 | 62012T300-015-G | CAP,1uF,+/-10%,X7S,25V,G,SMD0402 | MURATA ELEC. NORTH AMERICA | GRM155C71E105KE11D | G | PWA BOM | In Old BOM |
|  |  |  | 620138700-026-G | CAP,1uF,+/-10%,X6S,25V,G,SMD0402 | SAMSUNG SEMICONDUCTOR | CL05X105KA5NQNC | G | PWA BOM | In Old BOM |
|  |  |  | 620138700-015-G | CAP,1uF,+/-10%,X6S,25V,G,SMD0402 | MURATA | GRM155C81E105KE11D | G | PWA BOM | In Old BOM |
| 2 | U17 | 1 | 420212A00-216-G | DRAM,MT40A512M16JY-083E:B,1.2V,512M*16,1.2GHz,G,FBGA-96,SMD | MICRON SEMICONDUCTOR ASIA PTE.LTD. | MT40A512M16JY-083E:B | G | PWA BOM | In New BOM |
|  |  |  | 420214J00-220-G | DRAM,H5AN8G6NAFR-UHC,1.2V,8G,1.2GHz,G,FBGA-96,SMD | HYNIX SEMICONDUCTOR INC | H5AN8G6NAFR-UHC | G | PWA BOM | In New BOM |
|  | U17 | 1 | 420212A00-216-G | DRAM,MT40A512M16JY-083E:B,1.2V,512M*16,1.2GHz,G,FBGA-96,SMD | MICRON SEMICONDUCTOR ASIA PTE.LTD. | MT40A512M16JY-083E:B | G | PWA BOM | In Old BOM |
|  |  |  | 420214J00-220-G | DRAM,H5AN8G6NAFR-UHC,1.2V,8G,1.2GHz,G,FBGA-96,SMD | SK HYNIX | H5AN8G6NAFR-UHC | G | PWA BOM | In Old BOM |
| 3 | X6 | 1 | 710106900-162-G | XTAL,32.768KHz,+/-20ppm,12.5pF,G,SMD | EPSON ELECTRONICS AMERICA,INC. | Q13FC1350000400 | G | PWA BOM | In New BOM |
|  |  |  | 710110M00-873-G | XTAL,32.768KHz,+/-20ppm,12.5pF,G,SMD | KYOCERA ELCO CORPORATION | ST3215SB32768H5HPWAA | G | PWA BOM | In New BOM |
|  |  |  | 710123400-061-G | XTAL,32.768KHz,+/-20ppm,12.5pF,-40_x0003_~85_x0003_,SMD,G | TAITIEN ELECTRONICS CO.,LTD | 06172-W-052-3 | G | PWA BOM | In New BOM |
|  | X6 | 1 | 710106900-162-G | XTAL,32.768KHz,+/-20ppm,12.5pF,G,SMD | EPSON ELECTRONICS AMERICA,INC. | Q13FC1350000400 | G | PWA BOM | In Old BOM |
|  |  |  | 710110M00-873-G | XTAL,32.768KHz,+/-20ppm,12.5pF,G,SMD | KYOCERA ELCO CORPORATION | ST3215SB32768H5HPWAA | G | PWA BOM | In Old BOM |
|  |  |  | 710123400-061-G | XTAL,32.768KHz,+/-20ppm,12.5pF,-40_x0003_~85_x0003_,SMD,G | TAITIEN | 06172-W-052-3 | G | PWA BOM | In Old BOM |
| 4 | Y2 | 1 | 71020Q600-16G-G | OSC,50MHz,50ppm,3.3V,G,SMD | SiTime Corporation | SIT1602AC-23-33E-50.000000T | G | PWA BOM | In New BOM |
|  |  |  | 71012DA00-100-G | OSC,50MHz,+/-25ppm,15pF,G,SMD | TXC CORPORATION | 7X50000015 | G | PWA BOM | In New BOM |
|  |  |  | 710216Q00-098-G | OSC,50MHz,50ppm,3.3V,G,SMD | HARMONY (HELE) | SSW050000I3CHE-ST7R2 | G | PWA BOM | In New BOM |
|  |  |  | 710216P00-873-G | OSC,50MHz,50ppm,3.3V,G,SMD | KYOCERA ELCO CORPORATION | KC3225K50.0000C1GE00 | G | PWA BOM | In New BOM |
|  | Y2 | 1 | 71020Q600-16G-G | OSC,50MHz,50ppm,3.3V,G,SMD | SiTime Corporation | SIT1602AC-23-33E-50.000000T | G | PWA BOM | In Old BOM |
|  |  |  | 71012DA00-100-G | OSC,50MHz,+/-25ppm,15pF,G,SMD | TXC CORPORATION | 7X50000015 | G | PWA BOM | In Old BOM |
|  |  |  | 710216Q00-098-G | OSC,50MHz,50ppm,3.3V,G,SMD | HARMONY (HELE) | SSW050000I3CHE-ST7R2 | G | PWA BOM | In Old BOM |
|  |  |  | 710216P00-873-G | OSC,50MHz,50ppm,3.3V,G,SMD | Kyocera | KC3225K50.0000C1GE00 | G | PWA BOM | In Old BOM |
| 5 | Y4 | 1 | 71020KL00-100-G | OSC,33MHz,+/-50ppm,3.3V,15pF,G,SMD | TXC CORPORATION | 7X33000013 | G | PWA BOM | In New BOM |
|  |  |  | 710211800-967-G | OSC,33MHz,+/-50ppm,3.3V,15pF,G,SMD | SaRonix-eCERA Corporation | FK3300011 | G | PWA BOM | In New BOM |
|  |  |  | 710216N00-873-G | OSC,33MHz,+/-50ppm,3.3V,15pF,G,SMD | KYOCERA ELCO CORPORATION | KC3225K33.0000C10E00 | G | PWA BOM | In New BOM |
|  | Y4 | 1 | 71020KL00-100-G | OSC,33MHz,+/-50ppm,3.3V,15pF,G,SMD | TXC CORPORATION | 7X33000013 | G | PWA BOM | In Old BOM |
|  |  |  | 710211800-967-G | OSC,33MHz,+/-50ppm,3.3V,15pF,G,SMD | eCERA | FK3300011 | G | PWA BOM | In Old BOM |
|  |  |  | 710216N00-873-G | OSC,33MHz,+/-50ppm,3.3V,15pF,G,SMD | Kyocera | KC3225K33.0000C10E00 | G | PWA BOM | In Old BOM |
| 6 | PBMU1,PBFU1,PBEU1,PBAU1,PAMU1,PAFU1,PAEU1,PAAU1 | 8 | ISL68137IRAZ-GG05 | IC,PWM Controller,ISL68137IRAZ-T,G,QFN-48,SMD | INTERSIL CORPORATION | ISL68137IRAZ-GG05 | G | PWA BOM | In New BOM |
|  | PBMU1,PBFU1,PBEU1,PBAU1,PAMU1,PAFU1,PAEU1,PAAU1 | 8 | ISL68137IRAZ-GG04 | IC,PWM Controller,ISL68137IRAZ-T,G,QFN-48,SMD | INTERSIL CORPORATION | ISL68137IRAZ-GG04 | G | PWA BOM | In Old BOM |
| ##### Change Revision |  |  |  |  |  |  |  |  |  |
| Sheet | REV OF BOM | CUSTOMER | CUSTOMER P/N | PWA PN | PWA DESCRIPTION | PWA REV | DATE | Remark |  |
| OOOOOOOOOOOOOOOOOOOOOOOOOOOOOOOOOOOOOOOOOOOOOOOOOOOOOOOOOOOOOOOOOOOOOOOOOOOOOOOOOOOOOOOOOO | OOOOOOOOOOOOOOOOOOOOOOOOOOOOOOOOOOOOOOOOOOOOOOOOOOOOOOOOOOOOOOOOOOOOOOOOOOOOOOOOOOOOOOOOOO | OOOOOOOOOOOOOOOOOOOOOOOOOOOOOOOOOOOOOOOOOOOOOOOOOOOOOOOOOOOOOOOOOOOOOOOOOOOOOOOOOOOOOOOOOO | OOOOOOOOOOOOOOOOOOOOOOOOOOOOOOOOOOOOOOOOOOOOOOOOOOOOOOOOOOOOOOOOOOOOOOOOOOOOOOOOOOOOOOOOOO | OOOOOOOOOOOOOOOOOOOOOOOOOOOOOOOOOOOOOOOOOOOOOOOOOOOOOOOOOOOOOOOOOOOOOOOOOOOOOOOOOOOOOOOOOO | OOOOOOOOOOOOOOOOOOOOOOOOOOOOOOOOOOOOOOOOOOOOOOOOOOOOOOOOOOOOOOOOOOOOOOOOOOOOOOOOOOOOOOOOOO | OOOOOOOOOOOOOOOOOOOOOOOOOOOOOOOOOOOOOOOOOOOOOOOOOOOOOOOOOOOOOOOOOOOOOOOOOOOOOOOOOOOOOOOOOO | OOOOOOOOOOOOOOOOOOOOOOOOOOOOOOOOOOOOOOOOOOOOOOOOOOOOOOOOOOOOOOOOOOOOOOOOOOOOOOOOOOOOOOOOOO | OOOOOOOOOOOOOOOOOOOOOOOOOOOOOOOOOOOOOOOOOOOOOOOOOOOOOOOOOOOOOOOOOOOOOOOOOOOOOOOOOOOOOOOOOO | OOOOOOOOOOOOOOOOOOOOOOOOOOOOOOOOOOOOOOOOOOOOOOOOOOOOOOOOOOOOOOOOOOOOOOOOOOOOOOOOOOOOOOOOOO |
| Second Source Change |  |  |  |  |  |  |  |  |  |
| Item | Location | Change Type | Foxconn P/N | Part Description | Manufacturer Full Name | Manufacturer P/N | RoHS | Sheet |  |
| OOOOOOOOOOOOOOOOOOOOOOOOOOOOOOOOOOOOOOOOOOOOOOOOOOOOOOOOOOOOOOOOOOOOOOOOOOOOOOOOOOOOOOOOOO | OOOOOOOOOOOOOOOOOOOOOOOOOOOOOOOOOOOOOOOOOOOOOOOOOOOOOOOOOOOOOOOOOOOOOOOOOOOOOOOOOOOOOOOOOO | OOOOOOOOOOOOOOOOOOOOOOOOOOOOOOOOOOOOOOOOOOOOOOOOOOOOOOOOOOOOOOOOOOOOOOOOOOOOOOOOOOOOOOOOOO | OOOOOOOOOOOOOOOOOOOOOOOOOOOOOOOOOOOOOOOOOOOOOOOOOOOOOOOOOOOOOOOOOOOOOOOOOOOOOOOOOOOOOOOOOO | OOOOOOOOOOOOOOOOOOOOOOOOOOOOOOOOOOOOOOOOOOOOOOOOOOOOOOOOOOOOOOOOOOOOOOOOOOOOOOOOOOOOOOOOOO | OOOOOOOOOOOOOOOOOOOOOOOOOOOOOOOOOOOOOOOOOOOOOOOOOOOOOOOOOOOOOOOOOOOOOOOOOOOOOOOOOOOOOOOOOO | OOOOOOOOOOOOOOOOOOOOOOOOOOOOOOOOOOOOOOOOOOOOOOOOOOOOOOOOOOOOOOOOOOOOOOOOOOOOOOOOOOOOOOOOOO | OOOOOOOOOOOOOOOOOOOOOOOOOOOOOOOOOOOOOOOOOOOOOOOOOOOOOOOOOOOOOOOOOOOOOOOOOOOOOOOOOOOOOOOOOO | OOOOOOOOOOOOOOOOOOOOOOOOOOOOOOOOOOOOOOOOOOOOOOOOOOOOOOOOOOOOOOOOOOOOOOOOOOOOOOOOOOOOOOOOOO | OOOOOOOOOOOOOOOOOOOOOOOOOOOOOOOOOOOOOOOOOOOOOOOOOOOOOOOOOOOOOOOOOOOOOOOOOOOOOOOOOOOOOOOOOO |
| Master Materials Change |  |  |  |  |  |  |  |  |  |
| Item | Foxconn P/N | Orig._Usage | New_Usage | Part Description | Manufacturer Full Name | Manufacturer P/N | RoHS | Location | Sheet |
| 1 | ISL68137IRAZ-GG05 | 0 | 8 | IC,PWM Controller,ISL68137IRAZ-T,G,QFN-48,SMD | INTERSIL CORPORATION | ISL68137IRAZ-GG05 | G | (+)PBMU1,PBFU1,PBEU1,PBAU1,PAMU1,PAFU1,PAEU1,PAAU1 | PWA BOM |
| 2 | ISL68137IRAZ-GG04 | 8 | 0 | IC,PWM Controller,ISL68137IRAZ-T,G,QFN-48,SMD | INTERSIL CORPORATION | ISL68137IRAZ-GG04 | G | (-)PBMU1,PBFU1,PBEU1,PBAU1,PAMU1,PAFU1,PAEU1,PAAU1 | PWA BOM |
| OOOOOOOOOOOOOOOOOOOOOOOOOOOOOOOOOOOOOOOOOOOOOOOOOOOOOOOOOOOOOOOOOOOOOOOOOOOOOOOOOOOOOOOOOO | OOOOOOOOOOOOOOOOOOOOOOOOOOOOOOOOOOOOOOOOOOOOOOOOOOOOOOOOOOOOOOOOOOOOOOOOOOOOOOOOOOOOOOOOOO | OOOOOOOOOOOOOOOOOOOOOOOOOOOOOOOOOOOOOOOOOOOOOOOOOOOOOOOOOOOOOOOOOOOOOOOOOOOOOOOOOOOOOOOOOO | OOOOOOOOOOOOOOOOOOOOOOOOOOOOOOOOOOOOOOOOOOOOOOOOOOOOOOOOOOOOOOOOOOOOOOOOOOOOOOOOOOOOOOOOOO | OOOOOOOOOOOOOOOOOOOOOOOOOOOOOOOOOOOOOOOOOOOOOOOOOOOOOOOOOOOOOOOOOOOOOOOOOOOOOOOOOOOOOOOOOO | OOOOOOOOOOOOOOOOOOOOOOOOOOOOOOOOOOOOOOOOOOOOOOOOOOOOOOOOOOOOOOOOOOOOOOOOOOOOOOOOOOOOOOOOOO | OOOOOOOOOOOOOOOOOOOOOOOOOOOOOOOOOOOOOOOOOOOOOOOOOOOOOOOOOOOOOOOOOOOOOOOOOOOOOOOOOOOOOOOOOO | OOOOOOOOOOOOOOOOOOOOOOOOOOOOOOOOOOOOOOOOOOOOOOOOOOOOOOOOOOOOOOOOOOOOOOOOOOOOOOOOOOOOOOOOOO | OOOOOOOOOOOOOOOOOOOOOOOOOOOOOOOOOOOOOOOOOOOOOOOOOOOOOOOOOOOOOOOOOOOOOOOOOOOOOOOOOOOOOOOOOO | OOOOOOOOOOOOOOOOOOOOOOOOOOOOOOOOOOOOOOOOOOOOOOOOOOOOOOOOOOOOOOOOOOOOOOOOOOOOOOOOOOOOOOOOOO |
| TLA Parts Change |  |  |  |  |  |  |  |  |  |
| Item | Foxconn P/N | Qty | Part Description | Manufacturer Full Name | Manufacturer P/N | RoHS | Location | Remark | BOM |
